G04*
G04 #@! TF.GenerationSoftware,Altium Limited,Altium Designer,23.7.1 (13)*
G04*
G04 Layer_Color=32896*
%FSLAX25Y25*%
%MOIN*%
G70*
G04*
G04 #@! TF.SameCoordinates,AF00DCEB-AC48-4C7C-91EA-99F42E284231*
G04*
G04*
G04 #@! TF.FilePolarity,Positive*
G04*
G01*
G75*
%ADD15C,0.00787*%
G36*
X595030Y-285767D02*
X595157Y-285782D01*
X595270Y-285800D01*
X595325Y-285814D01*
X595372Y-285825D01*
X595416Y-285836D01*
X595456Y-285851D01*
X595492Y-285861D01*
X595521Y-285869D01*
X595543Y-285880D01*
X595562Y-285883D01*
X595572Y-285891D01*
X595576D01*
X595685Y-285945D01*
X595784Y-286007D01*
X595867Y-286073D01*
X595900Y-286105D01*
X595933Y-286135D01*
X595962Y-286164D01*
X595987Y-286193D01*
X596009Y-286218D01*
X596024Y-286240D01*
X596038Y-286255D01*
X596049Y-286269D01*
X596053Y-286277D01*
X596057Y-286280D01*
X596086Y-286331D01*
X596111Y-286382D01*
X596151Y-286491D01*
X596180Y-286600D01*
X596199Y-286706D01*
X596206Y-286757D01*
X596213Y-286801D01*
X596217Y-286841D01*
Y-286874D01*
X596220Y-286903D01*
Y-286943D01*
X596217Y-287015D01*
X596209Y-287085D01*
X596202Y-287150D01*
X596188Y-287212D01*
X596169Y-287270D01*
X596151Y-287325D01*
X596133Y-287376D01*
X596111Y-287423D01*
X596093Y-287463D01*
X596075Y-287503D01*
X596057Y-287532D01*
X596038Y-287561D01*
X596024Y-287580D01*
X596017Y-287598D01*
X596009Y-287605D01*
X596006Y-287609D01*
X595962Y-287660D01*
X595918Y-287703D01*
X595867Y-287743D01*
X595816Y-287784D01*
X595714Y-287849D01*
X595612Y-287900D01*
X595565Y-287922D01*
X595521Y-287940D01*
X595481Y-287955D01*
X595449Y-287965D01*
X595420Y-287976D01*
X595398Y-287984D01*
X595383Y-287987D01*
X595379D01*
X595296Y-287652D01*
X595354Y-287638D01*
X595409Y-287620D01*
X595460Y-287601D01*
X595507Y-287583D01*
X595551Y-287561D01*
X595587Y-287540D01*
X595623Y-287514D01*
X595656Y-287492D01*
X595685Y-287474D01*
X595707Y-287452D01*
X595729Y-287434D01*
X595747Y-287420D01*
X595758Y-287405D01*
X595769Y-287394D01*
X595773Y-287390D01*
X595776Y-287387D01*
X595805Y-287350D01*
X595827Y-287310D01*
X595867Y-287230D01*
X595896Y-287154D01*
X595915Y-287077D01*
X595929Y-287012D01*
X595933Y-286986D01*
Y-286961D01*
X595936Y-286939D01*
Y-286913D01*
X595933Y-286830D01*
X595918Y-286750D01*
X595900Y-286677D01*
X595878Y-286611D01*
X595856Y-286560D01*
X595845Y-286539D01*
X595838Y-286520D01*
X595831Y-286506D01*
X595823Y-286495D01*
X595820Y-286488D01*
Y-286484D01*
X595769Y-286415D01*
X595714Y-286357D01*
X595652Y-286306D01*
X595594Y-286266D01*
X595543Y-286233D01*
X595500Y-286211D01*
X595481Y-286204D01*
X595471Y-286196D01*
X595463Y-286193D01*
X595460D01*
X595365Y-286164D01*
X595270Y-286142D01*
X595176Y-286124D01*
X595088Y-286113D01*
X595048Y-286109D01*
X595012Y-286105D01*
X594979D01*
X594954Y-286102D01*
X594932D01*
X594914D01*
X594903D01*
X594899D01*
X594804Y-286105D01*
X594717Y-286113D01*
X594637Y-286127D01*
X594564Y-286142D01*
X594502Y-286153D01*
X594477Y-286160D01*
X594455Y-286167D01*
X594437Y-286171D01*
X594426Y-286175D01*
X594418Y-286178D01*
X594415D01*
X594331Y-286215D01*
X594255Y-286255D01*
X594193Y-286298D01*
X594138Y-286346D01*
X594095Y-286386D01*
X594065Y-286419D01*
X594047Y-286444D01*
X594040Y-286448D01*
Y-286451D01*
X593993Y-286528D01*
X593956Y-286611D01*
X593931Y-286691D01*
X593916Y-286768D01*
X593905Y-286837D01*
X593902Y-286866D01*
Y-286892D01*
X593898Y-286910D01*
Y-286939D01*
X593902Y-287030D01*
X593916Y-287114D01*
X593938Y-287183D01*
X593960Y-287245D01*
X593985Y-287292D01*
X594003Y-287329D01*
X594018Y-287350D01*
X594025Y-287358D01*
X594080Y-287416D01*
X594142Y-287470D01*
X594207Y-287514D01*
X594273Y-287550D01*
X594331Y-287580D01*
X594360Y-287591D01*
X594382Y-287598D01*
X594400Y-287605D01*
X594415Y-287612D01*
X594422Y-287616D01*
X594426D01*
X594349Y-287944D01*
X594284Y-287922D01*
X594226Y-287900D01*
X594171Y-287871D01*
X594116Y-287845D01*
X594069Y-287816D01*
X594025Y-287784D01*
X593982Y-287754D01*
X593945Y-287725D01*
X593916Y-287696D01*
X593887Y-287671D01*
X593862Y-287645D01*
X593843Y-287627D01*
X593825Y-287609D01*
X593814Y-287594D01*
X593811Y-287587D01*
X593807Y-287583D01*
X593774Y-287532D01*
X593742Y-287481D01*
X593716Y-287430D01*
X593694Y-287376D01*
X593661Y-287267D01*
X593640Y-287168D01*
X593629Y-287121D01*
X593625Y-287081D01*
X593621Y-287041D01*
X593618Y-287008D01*
X593614Y-286983D01*
Y-286946D01*
X593621Y-286826D01*
X593640Y-286710D01*
X593661Y-286608D01*
X593676Y-286560D01*
X593690Y-286517D01*
X593705Y-286477D01*
X593720Y-286440D01*
X593731Y-286411D01*
X593742Y-286382D01*
X593752Y-286364D01*
X593760Y-286349D01*
X593763Y-286338D01*
X593767Y-286335D01*
X593829Y-286237D01*
X593902Y-286153D01*
X593974Y-286080D01*
X594047Y-286018D01*
X594113Y-285971D01*
X594142Y-285953D01*
X594167Y-285938D01*
X594185Y-285923D01*
X594200Y-285916D01*
X594211Y-285912D01*
X594215Y-285909D01*
X594327Y-285858D01*
X594444Y-285822D01*
X594560Y-285796D01*
X594666Y-285778D01*
X594713Y-285771D01*
X594761Y-285767D01*
X594797Y-285763D01*
X594834D01*
X594859Y-285760D01*
X594881D01*
X594895D01*
X594899D01*
X595030Y-285767D01*
D02*
G37*
G36*
X594557Y-288562D02*
X594531Y-288617D01*
X594506Y-288672D01*
X594480Y-288723D01*
X594459Y-288766D01*
X594440Y-288803D01*
X594426Y-288825D01*
X594422Y-288828D01*
Y-288832D01*
X594382Y-288897D01*
X594342Y-288955D01*
X594306Y-289006D01*
X594273Y-289047D01*
X594247Y-289083D01*
X594226Y-289105D01*
X594211Y-289123D01*
X594207Y-289127D01*
X596177D01*
Y-289436D01*
X593647D01*
Y-289236D01*
X593709Y-289199D01*
X593767Y-289159D01*
X593825Y-289112D01*
X593876Y-289068D01*
X593920Y-289025D01*
X593956Y-288992D01*
X593967Y-288977D01*
X593978Y-288966D01*
X593982Y-288963D01*
X593985Y-288959D01*
X594047Y-288883D01*
X594105Y-288806D01*
X594156Y-288734D01*
X594197Y-288661D01*
X594233Y-288599D01*
X594247Y-288573D01*
X594258Y-288551D01*
X594269Y-288533D01*
X594273Y-288519D01*
X594280Y-288511D01*
Y-288508D01*
X594579D01*
X594557Y-288562D01*
D02*
G37*
G36*
Y-290521D02*
X594531Y-290575D01*
X594506Y-290630D01*
X594480Y-290681D01*
X594459Y-290725D01*
X594440Y-290761D01*
X594426Y-290783D01*
X594422Y-290787D01*
Y-290790D01*
X594382Y-290856D01*
X594342Y-290914D01*
X594306Y-290965D01*
X594273Y-291005D01*
X594247Y-291041D01*
X594226Y-291063D01*
X594211Y-291081D01*
X594207Y-291085D01*
X596177D01*
Y-291394D01*
X593647D01*
Y-291194D01*
X593709Y-291158D01*
X593767Y-291118D01*
X593825Y-291070D01*
X593876Y-291027D01*
X593920Y-290983D01*
X593956Y-290950D01*
X593967Y-290936D01*
X593978Y-290925D01*
X593982Y-290921D01*
X593985Y-290917D01*
X594047Y-290841D01*
X594105Y-290765D01*
X594156Y-290692D01*
X594197Y-290619D01*
X594233Y-290557D01*
X594247Y-290532D01*
X594258Y-290510D01*
X594269Y-290492D01*
X594273Y-290477D01*
X594280Y-290470D01*
Y-290466D01*
X594579D01*
X594557Y-290521D01*
D02*
G37*
G36*
X595572Y-293178D02*
X596177D01*
Y-293487D01*
X595572D01*
Y-293829D01*
X595289D01*
Y-293487D01*
X593658D01*
Y-293236D01*
X595289Y-292082D01*
X595572D01*
Y-293178D01*
D02*
G37*
G36*
X545891Y-263781D02*
X545949D01*
X546007Y-263785D01*
X546058Y-263792D01*
X546109Y-263796D01*
X546153Y-263799D01*
X546193Y-263807D01*
X546229Y-263810D01*
X546262Y-263817D01*
X546287Y-263821D01*
X546309Y-263825D01*
X546327Y-263828D01*
X546338Y-263832D01*
X546346Y-263836D01*
X546349D01*
X546429Y-263858D01*
X546502Y-263883D01*
X546564Y-263912D01*
X546619Y-263934D01*
X546666Y-263959D01*
X546699Y-263974D01*
X546717Y-263988D01*
X546724Y-263992D01*
X546779Y-264032D01*
X546826Y-264072D01*
X546866Y-264116D01*
X546903Y-264156D01*
X546928Y-264192D01*
X546946Y-264222D01*
X546957Y-264240D01*
X546961Y-264243D01*
Y-264247D01*
X546990Y-264305D01*
X547008Y-264367D01*
X547023Y-264425D01*
X547034Y-264480D01*
X547041Y-264527D01*
X547045Y-264567D01*
Y-264600D01*
X547037Y-264698D01*
X547023Y-264789D01*
X546997Y-264866D01*
X546972Y-264931D01*
X546943Y-264986D01*
X546932Y-265008D01*
X546917Y-265026D01*
X546910Y-265040D01*
X546903Y-265051D01*
X546895Y-265055D01*
Y-265059D01*
X546837Y-265124D01*
X546768Y-265179D01*
X546699Y-265226D01*
X546633Y-265263D01*
X546571Y-265292D01*
X546546Y-265306D01*
X546520Y-265314D01*
X546502Y-265321D01*
X546488Y-265328D01*
X546480Y-265332D01*
X546477D01*
X546422Y-265346D01*
X546368Y-265361D01*
X546247Y-265383D01*
X546127Y-265401D01*
X546014Y-265412D01*
X545960Y-265415D01*
X545913Y-265419D01*
X545869D01*
X545829Y-265423D01*
X545800D01*
X545774D01*
X545760D01*
X545756D01*
X545629Y-265419D01*
X545508Y-265412D01*
X545399Y-265401D01*
X545297Y-265383D01*
X545203Y-265364D01*
X545119Y-265343D01*
X545043Y-265321D01*
X544977Y-265299D01*
X544919Y-265277D01*
X544868Y-265252D01*
X544824Y-265233D01*
X544791Y-265215D01*
X544762Y-265197D01*
X544744Y-265186D01*
X544733Y-265179D01*
X544730Y-265175D01*
X544686Y-265135D01*
X544646Y-265091D01*
X544609Y-265044D01*
X544580Y-264997D01*
X544555Y-264949D01*
X544533Y-264902D01*
X544518Y-264855D01*
X544504Y-264811D01*
X544493Y-264768D01*
X544486Y-264727D01*
X544478Y-264691D01*
X544475Y-264662D01*
X544471Y-264636D01*
Y-264600D01*
X544478Y-264502D01*
X544493Y-264411D01*
X544518Y-264334D01*
X544544Y-264269D01*
X544569Y-264214D01*
X544584Y-264196D01*
X544595Y-264178D01*
X544602Y-264163D01*
X544609Y-264152D01*
X544617Y-264149D01*
Y-264145D01*
X544679Y-264079D01*
X544744Y-264025D01*
X544817Y-263978D01*
X544882Y-263941D01*
X544944Y-263912D01*
X544970Y-263897D01*
X544995Y-263890D01*
X545014Y-263883D01*
X545028Y-263876D01*
X545035Y-263872D01*
X545039D01*
X545093Y-263854D01*
X545148Y-263839D01*
X545265Y-263817D01*
X545385Y-263799D01*
X545501Y-263788D01*
X545552Y-263785D01*
X545600Y-263781D01*
X545643D01*
X545683Y-263777D01*
X545712D01*
X545738D01*
X545752D01*
X545756D01*
X545825D01*
X545891Y-263781D01*
D02*
G37*
G36*
X547045Y-266416D02*
X546983Y-266453D01*
X546924Y-266493D01*
X546866Y-266540D01*
X546815Y-266584D01*
X546772Y-266628D01*
X546735Y-266660D01*
X546724Y-266675D01*
X546713Y-266686D01*
X546710Y-266689D01*
X546706Y-266693D01*
X546644Y-266770D01*
X546586Y-266846D01*
X546535Y-266919D01*
X546495Y-266991D01*
X546458Y-267053D01*
X546444Y-267079D01*
X546433Y-267101D01*
X546422Y-267119D01*
X546419Y-267133D01*
X546411Y-267141D01*
Y-267144D01*
X546113D01*
X546135Y-267090D01*
X546160Y-267035D01*
X546185Y-266981D01*
X546211Y-266930D01*
X546233Y-266886D01*
X546251Y-266850D01*
X546266Y-266828D01*
X546269Y-266824D01*
Y-266820D01*
X546309Y-266755D01*
X546349Y-266697D01*
X546386Y-266646D01*
X546419Y-266606D01*
X546444Y-266569D01*
X546466Y-266547D01*
X546480Y-266529D01*
X546484Y-266526D01*
X544515D01*
Y-266216D01*
X547045D01*
Y-266416D01*
D02*
G37*
G36*
Y-268375D02*
X546983Y-268411D01*
X546924Y-268451D01*
X546866Y-268498D01*
X546815Y-268542D01*
X546772Y-268586D01*
X546735Y-268619D01*
X546724Y-268633D01*
X546713Y-268644D01*
X546710Y-268648D01*
X546706Y-268651D01*
X546644Y-268728D01*
X546586Y-268804D01*
X546535Y-268877D01*
X546495Y-268950D01*
X546458Y-269012D01*
X546444Y-269037D01*
X546433Y-269059D01*
X546422Y-269077D01*
X546419Y-269092D01*
X546411Y-269099D01*
Y-269103D01*
X546113D01*
X546135Y-269048D01*
X546160Y-268993D01*
X546185Y-268939D01*
X546211Y-268888D01*
X546233Y-268844D01*
X546251Y-268808D01*
X546266Y-268786D01*
X546269Y-268782D01*
Y-268779D01*
X546309Y-268713D01*
X546349Y-268655D01*
X546386Y-268604D01*
X546419Y-268564D01*
X546444Y-268528D01*
X546466Y-268506D01*
X546480Y-268488D01*
X546484Y-268484D01*
X544515D01*
Y-268175D01*
X547045D01*
Y-268375D01*
D02*
G37*
G36*
X545396Y-269958D02*
X545337Y-269973D01*
X545283Y-269991D01*
X545232Y-270009D01*
X545185Y-270027D01*
X545141Y-270049D01*
X545104Y-270071D01*
X545068Y-270096D01*
X545035Y-270118D01*
X545006Y-270136D01*
X544984Y-270158D01*
X544963Y-270177D01*
X544944Y-270191D01*
X544933Y-270206D01*
X544922Y-270217D01*
X544919Y-270220D01*
X544915Y-270224D01*
X544886Y-270260D01*
X544864Y-270300D01*
X544824Y-270380D01*
X544795Y-270457D01*
X544777Y-270533D01*
X544762Y-270599D01*
X544759Y-270624D01*
Y-270650D01*
X544755Y-270672D01*
Y-270697D01*
X544759Y-270781D01*
X544773Y-270861D01*
X544791Y-270934D01*
X544813Y-270999D01*
X544835Y-271050D01*
X544846Y-271072D01*
X544853Y-271090D01*
X544861Y-271105D01*
X544868Y-271116D01*
X544872Y-271123D01*
Y-271127D01*
X544922Y-271196D01*
X544977Y-271254D01*
X545039Y-271305D01*
X545097Y-271345D01*
X545148Y-271378D01*
X545192Y-271400D01*
X545210Y-271407D01*
X545221Y-271414D01*
X545228Y-271418D01*
X545232D01*
X545327Y-271447D01*
X545421Y-271469D01*
X545516Y-271487D01*
X545603Y-271498D01*
X545643Y-271501D01*
X545680Y-271505D01*
X545712D01*
X545738Y-271509D01*
X545760D01*
X545778D01*
X545789D01*
X545792D01*
X545887Y-271505D01*
X545974Y-271498D01*
X546055Y-271483D01*
X546127Y-271469D01*
X546189Y-271458D01*
X546215Y-271450D01*
X546237Y-271443D01*
X546255Y-271440D01*
X546266Y-271436D01*
X546273Y-271432D01*
X546277D01*
X546360Y-271396D01*
X546437Y-271356D01*
X546499Y-271312D01*
X546553Y-271265D01*
X546597Y-271225D01*
X546626Y-271192D01*
X546644Y-271167D01*
X546652Y-271163D01*
Y-271159D01*
X546699Y-271083D01*
X546735Y-270999D01*
X546761Y-270919D01*
X546775Y-270843D01*
X546786Y-270774D01*
X546790Y-270744D01*
Y-270719D01*
X546793Y-270701D01*
Y-270672D01*
X546790Y-270581D01*
X546775Y-270497D01*
X546753Y-270428D01*
X546732Y-270366D01*
X546706Y-270319D01*
X546688Y-270282D01*
X546673Y-270260D01*
X546666Y-270253D01*
X546611Y-270195D01*
X546550Y-270140D01*
X546484Y-270096D01*
X546419Y-270060D01*
X546360Y-270031D01*
X546331Y-270020D01*
X546309Y-270013D01*
X546291Y-270005D01*
X546277Y-269998D01*
X546269Y-269994D01*
X546266D01*
X546342Y-269667D01*
X546408Y-269689D01*
X546466Y-269711D01*
X546520Y-269740D01*
X546575Y-269765D01*
X546622Y-269794D01*
X546666Y-269827D01*
X546710Y-269856D01*
X546746Y-269885D01*
X546775Y-269914D01*
X546804Y-269940D01*
X546830Y-269965D01*
X546848Y-269984D01*
X546866Y-270002D01*
X546877Y-270016D01*
X546881Y-270024D01*
X546884Y-270027D01*
X546917Y-270078D01*
X546950Y-270129D01*
X546975Y-270180D01*
X546997Y-270235D01*
X547030Y-270344D01*
X547052Y-270442D01*
X547063Y-270490D01*
X547066Y-270530D01*
X547070Y-270570D01*
X547074Y-270602D01*
X547077Y-270628D01*
Y-270664D01*
X547070Y-270784D01*
X547052Y-270901D01*
X547030Y-271003D01*
X547015Y-271050D01*
X547001Y-271094D01*
X546986Y-271134D01*
X546972Y-271170D01*
X546961Y-271199D01*
X546950Y-271229D01*
X546939Y-271247D01*
X546932Y-271261D01*
X546928Y-271272D01*
X546924Y-271276D01*
X546863Y-271374D01*
X546790Y-271458D01*
X546717Y-271531D01*
X546644Y-271592D01*
X546579Y-271640D01*
X546550Y-271658D01*
X546524Y-271673D01*
X546506Y-271687D01*
X546491Y-271694D01*
X546480Y-271698D01*
X546477Y-271702D01*
X546364Y-271753D01*
X546247Y-271789D01*
X546131Y-271814D01*
X546025Y-271833D01*
X545978Y-271840D01*
X545931Y-271844D01*
X545894Y-271847D01*
X545858D01*
X545832Y-271851D01*
X545811D01*
X545796D01*
X545792D01*
X545661Y-271844D01*
X545534Y-271829D01*
X545421Y-271811D01*
X545366Y-271796D01*
X545319Y-271785D01*
X545275Y-271775D01*
X545235Y-271760D01*
X545199Y-271749D01*
X545170Y-271742D01*
X545148Y-271731D01*
X545130Y-271727D01*
X545119Y-271720D01*
X545115D01*
X545006Y-271665D01*
X544908Y-271603D01*
X544824Y-271538D01*
X544791Y-271505D01*
X544759Y-271476D01*
X544730Y-271447D01*
X544704Y-271418D01*
X544682Y-271392D01*
X544668Y-271370D01*
X544653Y-271356D01*
X544642Y-271341D01*
X544638Y-271334D01*
X544635Y-271330D01*
X544606Y-271279D01*
X544580Y-271229D01*
X544540Y-271119D01*
X544511Y-271010D01*
X544493Y-270904D01*
X544486Y-270854D01*
X544478Y-270810D01*
X544475Y-270770D01*
Y-270737D01*
X544471Y-270708D01*
Y-270668D01*
X544475Y-270595D01*
X544482Y-270526D01*
X544489Y-270460D01*
X544504Y-270399D01*
X544522Y-270340D01*
X544540Y-270286D01*
X544558Y-270235D01*
X544580Y-270187D01*
X544598Y-270147D01*
X544617Y-270107D01*
X544635Y-270078D01*
X544653Y-270049D01*
X544668Y-270031D01*
X544675Y-270013D01*
X544682Y-270005D01*
X544686Y-270002D01*
X544730Y-269951D01*
X544773Y-269907D01*
X544824Y-269867D01*
X544875Y-269827D01*
X544977Y-269762D01*
X545079Y-269711D01*
X545126Y-269689D01*
X545170Y-269671D01*
X545210Y-269656D01*
X545243Y-269645D01*
X545272Y-269634D01*
X545294Y-269627D01*
X545308Y-269623D01*
X545312D01*
X545396Y-269958D01*
D02*
G37*
G36*
X581208Y-270678D02*
X581270Y-270634D01*
X581295Y-270612D01*
X581321Y-270594D01*
X581343Y-270576D01*
X581357Y-270561D01*
X581368Y-270550D01*
X581372Y-270547D01*
X581390Y-270529D01*
X581408Y-270507D01*
X581456Y-270456D01*
X581510Y-270398D01*
X581565Y-270336D01*
X581612Y-270278D01*
X581634Y-270252D01*
X581656Y-270230D01*
X581670Y-270212D01*
X581681Y-270197D01*
X581688Y-270190D01*
X581692Y-270186D01*
X581743Y-270128D01*
X581790Y-270070D01*
X581838Y-270019D01*
X581878Y-269972D01*
X581918Y-269928D01*
X581954Y-269892D01*
X581987Y-269855D01*
X582016Y-269826D01*
X582045Y-269797D01*
X582067Y-269775D01*
X582085Y-269757D01*
X582103Y-269739D01*
X582125Y-269721D01*
X582133Y-269713D01*
X582195Y-269662D01*
X582249Y-269619D01*
X582304Y-269582D01*
X582347Y-269553D01*
X582387Y-269531D01*
X582416Y-269517D01*
X582435Y-269510D01*
X582442Y-269506D01*
X582497Y-269484D01*
X582551Y-269469D01*
X582602Y-269455D01*
X582646Y-269448D01*
X582686Y-269444D01*
X582715Y-269440D01*
X582733D01*
X582740D01*
X582795Y-269444D01*
X582846Y-269451D01*
X582897Y-269459D01*
X582941Y-269473D01*
X583028Y-269510D01*
X583097Y-269546D01*
X583130Y-269568D01*
X583155Y-269586D01*
X583181Y-269604D01*
X583199Y-269622D01*
X583214Y-269637D01*
X583228Y-269644D01*
X583232Y-269651D01*
X583236Y-269655D01*
X583272Y-269695D01*
X583305Y-269739D01*
X583330Y-269786D01*
X583352Y-269833D01*
X583388Y-269928D01*
X583414Y-270023D01*
X583421Y-270063D01*
X583428Y-270103D01*
X583432Y-270139D01*
X583436Y-270168D01*
X583439Y-270194D01*
Y-270230D01*
X583436Y-270296D01*
X583432Y-270358D01*
X583421Y-270416D01*
X583410Y-270470D01*
X583396Y-270521D01*
X583381Y-270569D01*
X583363Y-270612D01*
X583345Y-270652D01*
X583326Y-270689D01*
X583308Y-270718D01*
X583294Y-270743D01*
X583279Y-270765D01*
X583268Y-270783D01*
X583257Y-270794D01*
X583254Y-270802D01*
X583250Y-270805D01*
X583214Y-270842D01*
X583174Y-270875D01*
X583130Y-270907D01*
X583086Y-270933D01*
X582999Y-270976D01*
X582912Y-271006D01*
X582871Y-271016D01*
X582831Y-271027D01*
X582799Y-271035D01*
X582770Y-271042D01*
X582744Y-271046D01*
X582726D01*
X582715Y-271049D01*
X582711D01*
X582679Y-270732D01*
X582762Y-270725D01*
X582835Y-270711D01*
X582901Y-270689D01*
X582952Y-270663D01*
X582995Y-270641D01*
X583024Y-270620D01*
X583043Y-270605D01*
X583050Y-270598D01*
X583094Y-270543D01*
X583126Y-270485D01*
X583152Y-270423D01*
X583166Y-270369D01*
X583177Y-270318D01*
X583181Y-270274D01*
X583185Y-270259D01*
Y-270237D01*
X583181Y-270161D01*
X583166Y-270092D01*
X583145Y-270034D01*
X583123Y-269983D01*
X583097Y-269943D01*
X583079Y-269917D01*
X583065Y-269899D01*
X583057Y-269892D01*
X583006Y-269848D01*
X582955Y-269815D01*
X582904Y-269790D01*
X582853Y-269775D01*
X582813Y-269764D01*
X582777Y-269761D01*
X582755Y-269757D01*
X582751D01*
X582748D01*
X582682Y-269764D01*
X582613Y-269779D01*
X582551Y-269804D01*
X582493Y-269830D01*
X582446Y-269859D01*
X582406Y-269884D01*
X582391Y-269892D01*
X582380Y-269899D01*
X582376Y-269906D01*
X582373D01*
X582333Y-269935D01*
X582293Y-269972D01*
X582249Y-270012D01*
X582205Y-270056D01*
X582118Y-270146D01*
X582031Y-270237D01*
X581991Y-270285D01*
X581954Y-270325D01*
X581921Y-270365D01*
X581892Y-270398D01*
X581871Y-270423D01*
X581852Y-270445D01*
X581841Y-270460D01*
X581838Y-270463D01*
X581761Y-270554D01*
X581688Y-270638D01*
X581623Y-270707D01*
X581568Y-270762D01*
X581521Y-270809D01*
X581488Y-270842D01*
X581466Y-270860D01*
X581463Y-270867D01*
X581459D01*
X581397Y-270918D01*
X581339Y-270958D01*
X581281Y-270995D01*
X581230Y-271024D01*
X581186Y-271046D01*
X581153Y-271060D01*
X581132Y-271067D01*
X581128Y-271071D01*
X581124D01*
X581084Y-271086D01*
X581048Y-271093D01*
X581011Y-271100D01*
X580979Y-271104D01*
X580950Y-271107D01*
X580928D01*
X580913D01*
X580910D01*
Y-269437D01*
X581208D01*
Y-270678D01*
D02*
G37*
G36*
X583439Y-272058D02*
X583378Y-272094D01*
X583319Y-272134D01*
X583261Y-272181D01*
X583210Y-272225D01*
X583166Y-272269D01*
X583130Y-272301D01*
X583119Y-272316D01*
X583108Y-272327D01*
X583105Y-272330D01*
X583101Y-272334D01*
X583039Y-272411D01*
X582981Y-272487D01*
X582930Y-272560D01*
X582890Y-272633D01*
X582853Y-272694D01*
X582839Y-272720D01*
X582828Y-272742D01*
X582817Y-272760D01*
X582813Y-272775D01*
X582806Y-272782D01*
Y-272785D01*
X582508D01*
X582529Y-272731D01*
X582555Y-272676D01*
X582580Y-272622D01*
X582606Y-272571D01*
X582628Y-272527D01*
X582646Y-272491D01*
X582660Y-272469D01*
X582664Y-272465D01*
Y-272462D01*
X582704Y-272396D01*
X582744Y-272338D01*
X582781Y-272287D01*
X582813Y-272247D01*
X582839Y-272210D01*
X582861Y-272188D01*
X582875Y-272170D01*
X582879Y-272167D01*
X580910D01*
Y-271857D01*
X583439D01*
Y-272058D01*
D02*
G37*
G36*
Y-274016D02*
X583378Y-274052D01*
X583319Y-274092D01*
X583261Y-274140D01*
X583210Y-274183D01*
X583166Y-274227D01*
X583130Y-274260D01*
X583119Y-274274D01*
X583108Y-274285D01*
X583105Y-274289D01*
X583101Y-274292D01*
X583039Y-274369D01*
X582981Y-274445D01*
X582930Y-274518D01*
X582890Y-274591D01*
X582853Y-274653D01*
X582839Y-274678D01*
X582828Y-274700D01*
X582817Y-274718D01*
X582813Y-274733D01*
X582806Y-274740D01*
Y-274744D01*
X582508D01*
X582529Y-274689D01*
X582555Y-274635D01*
X582580Y-274580D01*
X582606Y-274529D01*
X582628Y-274485D01*
X582646Y-274449D01*
X582660Y-274427D01*
X582664Y-274424D01*
Y-274420D01*
X582704Y-274354D01*
X582744Y-274296D01*
X582781Y-274245D01*
X582813Y-274205D01*
X582839Y-274169D01*
X582861Y-274147D01*
X582875Y-274129D01*
X582879Y-274125D01*
X580910D01*
Y-273816D01*
X583439D01*
Y-274016D01*
D02*
G37*
G36*
X581790Y-275599D02*
X581732Y-275614D01*
X581678Y-275632D01*
X581627Y-275650D01*
X581579Y-275668D01*
X581536Y-275690D01*
X581499Y-275712D01*
X581463Y-275738D01*
X581430Y-275759D01*
X581401Y-275778D01*
X581379Y-275799D01*
X581357Y-275818D01*
X581339Y-275832D01*
X581328Y-275847D01*
X581317Y-275858D01*
X581314Y-275861D01*
X581310Y-275865D01*
X581281Y-275901D01*
X581259Y-275941D01*
X581219Y-276021D01*
X581190Y-276098D01*
X581172Y-276174D01*
X581157Y-276240D01*
X581153Y-276265D01*
Y-276291D01*
X581150Y-276313D01*
Y-276338D01*
X581153Y-276422D01*
X581168Y-276502D01*
X581186Y-276575D01*
X581208Y-276640D01*
X581230Y-276691D01*
X581241Y-276713D01*
X581248Y-276731D01*
X581255Y-276746D01*
X581263Y-276757D01*
X581266Y-276764D01*
Y-276768D01*
X581317Y-276837D01*
X581372Y-276895D01*
X581434Y-276946D01*
X581492Y-276986D01*
X581543Y-277019D01*
X581587Y-277041D01*
X581605Y-277048D01*
X581616Y-277055D01*
X581623Y-277059D01*
X581627D01*
X581721Y-277088D01*
X581816Y-277110D01*
X581911Y-277128D01*
X581998Y-277139D01*
X582038Y-277143D01*
X582074Y-277146D01*
X582107D01*
X582133Y-277150D01*
X582154D01*
X582173D01*
X582184D01*
X582187D01*
X582282Y-277146D01*
X582369Y-277139D01*
X582449Y-277124D01*
X582522Y-277110D01*
X582584Y-277099D01*
X582610Y-277092D01*
X582631Y-277084D01*
X582650Y-277081D01*
X582660Y-277077D01*
X582668Y-277073D01*
X582671D01*
X582755Y-277037D01*
X582831Y-276997D01*
X582893Y-276953D01*
X582948Y-276906D01*
X582992Y-276866D01*
X583021Y-276833D01*
X583039Y-276808D01*
X583046Y-276804D01*
Y-276800D01*
X583094Y-276724D01*
X583130Y-276640D01*
X583155Y-276560D01*
X583170Y-276484D01*
X583181Y-276415D01*
X583185Y-276385D01*
Y-276360D01*
X583188Y-276342D01*
Y-276313D01*
X583185Y-276222D01*
X583170Y-276138D01*
X583148Y-276069D01*
X583126Y-276007D01*
X583101Y-275960D01*
X583083Y-275923D01*
X583068Y-275901D01*
X583061Y-275894D01*
X583006Y-275836D01*
X582944Y-275781D01*
X582879Y-275738D01*
X582813Y-275701D01*
X582755Y-275672D01*
X582726Y-275661D01*
X582704Y-275654D01*
X582686Y-275646D01*
X582671Y-275639D01*
X582664Y-275636D01*
X582660D01*
X582737Y-275308D01*
X582802Y-275330D01*
X582861Y-275352D01*
X582915Y-275381D01*
X582970Y-275406D01*
X583017Y-275435D01*
X583061Y-275468D01*
X583105Y-275497D01*
X583141Y-275526D01*
X583170Y-275555D01*
X583199Y-275581D01*
X583225Y-275606D01*
X583243Y-275625D01*
X583261Y-275643D01*
X583272Y-275657D01*
X583276Y-275665D01*
X583279Y-275668D01*
X583312Y-275719D01*
X583345Y-275770D01*
X583370Y-275821D01*
X583392Y-275876D01*
X583425Y-275985D01*
X583447Y-276083D01*
X583458Y-276131D01*
X583461Y-276171D01*
X583465Y-276211D01*
X583468Y-276243D01*
X583472Y-276269D01*
Y-276305D01*
X583465Y-276426D01*
X583447Y-276542D01*
X583425Y-276644D01*
X583410Y-276691D01*
X583396Y-276735D01*
X583381Y-276775D01*
X583367Y-276811D01*
X583356Y-276840D01*
X583345Y-276870D01*
X583334Y-276888D01*
X583326Y-276902D01*
X583323Y-276913D01*
X583319Y-276917D01*
X583257Y-277015D01*
X583185Y-277099D01*
X583112Y-277172D01*
X583039Y-277234D01*
X582973Y-277281D01*
X582944Y-277299D01*
X582919Y-277314D01*
X582901Y-277328D01*
X582886Y-277336D01*
X582875Y-277339D01*
X582871Y-277343D01*
X582759Y-277394D01*
X582642Y-277430D01*
X582526Y-277456D01*
X582420Y-277474D01*
X582373Y-277481D01*
X582326Y-277485D01*
X582289Y-277488D01*
X582253D01*
X582227Y-277492D01*
X582205D01*
X582191D01*
X582187D01*
X582056Y-277485D01*
X581929Y-277470D01*
X581816Y-277452D01*
X581761Y-277437D01*
X581714Y-277427D01*
X581670Y-277416D01*
X581630Y-277401D01*
X581594Y-277390D01*
X581565Y-277383D01*
X581543Y-277372D01*
X581525Y-277368D01*
X581514Y-277361D01*
X581510D01*
X581401Y-277306D01*
X581303Y-277244D01*
X581219Y-277179D01*
X581186Y-277146D01*
X581153Y-277117D01*
X581124Y-277088D01*
X581099Y-277059D01*
X581077Y-277033D01*
X581062Y-277011D01*
X581048Y-276997D01*
X581037Y-276982D01*
X581033Y-276975D01*
X581030Y-276972D01*
X581001Y-276921D01*
X580975Y-276870D01*
X580935Y-276760D01*
X580906Y-276651D01*
X580888Y-276546D01*
X580880Y-276495D01*
X580873Y-276451D01*
X580869Y-276411D01*
Y-276378D01*
X580866Y-276349D01*
Y-276309D01*
X580869Y-276236D01*
X580877Y-276167D01*
X580884Y-276101D01*
X580899Y-276040D01*
X580917Y-275981D01*
X580935Y-275927D01*
X580953Y-275876D01*
X580975Y-275829D01*
X580993Y-275788D01*
X581011Y-275748D01*
X581030Y-275719D01*
X581048Y-275690D01*
X581062Y-275672D01*
X581070Y-275654D01*
X581077Y-275646D01*
X581081Y-275643D01*
X581124Y-275592D01*
X581168Y-275548D01*
X581219Y-275508D01*
X581270Y-275468D01*
X581372Y-275403D01*
X581474Y-275352D01*
X581521Y-275330D01*
X581565Y-275312D01*
X581605Y-275297D01*
X581638Y-275286D01*
X581667Y-275275D01*
X581688Y-275268D01*
X581703Y-275264D01*
X581707D01*
X581790Y-275599D01*
D02*
G37*
G36*
X579676Y-285373D02*
X579803Y-285388D01*
X579916Y-285406D01*
X579971Y-285420D01*
X580018Y-285431D01*
X580061Y-285442D01*
X580102Y-285457D01*
X580138Y-285468D01*
X580167Y-285475D01*
X580189Y-285486D01*
X580207Y-285490D01*
X580218Y-285497D01*
X580222D01*
X580331Y-285552D01*
X580429Y-285613D01*
X580513Y-285679D01*
X580546Y-285712D01*
X580578Y-285741D01*
X580608Y-285770D01*
X580633Y-285799D01*
X580655Y-285824D01*
X580669Y-285846D01*
X580684Y-285861D01*
X580695Y-285876D01*
X580698Y-285883D01*
X580702Y-285886D01*
X580731Y-285937D01*
X580757Y-285988D01*
X580797Y-286098D01*
X580826Y-286207D01*
X580844Y-286312D01*
X580851Y-286363D01*
X580859Y-286407D01*
X580862Y-286447D01*
Y-286480D01*
X580866Y-286509D01*
Y-286549D01*
X580862Y-286622D01*
X580855Y-286691D01*
X580848Y-286756D01*
X580833Y-286818D01*
X580815Y-286877D01*
X580797Y-286931D01*
X580779Y-286982D01*
X580757Y-287029D01*
X580739Y-287069D01*
X580720Y-287109D01*
X580702Y-287139D01*
X580684Y-287168D01*
X580669Y-287186D01*
X580662Y-287204D01*
X580655Y-287211D01*
X580651Y-287215D01*
X580608Y-287266D01*
X580564Y-287310D01*
X580513Y-287350D01*
X580462Y-287390D01*
X580360Y-287455D01*
X580258Y-287506D01*
X580211Y-287528D01*
X580167Y-287546D01*
X580127Y-287561D01*
X580094Y-287572D01*
X580065Y-287583D01*
X580043Y-287590D01*
X580029Y-287594D01*
X580025D01*
X579941Y-287259D01*
X580000Y-287244D01*
X580054Y-287226D01*
X580105Y-287208D01*
X580153Y-287190D01*
X580196Y-287168D01*
X580233Y-287146D01*
X580269Y-287120D01*
X580302Y-287099D01*
X580331Y-287080D01*
X580353Y-287058D01*
X580375Y-287040D01*
X580393Y-287026D01*
X580404Y-287011D01*
X580415Y-287000D01*
X580418Y-286997D01*
X580422Y-286993D01*
X580451Y-286957D01*
X580473Y-286916D01*
X580513Y-286837D01*
X580542Y-286760D01*
X580560Y-286684D01*
X580575Y-286618D01*
X580578Y-286593D01*
Y-286567D01*
X580582Y-286545D01*
Y-286520D01*
X580578Y-286436D01*
X580564Y-286356D01*
X580546Y-286283D01*
X580524Y-286218D01*
X580502Y-286167D01*
X580491Y-286145D01*
X580484Y-286127D01*
X580477Y-286112D01*
X580469Y-286101D01*
X580466Y-286094D01*
Y-286090D01*
X580415Y-286021D01*
X580360Y-285963D01*
X580298Y-285912D01*
X580240Y-285872D01*
X580189Y-285839D01*
X580145Y-285817D01*
X580127Y-285810D01*
X580116Y-285803D01*
X580109Y-285799D01*
X580105D01*
X580011Y-285770D01*
X579916Y-285748D01*
X579821Y-285730D01*
X579734Y-285719D01*
X579694Y-285715D01*
X579658Y-285712D01*
X579625D01*
X579599Y-285708D01*
X579577D01*
X579559D01*
X579548D01*
X579545D01*
X579450Y-285712D01*
X579363Y-285719D01*
X579283Y-285734D01*
X579210Y-285748D01*
X579148Y-285759D01*
X579122Y-285766D01*
X579101Y-285774D01*
X579082Y-285777D01*
X579072Y-285781D01*
X579064Y-285785D01*
X579061D01*
X578977Y-285821D01*
X578900Y-285861D01*
X578838Y-285905D01*
X578784Y-285952D01*
X578740Y-285992D01*
X578711Y-286025D01*
X578693Y-286050D01*
X578686Y-286054D01*
Y-286057D01*
X578638Y-286134D01*
X578602Y-286218D01*
X578576Y-286298D01*
X578562Y-286374D01*
X578551Y-286443D01*
X578547Y-286473D01*
Y-286498D01*
X578544Y-286516D01*
Y-286545D01*
X578547Y-286636D01*
X578562Y-286720D01*
X578584Y-286789D01*
X578606Y-286851D01*
X578631Y-286898D01*
X578649Y-286935D01*
X578664Y-286957D01*
X578671Y-286964D01*
X578726Y-287022D01*
X578788Y-287077D01*
X578853Y-287120D01*
X578919Y-287157D01*
X578977Y-287186D01*
X579006Y-287197D01*
X579028Y-287204D01*
X579046Y-287211D01*
X579061Y-287219D01*
X579068Y-287222D01*
X579072D01*
X578995Y-287550D01*
X578930Y-287528D01*
X578871Y-287506D01*
X578817Y-287477D01*
X578762Y-287452D01*
X578715Y-287422D01*
X578671Y-287390D01*
X578627Y-287361D01*
X578591Y-287332D01*
X578562Y-287302D01*
X578533Y-287277D01*
X578507Y-287251D01*
X578489Y-287233D01*
X578471Y-287215D01*
X578460Y-287200D01*
X578456Y-287193D01*
X578453Y-287190D01*
X578420Y-287139D01*
X578387Y-287088D01*
X578362Y-287037D01*
X578340Y-286982D01*
X578307Y-286873D01*
X578285Y-286775D01*
X578274Y-286727D01*
X578271Y-286687D01*
X578267Y-286647D01*
X578263Y-286614D01*
X578260Y-286589D01*
Y-286553D01*
X578267Y-286432D01*
X578285Y-286316D01*
X578307Y-286214D01*
X578322Y-286167D01*
X578336Y-286123D01*
X578351Y-286083D01*
X578365Y-286047D01*
X578376Y-286017D01*
X578387Y-285988D01*
X578398Y-285970D01*
X578405Y-285956D01*
X578409Y-285945D01*
X578413Y-285941D01*
X578475Y-285843D01*
X578547Y-285759D01*
X578620Y-285686D01*
X578693Y-285624D01*
X578758Y-285577D01*
X578788Y-285559D01*
X578813Y-285544D01*
X578831Y-285530D01*
X578846Y-285522D01*
X578857Y-285519D01*
X578860Y-285515D01*
X578973Y-285464D01*
X579090Y-285428D01*
X579206Y-285402D01*
X579312Y-285384D01*
X579359Y-285377D01*
X579406Y-285373D01*
X579443Y-285369D01*
X579479D01*
X579505Y-285366D01*
X579527D01*
X579541D01*
X579545D01*
X579676Y-285373D01*
D02*
G37*
G36*
X579203Y-288169D02*
X579177Y-288223D01*
X579151Y-288278D01*
X579126Y-288329D01*
X579104Y-288372D01*
X579086Y-288409D01*
X579072Y-288431D01*
X579068Y-288434D01*
Y-288438D01*
X579028Y-288504D01*
X578988Y-288562D01*
X578951Y-288613D01*
X578919Y-288653D01*
X578893Y-288689D01*
X578871Y-288711D01*
X578857Y-288729D01*
X578853Y-288733D01*
X580822D01*
Y-289042D01*
X578293D01*
Y-288842D01*
X578354Y-288806D01*
X578413Y-288766D01*
X578471Y-288718D01*
X578522Y-288675D01*
X578566Y-288631D01*
X578602Y-288598D01*
X578613Y-288584D01*
X578624Y-288573D01*
X578627Y-288569D01*
X578631Y-288565D01*
X578693Y-288489D01*
X578751Y-288413D01*
X578802Y-288340D01*
X578842Y-288267D01*
X578878Y-288205D01*
X578893Y-288180D01*
X578904Y-288158D01*
X578915Y-288140D01*
X578919Y-288125D01*
X578926Y-288118D01*
Y-288114D01*
X579224D01*
X579203Y-288169D01*
D02*
G37*
G36*
Y-290127D02*
X579177Y-290182D01*
X579151Y-290236D01*
X579126Y-290287D01*
X579104Y-290331D01*
X579086Y-290367D01*
X579072Y-290389D01*
X579068Y-290393D01*
Y-290396D01*
X579028Y-290462D01*
X578988Y-290520D01*
X578951Y-290571D01*
X578919Y-290611D01*
X578893Y-290648D01*
X578871Y-290669D01*
X578857Y-290688D01*
X578853Y-290691D01*
X580822D01*
Y-291001D01*
X578293D01*
Y-290800D01*
X578354Y-290764D01*
X578413Y-290724D01*
X578471Y-290677D01*
X578522Y-290633D01*
X578566Y-290589D01*
X578602Y-290557D01*
X578613Y-290542D01*
X578624Y-290531D01*
X578627Y-290527D01*
X578631Y-290524D01*
X578693Y-290447D01*
X578751Y-290371D01*
X578802Y-290298D01*
X578842Y-290225D01*
X578878Y-290163D01*
X578893Y-290138D01*
X578904Y-290116D01*
X578915Y-290098D01*
X578919Y-290083D01*
X578926Y-290076D01*
Y-290072D01*
X579224D01*
X579203Y-290127D01*
D02*
G37*
G36*
Y-292085D02*
X579177Y-292140D01*
X579151Y-292195D01*
X579126Y-292246D01*
X579104Y-292289D01*
X579086Y-292326D01*
X579072Y-292347D01*
X579068Y-292351D01*
Y-292355D01*
X579028Y-292420D01*
X578988Y-292478D01*
X578951Y-292529D01*
X578919Y-292569D01*
X578893Y-292606D01*
X578871Y-292628D01*
X578857Y-292646D01*
X578853Y-292650D01*
X580822D01*
Y-292959D01*
X578293D01*
Y-292759D01*
X578354Y-292722D01*
X578413Y-292682D01*
X578471Y-292635D01*
X578522Y-292591D01*
X578566Y-292548D01*
X578602Y-292515D01*
X578613Y-292500D01*
X578624Y-292489D01*
X578627Y-292486D01*
X578631Y-292482D01*
X578693Y-292406D01*
X578751Y-292329D01*
X578802Y-292256D01*
X578842Y-292184D01*
X578878Y-292122D01*
X578893Y-292096D01*
X578904Y-292074D01*
X578915Y-292056D01*
X578919Y-292042D01*
X578926Y-292034D01*
Y-292031D01*
X579224D01*
X579203Y-292085D01*
D02*
G37*
G36*
X549823Y-278189D02*
X549922Y-278207D01*
X550005Y-278236D01*
X550078Y-278265D01*
X550111Y-278283D01*
X550136Y-278298D01*
X550162Y-278312D01*
X550180Y-278327D01*
X550195Y-278338D01*
X550206Y-278345D01*
X550213Y-278349D01*
X550216Y-278352D01*
X550286Y-278422D01*
X550340Y-278498D01*
X550384Y-278578D01*
X550420Y-278658D01*
X550442Y-278727D01*
X550453Y-278756D01*
X550460Y-278782D01*
X550464Y-278804D01*
X550468Y-278818D01*
X550471Y-278829D01*
Y-278833D01*
X550162Y-278888D01*
X550147Y-278807D01*
X550126Y-278738D01*
X550100Y-278680D01*
X550074Y-278633D01*
X550049Y-278596D01*
X550027Y-278571D01*
X550013Y-278553D01*
X550009Y-278549D01*
X549962Y-278513D01*
X549911Y-278484D01*
X549863Y-278465D01*
X549816Y-278451D01*
X549772Y-278443D01*
X549740Y-278436D01*
X549711D01*
X549645Y-278440D01*
X549587Y-278454D01*
X549536Y-278473D01*
X549492Y-278491D01*
X549459Y-278513D01*
X549434Y-278531D01*
X549416Y-278545D01*
X549412Y-278549D01*
X549372Y-278593D01*
X549343Y-278640D01*
X549325Y-278687D01*
X549310Y-278731D01*
X549303Y-278771D01*
X549296Y-278800D01*
Y-278822D01*
Y-278826D01*
Y-278829D01*
Y-278869D01*
X549303Y-278906D01*
X549321Y-278968D01*
X549346Y-279022D01*
X549376Y-279069D01*
X549405Y-279102D01*
X549430Y-279128D01*
X549448Y-279142D01*
X549452Y-279146D01*
X549456D01*
X549518Y-279179D01*
X549576Y-279204D01*
X549638Y-279222D01*
X549692Y-279233D01*
X549740Y-279241D01*
X549780Y-279248D01*
X549827D01*
X549842Y-279244D01*
X549860D01*
X549896Y-279517D01*
X549849Y-279506D01*
X549805Y-279499D01*
X549769Y-279492D01*
X549736Y-279488D01*
X549711Y-279485D01*
X549678D01*
X549601Y-279492D01*
X549532Y-279506D01*
X549470Y-279528D01*
X549419Y-279554D01*
X549379Y-279579D01*
X549350Y-279601D01*
X549332Y-279615D01*
X549325Y-279623D01*
X549277Y-279677D01*
X549241Y-279736D01*
X549216Y-279794D01*
X549201Y-279852D01*
X549190Y-279899D01*
X549186Y-279940D01*
X549183Y-279954D01*
Y-279965D01*
Y-279972D01*
Y-279976D01*
X549190Y-280056D01*
X549208Y-280129D01*
X549230Y-280191D01*
X549259Y-280245D01*
X549288Y-280289D01*
X549310Y-280322D01*
X549328Y-280344D01*
X549336Y-280351D01*
X549394Y-280402D01*
X549456Y-280438D01*
X549518Y-280464D01*
X549576Y-280482D01*
X549627Y-280493D01*
X549667Y-280496D01*
X549681Y-280500D01*
X549703D01*
X549769Y-280496D01*
X549831Y-280482D01*
X549885Y-280464D01*
X549929Y-280442D01*
X549965Y-280424D01*
X549994Y-280405D01*
X550009Y-280391D01*
X550016Y-280387D01*
X550060Y-280336D01*
X550096Y-280278D01*
X550129Y-280216D01*
X550155Y-280151D01*
X550173Y-280096D01*
X550180Y-280070D01*
X550184Y-280049D01*
X550187Y-280030D01*
X550191Y-280016D01*
X550195Y-280009D01*
Y-280005D01*
X550504Y-280045D01*
X550497Y-280103D01*
X550486Y-280158D01*
X550453Y-280260D01*
X550413Y-280347D01*
X550391Y-280384D01*
X550369Y-280420D01*
X550348Y-280453D01*
X550326Y-280478D01*
X550308Y-280504D01*
X550289Y-280522D01*
X550278Y-280536D01*
X550267Y-280547D01*
X550260Y-280555D01*
X550256Y-280558D01*
X550213Y-280591D01*
X550169Y-280624D01*
X550126Y-280649D01*
X550078Y-280671D01*
X549987Y-280708D01*
X549900Y-280729D01*
X549860Y-280737D01*
X549823Y-280744D01*
X549791Y-280748D01*
X549761Y-280751D01*
X549740Y-280755D01*
X549707D01*
X549638Y-280751D01*
X549576Y-280744D01*
X549514Y-280733D01*
X549456Y-280718D01*
X549401Y-280700D01*
X549354Y-280682D01*
X549306Y-280660D01*
X549266Y-280638D01*
X549226Y-280620D01*
X549194Y-280598D01*
X549164Y-280580D01*
X549143Y-280562D01*
X549124Y-280547D01*
X549110Y-280536D01*
X549103Y-280529D01*
X549099Y-280525D01*
X549055Y-280482D01*
X549019Y-280434D01*
X548986Y-280387D01*
X548957Y-280340D01*
X548935Y-280296D01*
X548913Y-280249D01*
X548884Y-280161D01*
X548877Y-280121D01*
X548870Y-280085D01*
X548862Y-280052D01*
X548859Y-280023D01*
X548855Y-280001D01*
Y-279983D01*
Y-279972D01*
Y-279969D01*
X548859Y-279881D01*
X548873Y-279801D01*
X548895Y-279732D01*
X548917Y-279674D01*
X548939Y-279626D01*
X548961Y-279590D01*
X548975Y-279568D01*
X548979Y-279561D01*
X549030Y-279506D01*
X549084Y-279459D01*
X549143Y-279423D01*
X549201Y-279394D01*
X549252Y-279372D01*
X549292Y-279357D01*
X549306Y-279353D01*
X549317Y-279350D01*
X549325Y-279346D01*
X549328D01*
X549266Y-279313D01*
X549216Y-279281D01*
X549172Y-279244D01*
X549135Y-279211D01*
X549106Y-279182D01*
X549084Y-279157D01*
X549074Y-279142D01*
X549070Y-279135D01*
X549041Y-279084D01*
X549019Y-279033D01*
X549001Y-278982D01*
X548990Y-278935D01*
X548982Y-278895D01*
X548979Y-278866D01*
Y-278844D01*
Y-278836D01*
X548982Y-278775D01*
X548993Y-278713D01*
X549008Y-278658D01*
X549026Y-278611D01*
X549044Y-278571D01*
X549059Y-278538D01*
X549070Y-278520D01*
X549074Y-278513D01*
X549110Y-278458D01*
X549154Y-278411D01*
X549197Y-278371D01*
X549241Y-278334D01*
X549277Y-278309D01*
X549310Y-278287D01*
X549332Y-278276D01*
X549336Y-278272D01*
X549339D01*
X549405Y-278243D01*
X549470Y-278221D01*
X549536Y-278203D01*
X549594Y-278192D01*
X549641Y-278185D01*
X549681Y-278181D01*
X549772D01*
X549823Y-278189D01*
D02*
G37*
G36*
X553496Y-278243D02*
X553536Y-278302D01*
X553583Y-278360D01*
X553627Y-278411D01*
X553671Y-278454D01*
X553704Y-278491D01*
X553718Y-278502D01*
X553729Y-278513D01*
X553733Y-278516D01*
X553736Y-278520D01*
X553813Y-278582D01*
X553889Y-278640D01*
X553962Y-278691D01*
X554035Y-278731D01*
X554097Y-278767D01*
X554122Y-278782D01*
X554144Y-278793D01*
X554162Y-278804D01*
X554177Y-278807D01*
X554184Y-278815D01*
X554188D01*
Y-279113D01*
X554133Y-279091D01*
X554078Y-279066D01*
X554024Y-279040D01*
X553973Y-279015D01*
X553929Y-278993D01*
X553893Y-278975D01*
X553871Y-278960D01*
X553867Y-278957D01*
X553864D01*
X553798Y-278917D01*
X553740Y-278877D01*
X553689Y-278840D01*
X553649Y-278807D01*
X553613Y-278782D01*
X553591Y-278760D01*
X553573Y-278746D01*
X553569Y-278742D01*
Y-280711D01*
X553260D01*
Y-278181D01*
X553460D01*
X553496Y-278243D01*
D02*
G37*
G36*
X551538D02*
X551578Y-278302D01*
X551625Y-278360D01*
X551669Y-278411D01*
X551713Y-278454D01*
X551745Y-278491D01*
X551760Y-278502D01*
X551771Y-278513D01*
X551774Y-278516D01*
X551778Y-278520D01*
X551855Y-278582D01*
X551931Y-278640D01*
X552004Y-278691D01*
X552076Y-278731D01*
X552138Y-278767D01*
X552164Y-278782D01*
X552186Y-278793D01*
X552204Y-278804D01*
X552218Y-278807D01*
X552226Y-278815D01*
X552229D01*
Y-279113D01*
X552175Y-279091D01*
X552120Y-279066D01*
X552066Y-279040D01*
X552015Y-279015D01*
X551971Y-278993D01*
X551935Y-278975D01*
X551913Y-278960D01*
X551909Y-278957D01*
X551905D01*
X551840Y-278917D01*
X551782Y-278877D01*
X551731Y-278840D01*
X551691Y-278807D01*
X551654Y-278782D01*
X551632Y-278760D01*
X551614Y-278746D01*
X551611Y-278742D01*
Y-280711D01*
X551301D01*
Y-278181D01*
X551501D01*
X551538Y-278243D01*
D02*
G37*
G36*
X555869Y-278156D02*
X555986Y-278174D01*
X556088Y-278196D01*
X556135Y-278210D01*
X556179Y-278225D01*
X556219Y-278240D01*
X556255Y-278254D01*
X556284Y-278265D01*
X556314Y-278276D01*
X556332Y-278287D01*
X556346Y-278294D01*
X556357Y-278298D01*
X556361Y-278302D01*
X556459Y-278363D01*
X556543Y-278436D01*
X556616Y-278509D01*
X556677Y-278582D01*
X556725Y-278647D01*
X556743Y-278676D01*
X556757Y-278702D01*
X556772Y-278720D01*
X556779Y-278735D01*
X556783Y-278746D01*
X556787Y-278749D01*
X556838Y-278862D01*
X556874Y-278978D01*
X556899Y-279095D01*
X556918Y-279201D01*
X556925Y-279248D01*
X556929Y-279295D01*
X556932Y-279332D01*
Y-279368D01*
X556936Y-279394D01*
Y-279415D01*
Y-279430D01*
Y-279433D01*
X556929Y-279565D01*
X556914Y-279692D01*
X556896Y-279805D01*
X556881Y-279859D01*
X556870Y-279907D01*
X556859Y-279950D01*
X556845Y-279990D01*
X556834Y-280027D01*
X556827Y-280056D01*
X556816Y-280078D01*
X556812Y-280096D01*
X556805Y-280107D01*
Y-280111D01*
X556750Y-280220D01*
X556688Y-280318D01*
X556623Y-280402D01*
X556590Y-280434D01*
X556561Y-280467D01*
X556532Y-280496D01*
X556503Y-280522D01*
X556477Y-280544D01*
X556455Y-280558D01*
X556441Y-280573D01*
X556426Y-280584D01*
X556419Y-280587D01*
X556415Y-280591D01*
X556364Y-280620D01*
X556314Y-280646D01*
X556204Y-280686D01*
X556095Y-280715D01*
X555990Y-280733D01*
X555939Y-280740D01*
X555895Y-280748D01*
X555855Y-280751D01*
X555822D01*
X555793Y-280755D01*
X555753D01*
X555680Y-280751D01*
X555611Y-280744D01*
X555545Y-280737D01*
X555484Y-280722D01*
X555425Y-280704D01*
X555371Y-280686D01*
X555320Y-280667D01*
X555272Y-280646D01*
X555232Y-280627D01*
X555192Y-280609D01*
X555163Y-280591D01*
X555134Y-280573D01*
X555116Y-280558D01*
X555098Y-280551D01*
X555090Y-280544D01*
X555087Y-280540D01*
X555036Y-280496D01*
X554992Y-280453D01*
X554952Y-280402D01*
X554912Y-280351D01*
X554847Y-280249D01*
X554796Y-280147D01*
X554774Y-280100D01*
X554756Y-280056D01*
X554741Y-280016D01*
X554730Y-279983D01*
X554719Y-279954D01*
X554712Y-279932D01*
X554708Y-279918D01*
Y-279914D01*
X555043Y-279830D01*
X555058Y-279889D01*
X555076Y-279943D01*
X555094Y-279994D01*
X555112Y-280041D01*
X555134Y-280085D01*
X555156Y-280121D01*
X555181Y-280158D01*
X555203Y-280191D01*
X555222Y-280220D01*
X555243Y-280242D01*
X555262Y-280263D01*
X555276Y-280282D01*
X555291Y-280293D01*
X555302Y-280304D01*
X555305Y-280307D01*
X555309Y-280311D01*
X555345Y-280340D01*
X555385Y-280362D01*
X555465Y-280402D01*
X555542Y-280431D01*
X555618Y-280449D01*
X555684Y-280464D01*
X555709Y-280467D01*
X555735D01*
X555757Y-280471D01*
X555782D01*
X555866Y-280467D01*
X555946Y-280453D01*
X556019Y-280434D01*
X556084Y-280413D01*
X556135Y-280391D01*
X556157Y-280380D01*
X556175Y-280373D01*
X556190Y-280365D01*
X556201Y-280358D01*
X556208Y-280354D01*
X556212D01*
X556281Y-280304D01*
X556339Y-280249D01*
X556390Y-280187D01*
X556430Y-280129D01*
X556463Y-280078D01*
X556485Y-280034D01*
X556492Y-280016D01*
X556499Y-280005D01*
X556503Y-279998D01*
Y-279994D01*
X556532Y-279899D01*
X556554Y-279805D01*
X556572Y-279710D01*
X556583Y-279623D01*
X556587Y-279583D01*
X556590Y-279546D01*
Y-279514D01*
X556594Y-279488D01*
Y-279466D01*
Y-279448D01*
Y-279437D01*
Y-279433D01*
X556590Y-279339D01*
X556583Y-279252D01*
X556568Y-279171D01*
X556554Y-279099D01*
X556543Y-279037D01*
X556535Y-279011D01*
X556528Y-278989D01*
X556525Y-278971D01*
X556521Y-278960D01*
X556517Y-278953D01*
Y-278949D01*
X556481Y-278866D01*
X556441Y-278789D01*
X556397Y-278727D01*
X556350Y-278673D01*
X556310Y-278629D01*
X556277Y-278600D01*
X556252Y-278582D01*
X556248Y-278574D01*
X556244D01*
X556168Y-278527D01*
X556084Y-278491D01*
X556004Y-278465D01*
X555928Y-278451D01*
X555859Y-278440D01*
X555829Y-278436D01*
X555804D01*
X555786Y-278432D01*
X555757D01*
X555665Y-278436D01*
X555582Y-278451D01*
X555513Y-278473D01*
X555451Y-278494D01*
X555404Y-278520D01*
X555367Y-278538D01*
X555345Y-278553D01*
X555338Y-278560D01*
X555280Y-278614D01*
X555225Y-278676D01*
X555181Y-278742D01*
X555145Y-278807D01*
X555116Y-278866D01*
X555105Y-278895D01*
X555098Y-278917D01*
X555090Y-278935D01*
X555083Y-278949D01*
X555080Y-278957D01*
Y-278960D01*
X554752Y-278884D01*
X554774Y-278818D01*
X554796Y-278760D01*
X554825Y-278706D01*
X554850Y-278651D01*
X554879Y-278604D01*
X554912Y-278560D01*
X554941Y-278516D01*
X554970Y-278480D01*
X554999Y-278451D01*
X555025Y-278422D01*
X555050Y-278396D01*
X555069Y-278378D01*
X555087Y-278360D01*
X555101Y-278349D01*
X555109Y-278345D01*
X555112Y-278342D01*
X555163Y-278309D01*
X555214Y-278276D01*
X555265Y-278251D01*
X555320Y-278229D01*
X555429Y-278196D01*
X555527Y-278174D01*
X555575Y-278163D01*
X555615Y-278159D01*
X555655Y-278156D01*
X555687Y-278152D01*
X555713Y-278149D01*
X555749D01*
X555869Y-278156D01*
D02*
G37*
G36*
X594890Y-279255D02*
X594952Y-279262D01*
X595014Y-279273D01*
X595072Y-279288D01*
X595127Y-279306D01*
X595174Y-279324D01*
X595222Y-279346D01*
X595262Y-279368D01*
X595302Y-279386D01*
X595334Y-279408D01*
X595364Y-279426D01*
X595385Y-279444D01*
X595403Y-279459D01*
X595418Y-279470D01*
X595425Y-279477D01*
X595429Y-279481D01*
X595473Y-279524D01*
X595509Y-279572D01*
X595542Y-279619D01*
X595571Y-279666D01*
X595593Y-279710D01*
X595615Y-279757D01*
X595644Y-279845D01*
X595651Y-279885D01*
X595658Y-279921D01*
X595666Y-279954D01*
X595669Y-279983D01*
X595673Y-280005D01*
Y-280023D01*
Y-280034D01*
Y-280038D01*
X595669Y-280125D01*
X595655Y-280205D01*
X595633Y-280274D01*
X595611Y-280332D01*
X595589Y-280380D01*
X595567Y-280416D01*
X595553Y-280438D01*
X595549Y-280445D01*
X595498Y-280500D01*
X595444Y-280547D01*
X595385Y-280584D01*
X595327Y-280613D01*
X595276Y-280634D01*
X595236Y-280649D01*
X595222Y-280653D01*
X595211Y-280656D01*
X595203Y-280660D01*
X595200D01*
X595262Y-280693D01*
X595313Y-280726D01*
X595356Y-280762D01*
X595393Y-280795D01*
X595422Y-280824D01*
X595444Y-280849D01*
X595455Y-280864D01*
X595458Y-280871D01*
X595487Y-280922D01*
X595509Y-280973D01*
X595527Y-281024D01*
X595538Y-281071D01*
X595545Y-281111D01*
X595549Y-281140D01*
Y-281162D01*
Y-281170D01*
X595545Y-281231D01*
X595535Y-281293D01*
X595520Y-281348D01*
X595502Y-281395D01*
X595484Y-281435D01*
X595469Y-281468D01*
X595458Y-281486D01*
X595455Y-281494D01*
X595418Y-281548D01*
X595374Y-281595D01*
X595331Y-281635D01*
X595287Y-281672D01*
X595251Y-281697D01*
X595218Y-281719D01*
X595196Y-281730D01*
X595192Y-281734D01*
X595189D01*
X595123Y-281763D01*
X595058Y-281785D01*
X594992Y-281803D01*
X594934Y-281814D01*
X594887Y-281821D01*
X594847Y-281825D01*
X594756D01*
X594705Y-281818D01*
X594606Y-281799D01*
X594523Y-281770D01*
X594450Y-281741D01*
X594417Y-281723D01*
X594392Y-281708D01*
X594366Y-281694D01*
X594348Y-281679D01*
X594333Y-281668D01*
X594322Y-281661D01*
X594315Y-281657D01*
X594312Y-281654D01*
X594242Y-281585D01*
X594188Y-281508D01*
X594144Y-281428D01*
X594108Y-281348D01*
X594086Y-281279D01*
X594075Y-281250D01*
X594068Y-281224D01*
X594064Y-281202D01*
X594060Y-281188D01*
X594057Y-281177D01*
Y-281173D01*
X594366Y-281119D01*
X594381Y-281199D01*
X594403Y-281268D01*
X594428Y-281326D01*
X594453Y-281373D01*
X594479Y-281410D01*
X594501Y-281435D01*
X594515Y-281453D01*
X594519Y-281457D01*
X594566Y-281494D01*
X594617Y-281523D01*
X594665Y-281541D01*
X594712Y-281555D01*
X594756Y-281563D01*
X594788Y-281570D01*
X594817D01*
X594883Y-281566D01*
X594941Y-281552D01*
X594992Y-281534D01*
X595036Y-281515D01*
X595069Y-281494D01*
X595094Y-281475D01*
X595112Y-281461D01*
X595116Y-281457D01*
X595156Y-281414D01*
X595185Y-281366D01*
X595203Y-281319D01*
X595218Y-281275D01*
X595225Y-281235D01*
X595232Y-281206D01*
Y-281184D01*
Y-281181D01*
Y-281177D01*
Y-281137D01*
X595225Y-281100D01*
X595207Y-281039D01*
X595182Y-280984D01*
X595152Y-280937D01*
X595123Y-280904D01*
X595098Y-280878D01*
X595080Y-280864D01*
X595076Y-280860D01*
X595072D01*
X595010Y-280827D01*
X594952Y-280802D01*
X594890Y-280784D01*
X594836Y-280773D01*
X594788Y-280766D01*
X594748Y-280758D01*
X594701D01*
X594687Y-280762D01*
X594668D01*
X594632Y-280489D01*
X594679Y-280500D01*
X594723Y-280507D01*
X594759Y-280514D01*
X594792Y-280518D01*
X594817Y-280522D01*
X594850D01*
X594927Y-280514D01*
X594996Y-280500D01*
X595058Y-280478D01*
X595109Y-280452D01*
X595149Y-280427D01*
X595178Y-280405D01*
X595196Y-280391D01*
X595203Y-280383D01*
X595251Y-280329D01*
X595287Y-280271D01*
X595313Y-280212D01*
X595327Y-280154D01*
X595338Y-280107D01*
X595342Y-280067D01*
X595345Y-280052D01*
Y-280041D01*
Y-280034D01*
Y-280030D01*
X595338Y-279950D01*
X595320Y-279877D01*
X595298Y-279816D01*
X595269Y-279761D01*
X595240Y-279717D01*
X595218Y-279684D01*
X595200Y-279663D01*
X595192Y-279655D01*
X595134Y-279604D01*
X595072Y-279568D01*
X595010Y-279542D01*
X594952Y-279524D01*
X594901Y-279513D01*
X594861Y-279510D01*
X594847Y-279506D01*
X594825D01*
X594759Y-279510D01*
X594697Y-279524D01*
X594643Y-279542D01*
X594599Y-279564D01*
X594563Y-279583D01*
X594534Y-279601D01*
X594519Y-279615D01*
X594512Y-279619D01*
X594468Y-279670D01*
X594432Y-279728D01*
X594399Y-279790D01*
X594373Y-279856D01*
X594355Y-279910D01*
X594348Y-279936D01*
X594344Y-279958D01*
X594341Y-279976D01*
X594337Y-279990D01*
X594333Y-279997D01*
Y-280001D01*
X594024Y-279961D01*
X594031Y-279903D01*
X594042Y-279848D01*
X594075Y-279746D01*
X594115Y-279659D01*
X594137Y-279623D01*
X594159Y-279586D01*
X594180Y-279553D01*
X594202Y-279528D01*
X594221Y-279503D01*
X594239Y-279484D01*
X594250Y-279470D01*
X594261Y-279459D01*
X594268Y-279451D01*
X594272Y-279448D01*
X594315Y-279415D01*
X594359Y-279382D01*
X594403Y-279357D01*
X594450Y-279335D01*
X594541Y-279299D01*
X594628Y-279277D01*
X594668Y-279270D01*
X594705Y-279262D01*
X594737Y-279259D01*
X594767Y-279255D01*
X594788Y-279251D01*
X594821D01*
X594890Y-279255D01*
D02*
G37*
G36*
X592932D02*
X592994Y-279262D01*
X593056Y-279273D01*
X593114Y-279288D01*
X593169Y-279306D01*
X593216Y-279324D01*
X593263Y-279346D01*
X593303Y-279368D01*
X593343Y-279386D01*
X593376Y-279408D01*
X593405Y-279426D01*
X593427Y-279444D01*
X593445Y-279459D01*
X593460Y-279470D01*
X593467Y-279477D01*
X593471Y-279481D01*
X593514Y-279524D01*
X593551Y-279572D01*
X593584Y-279619D01*
X593613Y-279666D01*
X593635Y-279710D01*
X593656Y-279757D01*
X593685Y-279845D01*
X593693Y-279885D01*
X593700Y-279921D01*
X593707Y-279954D01*
X593711Y-279983D01*
X593715Y-280005D01*
Y-280023D01*
Y-280034D01*
Y-280038D01*
X593711Y-280125D01*
X593696Y-280205D01*
X593675Y-280274D01*
X593653Y-280332D01*
X593631Y-280380D01*
X593609Y-280416D01*
X593595Y-280438D01*
X593591Y-280445D01*
X593540Y-280500D01*
X593485Y-280547D01*
X593427Y-280584D01*
X593369Y-280613D01*
X593318Y-280634D01*
X593278Y-280649D01*
X593263Y-280653D01*
X593252Y-280656D01*
X593245Y-280660D01*
X593241D01*
X593303Y-280693D01*
X593354Y-280726D01*
X593398Y-280762D01*
X593434Y-280795D01*
X593463Y-280824D01*
X593485Y-280849D01*
X593496Y-280864D01*
X593500Y-280871D01*
X593529Y-280922D01*
X593551Y-280973D01*
X593569Y-281024D01*
X593580Y-281071D01*
X593587Y-281111D01*
X593591Y-281140D01*
Y-281162D01*
Y-281170D01*
X593587Y-281231D01*
X593576Y-281293D01*
X593562Y-281348D01*
X593543Y-281395D01*
X593525Y-281435D01*
X593511Y-281468D01*
X593500Y-281486D01*
X593496Y-281494D01*
X593460Y-281548D01*
X593416Y-281595D01*
X593372Y-281635D01*
X593329Y-281672D01*
X593292Y-281697D01*
X593260Y-281719D01*
X593238Y-281730D01*
X593234Y-281734D01*
X593230D01*
X593165Y-281763D01*
X593099Y-281785D01*
X593034Y-281803D01*
X592976Y-281814D01*
X592928Y-281821D01*
X592888Y-281825D01*
X592797D01*
X592746Y-281818D01*
X592648Y-281799D01*
X592564Y-281770D01*
X592492Y-281741D01*
X592459Y-281723D01*
X592433Y-281708D01*
X592408Y-281694D01*
X592390Y-281679D01*
X592375Y-281668D01*
X592364Y-281661D01*
X592357Y-281657D01*
X592353Y-281654D01*
X592284Y-281585D01*
X592230Y-281508D01*
X592186Y-281428D01*
X592149Y-281348D01*
X592128Y-281279D01*
X592117Y-281250D01*
X592109Y-281224D01*
X592106Y-281202D01*
X592102Y-281188D01*
X592098Y-281177D01*
Y-281173D01*
X592408Y-281119D01*
X592422Y-281199D01*
X592444Y-281268D01*
X592470Y-281326D01*
X592495Y-281373D01*
X592521Y-281410D01*
X592543Y-281435D01*
X592557Y-281453D01*
X592561Y-281457D01*
X592608Y-281494D01*
X592659Y-281523D01*
X592706Y-281541D01*
X592754Y-281555D01*
X592797Y-281563D01*
X592830Y-281570D01*
X592859D01*
X592925Y-281566D01*
X592983Y-281552D01*
X593034Y-281534D01*
X593078Y-281515D01*
X593110Y-281494D01*
X593136Y-281475D01*
X593154Y-281461D01*
X593158Y-281457D01*
X593198Y-281414D01*
X593227Y-281366D01*
X593245Y-281319D01*
X593260Y-281275D01*
X593267Y-281235D01*
X593274Y-281206D01*
Y-281184D01*
Y-281181D01*
Y-281177D01*
Y-281137D01*
X593267Y-281100D01*
X593249Y-281039D01*
X593223Y-280984D01*
X593194Y-280937D01*
X593165Y-280904D01*
X593140Y-280878D01*
X593121Y-280864D01*
X593118Y-280860D01*
X593114D01*
X593052Y-280827D01*
X592994Y-280802D01*
X592932Y-280784D01*
X592877Y-280773D01*
X592830Y-280766D01*
X592790Y-280758D01*
X592743D01*
X592728Y-280762D01*
X592710D01*
X592673Y-280489D01*
X592721Y-280500D01*
X592765Y-280507D01*
X592801Y-280514D01*
X592834Y-280518D01*
X592859Y-280522D01*
X592892D01*
X592968Y-280514D01*
X593038Y-280500D01*
X593099Y-280478D01*
X593150Y-280452D01*
X593190Y-280427D01*
X593220Y-280405D01*
X593238Y-280391D01*
X593245Y-280383D01*
X593292Y-280329D01*
X593329Y-280271D01*
X593354Y-280212D01*
X593369Y-280154D01*
X593380Y-280107D01*
X593383Y-280067D01*
X593387Y-280052D01*
Y-280041D01*
Y-280034D01*
Y-280030D01*
X593380Y-279950D01*
X593362Y-279877D01*
X593340Y-279816D01*
X593310Y-279761D01*
X593281Y-279717D01*
X593260Y-279684D01*
X593241Y-279663D01*
X593234Y-279655D01*
X593176Y-279604D01*
X593114Y-279568D01*
X593052Y-279542D01*
X592994Y-279524D01*
X592943Y-279513D01*
X592903Y-279510D01*
X592888Y-279506D01*
X592867D01*
X592801Y-279510D01*
X592739Y-279524D01*
X592685Y-279542D01*
X592641Y-279564D01*
X592604Y-279583D01*
X592575Y-279601D01*
X592561Y-279615D01*
X592553Y-279619D01*
X592510Y-279670D01*
X592473Y-279728D01*
X592441Y-279790D01*
X592415Y-279856D01*
X592397Y-279910D01*
X592390Y-279936D01*
X592386Y-279958D01*
X592382Y-279976D01*
X592379Y-279990D01*
X592375Y-279997D01*
Y-280001D01*
X592066Y-279961D01*
X592073Y-279903D01*
X592084Y-279848D01*
X592117Y-279746D01*
X592157Y-279659D01*
X592178Y-279623D01*
X592200Y-279586D01*
X592222Y-279553D01*
X592244Y-279528D01*
X592262Y-279503D01*
X592280Y-279484D01*
X592291Y-279470D01*
X592302Y-279459D01*
X592310Y-279451D01*
X592313Y-279448D01*
X592357Y-279415D01*
X592401Y-279382D01*
X592444Y-279357D01*
X592492Y-279335D01*
X592583Y-279299D01*
X592670Y-279277D01*
X592710Y-279270D01*
X592746Y-279262D01*
X592779Y-279259D01*
X592808Y-279255D01*
X592830Y-279251D01*
X592863D01*
X592932Y-279255D01*
D02*
G37*
G36*
X590777Y-279259D02*
X590835Y-279266D01*
X590890Y-279273D01*
X590944Y-279284D01*
X590992Y-279295D01*
X591036Y-279306D01*
X591076Y-279321D01*
X591112Y-279335D01*
X591141Y-279346D01*
X591170Y-279357D01*
X591192Y-279368D01*
X591210Y-279379D01*
X591221Y-279382D01*
X591228Y-279390D01*
X591232D01*
X591312Y-279444D01*
X591378Y-279506D01*
X591429Y-279564D01*
X591472Y-279623D01*
X591505Y-279674D01*
X591527Y-279714D01*
X591534Y-279728D01*
X591541Y-279739D01*
X591545Y-279746D01*
Y-279750D01*
X591560Y-279794D01*
X591574Y-279841D01*
X591596Y-279939D01*
X591611Y-280041D01*
X591622Y-280139D01*
X591625Y-280183D01*
X591629Y-280227D01*
Y-280263D01*
X591633Y-280296D01*
Y-280322D01*
Y-280340D01*
Y-280354D01*
Y-280358D01*
Y-281814D01*
X591298D01*
Y-280358D01*
Y-280274D01*
X591290Y-280194D01*
X591283Y-280125D01*
X591272Y-280059D01*
X591261Y-280001D01*
X591247Y-279947D01*
X591236Y-279899D01*
X591221Y-279859D01*
X591207Y-279826D01*
X591192Y-279794D01*
X591178Y-279772D01*
X591167Y-279750D01*
X591156Y-279735D01*
X591148Y-279725D01*
X591145Y-279721D01*
X591141Y-279717D01*
X591108Y-279688D01*
X591072Y-279663D01*
X590992Y-279623D01*
X590908Y-279593D01*
X590821Y-279575D01*
X590741Y-279561D01*
X590708Y-279557D01*
X590675D01*
X590653Y-279553D01*
X590617D01*
X590541Y-279557D01*
X590471Y-279568D01*
X590406Y-279579D01*
X590355Y-279597D01*
X590311Y-279612D01*
X590278Y-279623D01*
X590260Y-279633D01*
X590253Y-279637D01*
X590202Y-279670D01*
X590158Y-279710D01*
X590122Y-279750D01*
X590096Y-279786D01*
X590075Y-279823D01*
X590056Y-279848D01*
X590049Y-279867D01*
X590045Y-279874D01*
X590035Y-279907D01*
X590027Y-279939D01*
X590013Y-280016D01*
X590002Y-280096D01*
X589994Y-280176D01*
X589991Y-280245D01*
Y-280278D01*
X589987Y-280303D01*
Y-280325D01*
Y-280343D01*
Y-280354D01*
Y-280358D01*
Y-281814D01*
X589652D01*
Y-280358D01*
Y-280285D01*
X589656Y-280216D01*
X589660Y-280150D01*
X589667Y-280088D01*
X589674Y-280034D01*
X589681Y-279983D01*
X589692Y-279936D01*
X589700Y-279892D01*
X589707Y-279852D01*
X589718Y-279819D01*
X589725Y-279790D01*
X589732Y-279768D01*
X589740Y-279750D01*
X589743Y-279735D01*
X589747Y-279728D01*
Y-279725D01*
X589787Y-279644D01*
X589838Y-279572D01*
X589889Y-279513D01*
X589944Y-279462D01*
X589991Y-279422D01*
X590031Y-279393D01*
X590045Y-279386D01*
X590056Y-279379D01*
X590064Y-279371D01*
X590067D01*
X590158Y-279331D01*
X590253Y-279302D01*
X590351Y-279280D01*
X590442Y-279266D01*
X590482Y-279262D01*
X590522Y-279259D01*
X590559Y-279255D01*
X590588D01*
X590613Y-279251D01*
X590646D01*
X590777Y-279259D01*
D02*
G37*
G36*
X597181Y-270184D02*
X597243Y-270191D01*
X597305Y-270202D01*
X597360Y-270217D01*
X597410Y-270235D01*
X597462Y-270253D01*
X597505Y-270275D01*
X597545Y-270293D01*
X597582Y-270315D01*
X597614Y-270337D01*
X597640Y-270355D01*
X597665Y-270373D01*
X597683Y-270388D01*
X597694Y-270399D01*
X597702Y-270406D01*
X597705Y-270410D01*
X597745Y-270453D01*
X597782Y-270497D01*
X597811Y-270544D01*
X597836Y-270592D01*
X597862Y-270639D01*
X597880Y-270686D01*
X597906Y-270774D01*
X597917Y-270814D01*
X597924Y-270850D01*
X597927Y-270883D01*
X597931Y-270912D01*
X597935Y-270934D01*
Y-271014D01*
X597927Y-271058D01*
X597909Y-271145D01*
X597884Y-271225D01*
X597855Y-271298D01*
X597825Y-271356D01*
X597811Y-271382D01*
X597800Y-271404D01*
X597789Y-271422D01*
X597782Y-271433D01*
X597778Y-271440D01*
X597775Y-271444D01*
X598455Y-271309D01*
Y-270301D01*
X598750D01*
Y-271553D01*
X597454Y-271797D01*
X597414Y-271505D01*
X597454Y-271480D01*
X597487Y-271447D01*
X597520Y-271418D01*
X597545Y-271389D01*
X597563Y-271360D01*
X597582Y-271338D01*
X597589Y-271323D01*
X597592Y-271320D01*
X597614Y-271272D01*
X597633Y-271225D01*
X597644Y-271181D01*
X597654Y-271138D01*
X597658Y-271101D01*
X597662Y-271072D01*
Y-271003D01*
X597654Y-270959D01*
X597636Y-270883D01*
X597611Y-270817D01*
X597585Y-270759D01*
X597556Y-270715D01*
X597531Y-270683D01*
X597512Y-270665D01*
X597509Y-270657D01*
X597505D01*
X597443Y-270606D01*
X597378Y-270570D01*
X597309Y-270544D01*
X597239Y-270526D01*
X597181Y-270515D01*
X597156Y-270512D01*
X597134D01*
X597116Y-270508D01*
X597101D01*
X597094D01*
X597090D01*
X597039D01*
X596992Y-270515D01*
X596901Y-270533D01*
X596825Y-270559D01*
X596763Y-270585D01*
X596712Y-270614D01*
X596672Y-270639D01*
X596661Y-270650D01*
X596650Y-270657D01*
X596646Y-270661D01*
X596642Y-270665D01*
X596613Y-270694D01*
X596588Y-270723D01*
X596544Y-270788D01*
X596515Y-270850D01*
X596497Y-270912D01*
X596482Y-270963D01*
X596479Y-271007D01*
X596475Y-271021D01*
Y-271043D01*
X596479Y-271112D01*
X596493Y-271174D01*
X596511Y-271229D01*
X596533Y-271272D01*
X596555Y-271312D01*
X596573Y-271342D01*
X596588Y-271356D01*
X596592Y-271363D01*
X596642Y-271407D01*
X596697Y-271444D01*
X596759Y-271473D01*
X596814Y-271495D01*
X596868Y-271509D01*
X596908Y-271520D01*
X596926Y-271524D01*
X596937Y-271527D01*
X596945D01*
X596948D01*
X596923Y-271851D01*
X596865Y-271844D01*
X596810Y-271833D01*
X596708Y-271800D01*
X596621Y-271760D01*
X596581Y-271738D01*
X596548Y-271716D01*
X596515Y-271698D01*
X596486Y-271676D01*
X596464Y-271658D01*
X596446Y-271640D01*
X596431Y-271625D01*
X596417Y-271618D01*
X596413Y-271611D01*
X596410Y-271607D01*
X596377Y-271564D01*
X596348Y-271520D01*
X596322Y-271473D01*
X596300Y-271425D01*
X596268Y-271334D01*
X596246Y-271243D01*
X596235Y-271203D01*
X596231Y-271163D01*
X596228Y-271130D01*
X596224Y-271101D01*
X596220Y-271076D01*
Y-271043D01*
X596224Y-270967D01*
X596235Y-270894D01*
X596249Y-270825D01*
X596268Y-270763D01*
X596293Y-270705D01*
X596318Y-270650D01*
X596344Y-270599D01*
X596373Y-270555D01*
X596402Y-270515D01*
X596428Y-270479D01*
X596457Y-270450D01*
X596479Y-270424D01*
X596497Y-270406D01*
X596511Y-270392D01*
X596522Y-270384D01*
X596526Y-270381D01*
X596573Y-270344D01*
X596624Y-270315D01*
X596672Y-270286D01*
X596723Y-270264D01*
X596821Y-270228D01*
X596915Y-270206D01*
X596955Y-270199D01*
X596996Y-270191D01*
X597028Y-270188D01*
X597057Y-270184D01*
X597083Y-270180D01*
X597101D01*
X597112D01*
X597116D01*
X597181Y-270184D01*
D02*
G37*
G36*
X598794Y-272845D02*
X598732Y-272881D01*
X598674Y-272921D01*
X598615Y-272969D01*
X598564Y-273012D01*
X598521Y-273056D01*
X598484Y-273089D01*
X598473Y-273103D01*
X598462Y-273114D01*
X598459Y-273118D01*
X598455Y-273122D01*
X598393Y-273198D01*
X598335Y-273274D01*
X598284Y-273347D01*
X598244Y-273420D01*
X598208Y-273482D01*
X598193Y-273507D01*
X598182Y-273529D01*
X598171Y-273547D01*
X598168Y-273562D01*
X598160Y-273569D01*
Y-273573D01*
X597862D01*
X597884Y-273518D01*
X597909Y-273464D01*
X597935Y-273409D01*
X597960Y-273358D01*
X597982Y-273314D01*
X598000Y-273278D01*
X598015Y-273256D01*
X598018Y-273253D01*
Y-273249D01*
X598058Y-273183D01*
X598099Y-273125D01*
X598135Y-273074D01*
X598168Y-273034D01*
X598193Y-272998D01*
X598215Y-272976D01*
X598230Y-272958D01*
X598233Y-272954D01*
X596264D01*
Y-272645D01*
X598794D01*
Y-272845D01*
D02*
G37*
G36*
Y-274803D02*
X598732Y-274840D01*
X598674Y-274880D01*
X598615Y-274927D01*
X598564Y-274971D01*
X598521Y-275014D01*
X598484Y-275047D01*
X598473Y-275062D01*
X598462Y-275073D01*
X598459Y-275076D01*
X598455Y-275080D01*
X598393Y-275156D01*
X598335Y-275233D01*
X598284Y-275306D01*
X598244Y-275378D01*
X598208Y-275440D01*
X598193Y-275466D01*
X598182Y-275487D01*
X598171Y-275506D01*
X598168Y-275520D01*
X598160Y-275528D01*
Y-275531D01*
X597862D01*
X597884Y-275477D01*
X597909Y-275422D01*
X597935Y-275367D01*
X597960Y-275316D01*
X597982Y-275273D01*
X598000Y-275236D01*
X598015Y-275215D01*
X598018Y-275211D01*
Y-275207D01*
X598058Y-275142D01*
X598099Y-275083D01*
X598135Y-275032D01*
X598168Y-274992D01*
X598193Y-274956D01*
X598215Y-274934D01*
X598230Y-274916D01*
X598233Y-274912D01*
X596264D01*
Y-274603D01*
X598794D01*
Y-274803D01*
D02*
G37*
G36*
X597145Y-276387D02*
X597086Y-276401D01*
X597032Y-276419D01*
X596981Y-276438D01*
X596934Y-276456D01*
X596890Y-276478D01*
X596854Y-276499D01*
X596817Y-276525D01*
X596784Y-276547D01*
X596755Y-276565D01*
X596734Y-276587D01*
X596712Y-276605D01*
X596693Y-276620D01*
X596683Y-276634D01*
X596672Y-276645D01*
X596668Y-276649D01*
X596664Y-276652D01*
X596635Y-276689D01*
X596613Y-276729D01*
X596573Y-276809D01*
X596544Y-276885D01*
X596526Y-276962D01*
X596511Y-277027D01*
X596508Y-277053D01*
Y-277078D01*
X596504Y-277100D01*
Y-277126D01*
X596508Y-277209D01*
X596522Y-277289D01*
X596540Y-277362D01*
X596562Y-277428D01*
X596584Y-277479D01*
X596595Y-277501D01*
X596602Y-277519D01*
X596610Y-277533D01*
X596617Y-277544D01*
X596621Y-277551D01*
Y-277555D01*
X596672Y-277624D01*
X596726Y-277682D01*
X596788Y-277733D01*
X596846Y-277773D01*
X596897Y-277806D01*
X596941Y-277828D01*
X596959Y-277835D01*
X596970Y-277843D01*
X596977Y-277846D01*
X596981D01*
X597076Y-277875D01*
X597170Y-277897D01*
X597265Y-277915D01*
X597352Y-277926D01*
X597392Y-277930D01*
X597429Y-277934D01*
X597462D01*
X597487Y-277937D01*
X597509D01*
X597527D01*
X597538D01*
X597542D01*
X597636Y-277934D01*
X597723Y-277926D01*
X597804Y-277912D01*
X597876Y-277897D01*
X597938Y-277886D01*
X597964Y-277879D01*
X597986Y-277872D01*
X598004Y-277868D01*
X598015Y-277864D01*
X598022Y-277861D01*
X598026D01*
X598109Y-277824D01*
X598186Y-277784D01*
X598248Y-277741D01*
X598302Y-277693D01*
X598346Y-277653D01*
X598375Y-277621D01*
X598393Y-277595D01*
X598401Y-277591D01*
Y-277588D01*
X598448Y-277511D01*
X598484Y-277428D01*
X598510Y-277348D01*
X598524Y-277271D01*
X598535Y-277202D01*
X598539Y-277173D01*
Y-277147D01*
X598543Y-277129D01*
Y-277100D01*
X598539Y-277009D01*
X598524Y-276925D01*
X598502Y-276856D01*
X598481Y-276794D01*
X598455Y-276747D01*
X598437Y-276711D01*
X598422Y-276689D01*
X598415Y-276681D01*
X598360Y-276623D01*
X598299Y-276569D01*
X598233Y-276525D01*
X598168Y-276488D01*
X598109Y-276459D01*
X598080Y-276448D01*
X598058Y-276441D01*
X598040Y-276434D01*
X598026Y-276427D01*
X598018Y-276423D01*
X598015D01*
X598091Y-276095D01*
X598157Y-276117D01*
X598215Y-276139D01*
X598270Y-276168D01*
X598324Y-276194D01*
X598372Y-276223D01*
X598415Y-276256D01*
X598459Y-276285D01*
X598495Y-276314D01*
X598524Y-276343D01*
X598554Y-276368D01*
X598579Y-276394D01*
X598597Y-276412D01*
X598615Y-276430D01*
X598626Y-276445D01*
X598630Y-276452D01*
X598634Y-276456D01*
X598666Y-276507D01*
X598699Y-276558D01*
X598725Y-276609D01*
X598746Y-276663D01*
X598779Y-276772D01*
X598801Y-276871D01*
X598812Y-276918D01*
X598815Y-276958D01*
X598819Y-276998D01*
X598823Y-277031D01*
X598827Y-277056D01*
Y-277093D01*
X598819Y-277213D01*
X598801Y-277329D01*
X598779Y-277431D01*
X598765Y-277479D01*
X598750Y-277522D01*
X598736Y-277562D01*
X598721Y-277599D01*
X598710Y-277628D01*
X598699Y-277657D01*
X598688Y-277675D01*
X598681Y-277690D01*
X598677Y-277701D01*
X598674Y-277704D01*
X598612Y-277803D01*
X598539Y-277886D01*
X598466Y-277959D01*
X598393Y-278021D01*
X598328Y-278068D01*
X598299Y-278086D01*
X598273Y-278101D01*
X598255Y-278116D01*
X598240Y-278123D01*
X598230Y-278127D01*
X598226Y-278130D01*
X598113Y-278181D01*
X597997Y-278218D01*
X597880Y-278243D01*
X597775Y-278261D01*
X597727Y-278269D01*
X597680Y-278272D01*
X597644Y-278276D01*
X597607D01*
X597582Y-278279D01*
X597560D01*
X597545D01*
X597542D01*
X597410Y-278272D01*
X597283Y-278258D01*
X597170Y-278239D01*
X597116Y-278225D01*
X597068Y-278214D01*
X597025Y-278203D01*
X596985Y-278188D01*
X596948Y-278177D01*
X596919Y-278170D01*
X596897Y-278159D01*
X596879Y-278156D01*
X596868Y-278148D01*
X596865D01*
X596755Y-278094D01*
X596657Y-278032D01*
X596573Y-277966D01*
X596540Y-277934D01*
X596508Y-277905D01*
X596479Y-277875D01*
X596453Y-277846D01*
X596431Y-277821D01*
X596417Y-277799D01*
X596402Y-277784D01*
X596391Y-277770D01*
X596388Y-277763D01*
X596384Y-277759D01*
X596355Y-277708D01*
X596329Y-277657D01*
X596289Y-277548D01*
X596260Y-277439D01*
X596242Y-277333D01*
X596235Y-277282D01*
X596228Y-277238D01*
X596224Y-277198D01*
Y-277166D01*
X596220Y-277136D01*
Y-277096D01*
X596224Y-277024D01*
X596231Y-276954D01*
X596238Y-276889D01*
X596253Y-276827D01*
X596271Y-276769D01*
X596289Y-276714D01*
X596308Y-276663D01*
X596329Y-276616D01*
X596348Y-276576D01*
X596366Y-276536D01*
X596384Y-276507D01*
X596402Y-276478D01*
X596417Y-276459D01*
X596424Y-276441D01*
X596431Y-276434D01*
X596435Y-276430D01*
X596479Y-276379D01*
X596522Y-276336D01*
X596573Y-276296D01*
X596624Y-276256D01*
X596726Y-276190D01*
X596828Y-276139D01*
X596875Y-276117D01*
X596919Y-276099D01*
X596959Y-276084D01*
X596992Y-276074D01*
X597021Y-276063D01*
X597043Y-276055D01*
X597057Y-276052D01*
X597061D01*
X597145Y-276387D01*
D02*
G37*
G36*
X476682Y-300394D02*
X476810Y-300409D01*
X476922Y-300427D01*
X476977Y-300442D01*
X477024Y-300452D01*
X477068Y-300463D01*
X477108Y-300478D01*
X477144Y-300489D01*
X477174Y-300496D01*
X477195Y-300507D01*
X477214Y-300511D01*
X477224Y-300518D01*
X477228D01*
X477337Y-300573D01*
X477436Y-300635D01*
X477519Y-300700D01*
X477552Y-300733D01*
X477585Y-300762D01*
X477614Y-300791D01*
X477639Y-300820D01*
X477661Y-300846D01*
X477676Y-300868D01*
X477690Y-300882D01*
X477701Y-300897D01*
X477705Y-300904D01*
X477709Y-300907D01*
X477738Y-300958D01*
X477763Y-301009D01*
X477803Y-301119D01*
X477832Y-301228D01*
X477851Y-301333D01*
X477858Y-301384D01*
X477865Y-301428D01*
X477869Y-301468D01*
Y-301501D01*
X477872Y-301530D01*
Y-301570D01*
X477869Y-301643D01*
X477861Y-301712D01*
X477854Y-301777D01*
X477840Y-301839D01*
X477821Y-301898D01*
X477803Y-301952D01*
X477785Y-302003D01*
X477763Y-302050D01*
X477745Y-302091D01*
X477727Y-302131D01*
X477709Y-302160D01*
X477690Y-302189D01*
X477676Y-302207D01*
X477669Y-302225D01*
X477661Y-302233D01*
X477658Y-302236D01*
X477614Y-302287D01*
X477570Y-302331D01*
X477519Y-302371D01*
X477468Y-302411D01*
X477366Y-302476D01*
X477264Y-302527D01*
X477217Y-302549D01*
X477174Y-302567D01*
X477134Y-302582D01*
X477101Y-302593D01*
X477072Y-302604D01*
X477050Y-302611D01*
X477035Y-302615D01*
X477032D01*
X476948Y-302280D01*
X477006Y-302265D01*
X477061Y-302247D01*
X477112Y-302229D01*
X477159Y-302211D01*
X477203Y-302189D01*
X477239Y-302167D01*
X477276Y-302141D01*
X477308Y-302120D01*
X477337Y-302101D01*
X477359Y-302080D01*
X477381Y-302061D01*
X477399Y-302047D01*
X477410Y-302032D01*
X477421Y-302021D01*
X477425Y-302018D01*
X477428Y-302014D01*
X477458Y-301978D01*
X477479Y-301938D01*
X477519Y-301857D01*
X477549Y-301781D01*
X477567Y-301705D01*
X477581Y-301639D01*
X477585Y-301614D01*
Y-301588D01*
X477589Y-301566D01*
Y-301541D01*
X477585Y-301457D01*
X477570Y-301377D01*
X477552Y-301304D01*
X477530Y-301239D01*
X477508Y-301188D01*
X477497Y-301166D01*
X477490Y-301148D01*
X477483Y-301133D01*
X477476Y-301122D01*
X477472Y-301115D01*
Y-301111D01*
X477421Y-301042D01*
X477366Y-300984D01*
X477305Y-300933D01*
X477246Y-300893D01*
X477195Y-300860D01*
X477152Y-300838D01*
X477134Y-300831D01*
X477123Y-300824D01*
X477115Y-300820D01*
X477112D01*
X477017Y-300791D01*
X476922Y-300769D01*
X476828Y-300751D01*
X476740Y-300740D01*
X476700Y-300736D01*
X476664Y-300733D01*
X476631D01*
X476606Y-300729D01*
X476584D01*
X476566D01*
X476555D01*
X476551D01*
X476456Y-300733D01*
X476369Y-300740D01*
X476289Y-300755D01*
X476216Y-300769D01*
X476154Y-300780D01*
X476129Y-300787D01*
X476107Y-300795D01*
X476089Y-300798D01*
X476078Y-300802D01*
X476071Y-300806D01*
X476067D01*
X475983Y-300842D01*
X475907Y-300882D01*
X475845Y-300926D01*
X475790Y-300973D01*
X475747Y-301013D01*
X475718Y-301046D01*
X475699Y-301071D01*
X475692Y-301075D01*
Y-301079D01*
X475645Y-301155D01*
X475608Y-301239D01*
X475583Y-301319D01*
X475568Y-301395D01*
X475557Y-301464D01*
X475554Y-301494D01*
Y-301519D01*
X475550Y-301537D01*
Y-301566D01*
X475554Y-301657D01*
X475568Y-301741D01*
X475590Y-301810D01*
X475612Y-301872D01*
X475637Y-301919D01*
X475656Y-301956D01*
X475670Y-301978D01*
X475677Y-301985D01*
X475732Y-302043D01*
X475794Y-302098D01*
X475859Y-302141D01*
X475925Y-302178D01*
X475983Y-302207D01*
X476012Y-302218D01*
X476034Y-302225D01*
X476052Y-302233D01*
X476067Y-302240D01*
X476074Y-302243D01*
X476078D01*
X476002Y-302571D01*
X475936Y-302549D01*
X475878Y-302527D01*
X475823Y-302498D01*
X475769Y-302473D01*
X475721Y-302444D01*
X475677Y-302411D01*
X475634Y-302382D01*
X475597Y-302353D01*
X475568Y-302324D01*
X475539Y-302298D01*
X475514Y-302273D01*
X475495Y-302254D01*
X475477Y-302236D01*
X475466Y-302221D01*
X475463Y-302214D01*
X475459Y-302211D01*
X475426Y-302160D01*
X475394Y-302109D01*
X475368Y-302058D01*
X475346Y-302003D01*
X475314Y-301894D01*
X475292Y-301796D01*
X475281Y-301748D01*
X475277Y-301708D01*
X475274Y-301668D01*
X475270Y-301636D01*
X475266Y-301610D01*
Y-301574D01*
X475274Y-301453D01*
X475292Y-301337D01*
X475314Y-301235D01*
X475328Y-301188D01*
X475343Y-301144D01*
X475357Y-301104D01*
X475372Y-301068D01*
X475383Y-301039D01*
X475394Y-301009D01*
X475405Y-300991D01*
X475412Y-300977D01*
X475415Y-300966D01*
X475419Y-300962D01*
X475481Y-300864D01*
X475554Y-300780D01*
X475627Y-300707D01*
X475699Y-300645D01*
X475765Y-300598D01*
X475794Y-300580D01*
X475819Y-300565D01*
X475838Y-300551D01*
X475852Y-300543D01*
X475863Y-300540D01*
X475867Y-300536D01*
X475980Y-300485D01*
X476096Y-300449D01*
X476213Y-300423D01*
X476318Y-300405D01*
X476366Y-300398D01*
X476413Y-300394D01*
X476449Y-300391D01*
X476486D01*
X476511Y-300387D01*
X476533D01*
X476547D01*
X476551D01*
X476682Y-300394D01*
D02*
G37*
G36*
X476209Y-303190D02*
X476184Y-303244D01*
X476158Y-303299D01*
X476132Y-303350D01*
X476111Y-303394D01*
X476092Y-303430D01*
X476078Y-303452D01*
X476074Y-303455D01*
Y-303459D01*
X476034Y-303525D01*
X475994Y-303583D01*
X475958Y-303634D01*
X475925Y-303674D01*
X475900Y-303710D01*
X475878Y-303732D01*
X475863Y-303750D01*
X475859Y-303754D01*
X477829D01*
Y-304063D01*
X475299D01*
Y-303863D01*
X475361Y-303827D01*
X475419Y-303787D01*
X475477Y-303739D01*
X475528Y-303696D01*
X475572Y-303652D01*
X475608Y-303619D01*
X475619Y-303605D01*
X475630Y-303594D01*
X475634Y-303590D01*
X475637Y-303587D01*
X475699Y-303510D01*
X475758Y-303434D01*
X475809Y-303361D01*
X475849Y-303288D01*
X475885Y-303226D01*
X475900Y-303201D01*
X475911Y-303179D01*
X475921Y-303161D01*
X475925Y-303146D01*
X475932Y-303139D01*
Y-303135D01*
X476231D01*
X476209Y-303190D01*
D02*
G37*
G36*
X476715Y-304860D02*
X476835Y-304868D01*
X476944Y-304879D01*
X477046Y-304897D01*
X477141Y-304915D01*
X477224Y-304937D01*
X477301Y-304959D01*
X477366Y-304981D01*
X477425Y-305002D01*
X477476Y-305028D01*
X477519Y-305046D01*
X477552Y-305064D01*
X477581Y-305083D01*
X477599Y-305094D01*
X477610Y-305101D01*
X477614Y-305104D01*
X477658Y-305145D01*
X477698Y-305188D01*
X477734Y-305235D01*
X477763Y-305283D01*
X477789Y-305330D01*
X477810Y-305377D01*
X477825Y-305425D01*
X477840Y-305468D01*
X477851Y-305512D01*
X477858Y-305552D01*
X477865Y-305589D01*
X477869Y-305618D01*
X477872Y-305643D01*
Y-305679D01*
X477865Y-305778D01*
X477851Y-305869D01*
X477825Y-305945D01*
X477800Y-306011D01*
X477774Y-306065D01*
X477760Y-306084D01*
X477749Y-306102D01*
X477741Y-306116D01*
X477734Y-306127D01*
X477727Y-306131D01*
Y-306135D01*
X477665Y-306200D01*
X477599Y-306255D01*
X477527Y-306302D01*
X477461Y-306338D01*
X477399Y-306367D01*
X477374Y-306382D01*
X477348Y-306389D01*
X477330Y-306397D01*
X477316Y-306404D01*
X477308Y-306407D01*
X477305D01*
X477250Y-306426D01*
X477195Y-306440D01*
X477079Y-306462D01*
X476959Y-306480D01*
X476842Y-306491D01*
X476791Y-306495D01*
X476744Y-306499D01*
X476700D01*
X476660Y-306502D01*
X476631D01*
X476606D01*
X476591D01*
X476587D01*
X476518D01*
X476453Y-306499D01*
X476395D01*
X476336Y-306495D01*
X476285Y-306488D01*
X476234Y-306484D01*
X476191Y-306480D01*
X476151Y-306473D01*
X476114Y-306469D01*
X476082Y-306462D01*
X476056Y-306458D01*
X476034Y-306455D01*
X476016Y-306451D01*
X476005Y-306448D01*
X475998Y-306444D01*
X475994D01*
X475914Y-306422D01*
X475841Y-306397D01*
X475779Y-306367D01*
X475725Y-306346D01*
X475677Y-306320D01*
X475645Y-306306D01*
X475627Y-306291D01*
X475619Y-306287D01*
X475565Y-306247D01*
X475517Y-306207D01*
X475477Y-306164D01*
X475441Y-306124D01*
X475415Y-306087D01*
X475397Y-306058D01*
X475386Y-306040D01*
X475383Y-306036D01*
Y-306033D01*
X475353Y-305974D01*
X475335Y-305912D01*
X475321Y-305854D01*
X475310Y-305800D01*
X475303Y-305752D01*
X475299Y-305712D01*
Y-305679D01*
X475306Y-305581D01*
X475321Y-305490D01*
X475346Y-305414D01*
X475372Y-305348D01*
X475401Y-305294D01*
X475412Y-305272D01*
X475426Y-305254D01*
X475434Y-305239D01*
X475441Y-305228D01*
X475448Y-305224D01*
Y-305221D01*
X475506Y-305155D01*
X475576Y-305101D01*
X475645Y-305053D01*
X475710Y-305017D01*
X475772Y-304988D01*
X475798Y-304973D01*
X475823Y-304966D01*
X475841Y-304959D01*
X475856Y-304952D01*
X475863Y-304948D01*
X475867D01*
X475921Y-304933D01*
X475976Y-304919D01*
X476096Y-304897D01*
X476216Y-304879D01*
X476329Y-304868D01*
X476384Y-304864D01*
X476431Y-304860D01*
X476475D01*
X476515Y-304857D01*
X476544D01*
X476569D01*
X476584D01*
X476587D01*
X476715Y-304860D01*
D02*
G37*
G36*
X477163Y-306815D02*
X477221Y-306822D01*
X477276Y-306833D01*
X477330Y-306848D01*
X477421Y-306884D01*
X477465Y-306903D01*
X477501Y-306924D01*
X477538Y-306946D01*
X477567Y-306964D01*
X477592Y-306986D01*
X477614Y-307001D01*
X477632Y-307015D01*
X477643Y-307026D01*
X477650Y-307034D01*
X477654Y-307037D01*
X477694Y-307081D01*
X477727Y-307128D01*
X477756Y-307179D01*
X477781Y-307230D01*
X477800Y-307277D01*
X477818Y-307329D01*
X477843Y-307427D01*
X477854Y-307470D01*
X477861Y-307510D01*
X477865Y-307547D01*
X477869Y-307580D01*
X477872Y-307605D01*
Y-307642D01*
X477869Y-307711D01*
X477861Y-307772D01*
X477851Y-307834D01*
X477840Y-307893D01*
X477821Y-307944D01*
X477803Y-307995D01*
X477785Y-308042D01*
X477763Y-308082D01*
X477741Y-308118D01*
X477723Y-308151D01*
X477705Y-308177D01*
X477687Y-308202D01*
X477676Y-308220D01*
X477665Y-308231D01*
X477658Y-308239D01*
X477654Y-308242D01*
X477610Y-308282D01*
X477567Y-308318D01*
X477523Y-308348D01*
X477476Y-308373D01*
X477432Y-308399D01*
X477385Y-308417D01*
X477301Y-308442D01*
X477261Y-308453D01*
X477224Y-308460D01*
X477192Y-308464D01*
X477166Y-308468D01*
X477144Y-308471D01*
X477126D01*
X477115D01*
X477112D01*
X477028Y-308468D01*
X476952Y-308453D01*
X476882Y-308431D01*
X476824Y-308410D01*
X476777Y-308388D01*
X476740Y-308366D01*
X476719Y-308351D01*
X476715Y-308348D01*
X476711D01*
X476653Y-308297D01*
X476602Y-308242D01*
X476562Y-308184D01*
X476526Y-308129D01*
X476500Y-308078D01*
X476482Y-308035D01*
X476475Y-308020D01*
X476471Y-308009D01*
X476467Y-308002D01*
Y-307998D01*
X476438Y-308064D01*
X476405Y-308118D01*
X476373Y-308166D01*
X476340Y-308206D01*
X476311Y-308235D01*
X476289Y-308257D01*
X476274Y-308271D01*
X476267Y-308275D01*
X476216Y-308308D01*
X476165Y-308329D01*
X476114Y-308348D01*
X476063Y-308359D01*
X476023Y-308366D01*
X475990Y-308369D01*
X475969D01*
X475965D01*
X475961D01*
X475911Y-308366D01*
X475863Y-308362D01*
X475772Y-308337D01*
X475692Y-308304D01*
X475623Y-308268D01*
X475568Y-308231D01*
X475547Y-308213D01*
X475525Y-308198D01*
X475510Y-308184D01*
X475499Y-308173D01*
X475495Y-308169D01*
X475492Y-308166D01*
X475459Y-308126D01*
X475426Y-308086D01*
X475401Y-308042D01*
X475379Y-307998D01*
X475346Y-307911D01*
X475324Y-307823D01*
X475314Y-307787D01*
X475310Y-307751D01*
X475306Y-307718D01*
X475303Y-307689D01*
X475299Y-307667D01*
Y-307634D01*
X475303Y-307576D01*
X475306Y-307518D01*
X475328Y-307416D01*
X475343Y-307368D01*
X475357Y-307325D01*
X475375Y-307285D01*
X475394Y-307248D01*
X475412Y-307219D01*
X475430Y-307190D01*
X475445Y-307165D01*
X475459Y-307147D01*
X475470Y-307132D01*
X475481Y-307121D01*
X475485Y-307114D01*
X475488Y-307110D01*
X475525Y-307077D01*
X475561Y-307045D01*
X475601Y-307019D01*
X475641Y-306997D01*
X475718Y-306961D01*
X475790Y-306939D01*
X475852Y-306924D01*
X475881Y-306921D01*
X475903Y-306917D01*
X475925Y-306913D01*
X475940D01*
X475947D01*
X475950D01*
X476016Y-306917D01*
X476078Y-306928D01*
X476132Y-306943D01*
X476180Y-306961D01*
X476216Y-306975D01*
X476245Y-306990D01*
X476260Y-307001D01*
X476267Y-307004D01*
X476311Y-307045D01*
X476351Y-307088D01*
X476387Y-307136D01*
X476416Y-307183D01*
X476438Y-307226D01*
X476453Y-307259D01*
X476460Y-307274D01*
X476464Y-307285D01*
X476467Y-307288D01*
Y-307292D01*
X476493Y-307208D01*
X476526Y-307139D01*
X476566Y-307077D01*
X476602Y-307026D01*
X476639Y-306986D01*
X476668Y-306957D01*
X476686Y-306943D01*
X476689Y-306935D01*
X476693D01*
X476759Y-306895D01*
X476828Y-306862D01*
X476893Y-306841D01*
X476959Y-306826D01*
X477017Y-306819D01*
X477042Y-306815D01*
X477064D01*
X477079Y-306812D01*
X477094D01*
X477101D01*
X477104D01*
X477163Y-306815D01*
D02*
G37*
G36*
X476875Y-263236D02*
X476915Y-263295D01*
X476963Y-263353D01*
X477006Y-263404D01*
X477050Y-263448D01*
X477083Y-263484D01*
X477097Y-263495D01*
X477108Y-263506D01*
X477112Y-263509D01*
X477115Y-263513D01*
X477192Y-263575D01*
X477268Y-263633D01*
X477341Y-263684D01*
X477414Y-263724D01*
X477476Y-263761D01*
X477501Y-263775D01*
X477523Y-263786D01*
X477541Y-263797D01*
X477556Y-263801D01*
X477563Y-263808D01*
X477567D01*
Y-264106D01*
X477512Y-264085D01*
X477458Y-264059D01*
X477403Y-264034D01*
X477352Y-264008D01*
X477308Y-263986D01*
X477272Y-263968D01*
X477250Y-263954D01*
X477247Y-263950D01*
X477243D01*
X477177Y-263910D01*
X477119Y-263870D01*
X477068Y-263833D01*
X477028Y-263801D01*
X476992Y-263775D01*
X476970Y-263753D01*
X476952Y-263739D01*
X476948Y-263735D01*
Y-265704D01*
X476639D01*
Y-263175D01*
X476839D01*
X476875Y-263236D01*
D02*
G37*
G36*
X473068Y-263178D02*
X473137Y-263186D01*
X473203Y-263200D01*
X473264Y-263218D01*
X473319Y-263244D01*
X473374Y-263266D01*
X473421Y-263295D01*
X473464Y-263320D01*
X473501Y-263346D01*
X473537Y-263375D01*
X473566Y-263397D01*
X473588Y-263419D01*
X473606Y-263440D01*
X473621Y-263455D01*
X473628Y-263462D01*
X473632Y-263466D01*
X473679Y-263531D01*
X473719Y-263608D01*
X473756Y-263688D01*
X473788Y-263772D01*
X473814Y-263859D01*
X473836Y-263946D01*
X473854Y-264037D01*
X473869Y-264121D01*
X473879Y-264205D01*
X473887Y-264281D01*
X473894Y-264350D01*
X473898Y-264409D01*
Y-264459D01*
X473901Y-264496D01*
Y-264510D01*
Y-264521D01*
Y-264525D01*
Y-264529D01*
X473898Y-264645D01*
X473890Y-264754D01*
X473879Y-264856D01*
X473861Y-264951D01*
X473843Y-265035D01*
X473825Y-265111D01*
X473803Y-265180D01*
X473778Y-265242D01*
X473756Y-265293D01*
X473734Y-265340D01*
X473716Y-265377D01*
X473694Y-265410D01*
X473679Y-265435D01*
X473668Y-265450D01*
X473661Y-265460D01*
X473657Y-265464D01*
X473610Y-265515D01*
X473559Y-265559D01*
X473508Y-265595D01*
X473457Y-265628D01*
X473403Y-265657D01*
X473352Y-265679D01*
X473301Y-265697D01*
X473250Y-265712D01*
X473206Y-265723D01*
X473162Y-265734D01*
X473126Y-265741D01*
X473093Y-265744D01*
X473064D01*
X473046Y-265748D01*
X473028D01*
X472944Y-265744D01*
X472868Y-265730D01*
X472798Y-265715D01*
X472737Y-265693D01*
X472689Y-265675D01*
X472653Y-265657D01*
X472638Y-265653D01*
X472627Y-265646D01*
X472624Y-265642D01*
X472620D01*
X472558Y-265599D01*
X472500Y-265548D01*
X472453Y-265497D01*
X472413Y-265446D01*
X472380Y-265399D01*
X472358Y-265362D01*
X472351Y-265348D01*
X472343Y-265337D01*
X472340Y-265333D01*
Y-265330D01*
X472303Y-265253D01*
X472278Y-265173D01*
X472260Y-265100D01*
X472249Y-265031D01*
X472238Y-264973D01*
Y-264951D01*
X472234Y-264929D01*
Y-264911D01*
Y-264900D01*
Y-264893D01*
Y-264889D01*
X472238Y-264824D01*
X472245Y-264762D01*
X472256Y-264700D01*
X472267Y-264645D01*
X472285Y-264594D01*
X472303Y-264543D01*
X472322Y-264500D01*
X472343Y-264459D01*
X472365Y-264423D01*
X472383Y-264390D01*
X472402Y-264365D01*
X472420Y-264339D01*
X472431Y-264321D01*
X472442Y-264310D01*
X472449Y-264303D01*
X472453Y-264299D01*
X472493Y-264259D01*
X472536Y-264223D01*
X472584Y-264194D01*
X472627Y-264168D01*
X472671Y-264143D01*
X472715Y-264125D01*
X472798Y-264099D01*
X472835Y-264088D01*
X472871Y-264081D01*
X472900Y-264077D01*
X472929Y-264074D01*
X472951Y-264070D01*
X472980D01*
X473046Y-264074D01*
X473108Y-264085D01*
X473166Y-264095D01*
X473217Y-264110D01*
X473261Y-264128D01*
X473293Y-264139D01*
X473315Y-264150D01*
X473319Y-264154D01*
X473323D01*
X473381Y-264190D01*
X473432Y-264230D01*
X473479Y-264270D01*
X473516Y-264314D01*
X473548Y-264350D01*
X473574Y-264379D01*
X473588Y-264401D01*
X473592Y-264405D01*
Y-264339D01*
X473588Y-264274D01*
X473585Y-264216D01*
X473577Y-264157D01*
X473574Y-264106D01*
X473566Y-264059D01*
X473559Y-264015D01*
X473548Y-263975D01*
X473541Y-263939D01*
X473534Y-263910D01*
X473526Y-263884D01*
X473523Y-263863D01*
X473516Y-263848D01*
X473512Y-263837D01*
X473508Y-263830D01*
Y-263826D01*
X473472Y-263753D01*
X473435Y-263688D01*
X473395Y-263637D01*
X473359Y-263593D01*
X473326Y-263557D01*
X473301Y-263531D01*
X473282Y-263517D01*
X473275Y-263513D01*
X473232Y-263484D01*
X473188Y-263466D01*
X473144Y-263451D01*
X473101Y-263440D01*
X473068Y-263433D01*
X473039Y-263429D01*
X473013D01*
X472948Y-263437D01*
X472886Y-263451D01*
X472835Y-263473D01*
X472788Y-263495D01*
X472751Y-263520D01*
X472726Y-263542D01*
X472711Y-263557D01*
X472704Y-263564D01*
X472678Y-263597D01*
X472653Y-263637D01*
X472631Y-263681D01*
X472616Y-263724D01*
X472602Y-263764D01*
X472591Y-263797D01*
X472587Y-263819D01*
X472584Y-263823D01*
Y-263826D01*
X472274Y-263801D01*
X472296Y-263699D01*
X472329Y-263608D01*
X472365Y-263528D01*
X472405Y-263462D01*
X472445Y-263411D01*
X472460Y-263389D01*
X472478Y-263371D01*
X472489Y-263360D01*
X472500Y-263349D01*
X472504Y-263346D01*
X472507Y-263342D01*
X472544Y-263313D01*
X472584Y-263287D01*
X472664Y-263244D01*
X472744Y-263215D01*
X472820Y-263196D01*
X472889Y-263182D01*
X472919Y-263178D01*
X472944D01*
X472966Y-263175D01*
X472995D01*
X473068Y-263178D01*
D02*
G37*
G36*
X479249Y-263149D02*
X479365Y-263167D01*
X479467Y-263189D01*
X479514Y-263204D01*
X479558Y-263218D01*
X479598Y-263233D01*
X479634Y-263247D01*
X479664Y-263258D01*
X479693Y-263269D01*
X479711Y-263280D01*
X479725Y-263287D01*
X479736Y-263291D01*
X479740Y-263295D01*
X479838Y-263357D01*
X479922Y-263429D01*
X479995Y-263502D01*
X480057Y-263575D01*
X480104Y-263640D01*
X480122Y-263670D01*
X480137Y-263695D01*
X480151Y-263713D01*
X480159Y-263728D01*
X480162Y-263739D01*
X480166Y-263742D01*
X480217Y-263855D01*
X480253Y-263972D01*
X480279Y-264088D01*
X480297Y-264194D01*
X480304Y-264241D01*
X480308Y-264288D01*
X480311Y-264325D01*
Y-264361D01*
X480315Y-264387D01*
Y-264409D01*
Y-264423D01*
Y-264427D01*
X480308Y-264558D01*
X480293Y-264685D01*
X480275Y-264798D01*
X480260Y-264853D01*
X480250Y-264900D01*
X480239Y-264944D01*
X480224Y-264984D01*
X480213Y-265020D01*
X480206Y-265049D01*
X480195Y-265071D01*
X480191Y-265089D01*
X480184Y-265100D01*
Y-265104D01*
X480129Y-265213D01*
X480067Y-265311D01*
X480002Y-265395D01*
X479969Y-265428D01*
X479940Y-265460D01*
X479911Y-265490D01*
X479882Y-265515D01*
X479856Y-265537D01*
X479835Y-265551D01*
X479820Y-265566D01*
X479805Y-265577D01*
X479798Y-265581D01*
X479795Y-265584D01*
X479743Y-265613D01*
X479693Y-265639D01*
X479583Y-265679D01*
X479474Y-265708D01*
X479369Y-265726D01*
X479318Y-265734D01*
X479274Y-265741D01*
X479234Y-265744D01*
X479201D01*
X479172Y-265748D01*
X479132D01*
X479059Y-265744D01*
X478990Y-265737D01*
X478925Y-265730D01*
X478863Y-265715D01*
X478804Y-265697D01*
X478750Y-265679D01*
X478699Y-265661D01*
X478652Y-265639D01*
X478612Y-265621D01*
X478572Y-265602D01*
X478542Y-265584D01*
X478513Y-265566D01*
X478495Y-265551D01*
X478477Y-265544D01*
X478470Y-265537D01*
X478466Y-265533D01*
X478415Y-265490D01*
X478371Y-265446D01*
X478331Y-265395D01*
X478291Y-265344D01*
X478226Y-265242D01*
X478175Y-265140D01*
X478153Y-265093D01*
X478135Y-265049D01*
X478120Y-265009D01*
X478109Y-264976D01*
X478098Y-264947D01*
X478091Y-264925D01*
X478087Y-264911D01*
Y-264907D01*
X478422Y-264824D01*
X478437Y-264882D01*
X478455Y-264936D01*
X478473Y-264987D01*
X478491Y-265035D01*
X478513Y-265078D01*
X478535Y-265115D01*
X478560Y-265151D01*
X478582Y-265184D01*
X478601Y-265213D01*
X478622Y-265235D01*
X478641Y-265257D01*
X478655Y-265275D01*
X478670Y-265286D01*
X478681Y-265297D01*
X478684Y-265300D01*
X478688Y-265304D01*
X478724Y-265333D01*
X478764Y-265355D01*
X478844Y-265395D01*
X478921Y-265424D01*
X478997Y-265442D01*
X479063Y-265457D01*
X479088Y-265460D01*
X479114D01*
X479136Y-265464D01*
X479161D01*
X479245Y-265460D01*
X479325Y-265446D01*
X479398Y-265428D01*
X479463Y-265406D01*
X479514Y-265384D01*
X479536Y-265373D01*
X479554Y-265366D01*
X479569Y-265359D01*
X479580Y-265351D01*
X479587Y-265348D01*
X479591D01*
X479660Y-265297D01*
X479718Y-265242D01*
X479769Y-265180D01*
X479809Y-265122D01*
X479842Y-265071D01*
X479864Y-265027D01*
X479871Y-265009D01*
X479878Y-264998D01*
X479882Y-264991D01*
Y-264987D01*
X479911Y-264893D01*
X479933Y-264798D01*
X479951Y-264703D01*
X479962Y-264616D01*
X479966Y-264576D01*
X479969Y-264540D01*
Y-264507D01*
X479973Y-264481D01*
Y-264459D01*
Y-264441D01*
Y-264430D01*
Y-264427D01*
X479969Y-264332D01*
X479962Y-264245D01*
X479947Y-264165D01*
X479933Y-264092D01*
X479922Y-264030D01*
X479915Y-264004D01*
X479907Y-263983D01*
X479904Y-263965D01*
X479900Y-263954D01*
X479896Y-263946D01*
Y-263943D01*
X479860Y-263859D01*
X479820Y-263783D01*
X479776Y-263721D01*
X479729Y-263666D01*
X479689Y-263622D01*
X479656Y-263593D01*
X479631Y-263575D01*
X479627Y-263568D01*
X479623D01*
X479547Y-263520D01*
X479463Y-263484D01*
X479383Y-263458D01*
X479307Y-263444D01*
X479238Y-263433D01*
X479208Y-263429D01*
X479183D01*
X479165Y-263426D01*
X479136D01*
X479045Y-263429D01*
X478961Y-263444D01*
X478892Y-263466D01*
X478830Y-263488D01*
X478783Y-263513D01*
X478746Y-263531D01*
X478724Y-263546D01*
X478717Y-263553D01*
X478659Y-263608D01*
X478604Y-263670D01*
X478560Y-263735D01*
X478524Y-263801D01*
X478495Y-263859D01*
X478484Y-263888D01*
X478477Y-263910D01*
X478470Y-263928D01*
X478462Y-263943D01*
X478459Y-263950D01*
Y-263954D01*
X478131Y-263877D01*
X478153Y-263812D01*
X478175Y-263753D01*
X478204Y-263699D01*
X478229Y-263644D01*
X478258Y-263597D01*
X478291Y-263553D01*
X478320Y-263509D01*
X478349Y-263473D01*
X478378Y-263444D01*
X478404Y-263415D01*
X478430Y-263389D01*
X478448Y-263371D01*
X478466Y-263353D01*
X478480Y-263342D01*
X478488Y-263338D01*
X478491Y-263335D01*
X478542Y-263302D01*
X478593Y-263269D01*
X478644Y-263244D01*
X478699Y-263222D01*
X478808Y-263189D01*
X478906Y-263167D01*
X478954Y-263156D01*
X478994Y-263153D01*
X479034Y-263149D01*
X479067Y-263145D01*
X479092Y-263142D01*
X479128D01*
X479249Y-263149D01*
D02*
G37*
G36*
X475121Y-263182D02*
X475212Y-263196D01*
X475288Y-263222D01*
X475354Y-263247D01*
X475408Y-263277D01*
X475430Y-263287D01*
X475448Y-263302D01*
X475463Y-263309D01*
X475474Y-263317D01*
X475478Y-263324D01*
X475481D01*
X475547Y-263382D01*
X475601Y-263451D01*
X475648Y-263520D01*
X475685Y-263586D01*
X475714Y-263648D01*
X475729Y-263673D01*
X475736Y-263699D01*
X475743Y-263717D01*
X475750Y-263732D01*
X475754Y-263739D01*
Y-263742D01*
X475769Y-263797D01*
X475783Y-263852D01*
X475805Y-263972D01*
X475823Y-264092D01*
X475834Y-264205D01*
X475838Y-264259D01*
X475841Y-264307D01*
Y-264350D01*
X475845Y-264390D01*
Y-264420D01*
Y-264445D01*
Y-264459D01*
Y-264463D01*
X475841Y-264591D01*
X475834Y-264711D01*
X475823Y-264820D01*
X475805Y-264922D01*
X475787Y-265016D01*
X475765Y-265100D01*
X475743Y-265177D01*
X475721Y-265242D01*
X475700Y-265300D01*
X475674Y-265351D01*
X475656Y-265395D01*
X475638Y-265428D01*
X475619Y-265457D01*
X475608Y-265475D01*
X475601Y-265486D01*
X475598Y-265490D01*
X475558Y-265533D01*
X475514Y-265573D01*
X475466Y-265610D01*
X475419Y-265639D01*
X475372Y-265664D01*
X475325Y-265686D01*
X475277Y-265701D01*
X475234Y-265715D01*
X475190Y-265726D01*
X475150Y-265734D01*
X475113Y-265741D01*
X475084Y-265744D01*
X475059Y-265748D01*
X475023D01*
X474924Y-265741D01*
X474833Y-265726D01*
X474757Y-265701D01*
X474691Y-265675D01*
X474637Y-265650D01*
X474618Y-265635D01*
X474600Y-265624D01*
X474586Y-265617D01*
X474575Y-265610D01*
X474571Y-265602D01*
X474568D01*
X474502Y-265541D01*
X474447Y-265475D01*
X474400Y-265402D01*
X474364Y-265337D01*
X474334Y-265275D01*
X474320Y-265249D01*
X474313Y-265224D01*
X474305Y-265206D01*
X474298Y-265191D01*
X474294Y-265184D01*
Y-265180D01*
X474276Y-265126D01*
X474262Y-265071D01*
X474240Y-264955D01*
X474222Y-264834D01*
X474211Y-264718D01*
X474207Y-264667D01*
X474203Y-264620D01*
Y-264576D01*
X474200Y-264536D01*
Y-264507D01*
Y-264481D01*
Y-264467D01*
Y-264463D01*
Y-264394D01*
X474203Y-264329D01*
Y-264270D01*
X474207Y-264212D01*
X474214Y-264161D01*
X474218Y-264110D01*
X474222Y-264066D01*
X474229Y-264026D01*
X474233Y-263990D01*
X474240Y-263957D01*
X474243Y-263932D01*
X474247Y-263910D01*
X474251Y-263892D01*
X474254Y-263881D01*
X474258Y-263874D01*
Y-263870D01*
X474280Y-263790D01*
X474305Y-263717D01*
X474334Y-263655D01*
X474356Y-263600D01*
X474382Y-263553D01*
X474396Y-263520D01*
X474411Y-263502D01*
X474415Y-263495D01*
X474455Y-263440D01*
X474495Y-263393D01*
X474538Y-263353D01*
X474578Y-263317D01*
X474615Y-263291D01*
X474644Y-263273D01*
X474662Y-263262D01*
X474666Y-263258D01*
X474669D01*
X474728Y-263229D01*
X474789Y-263211D01*
X474848Y-263196D01*
X474902Y-263186D01*
X474950Y-263178D01*
X474990Y-263175D01*
X475023D01*
X475121Y-263182D01*
D02*
G37*
G36*
X188574Y-94495D02*
X188701Y-94510D01*
X188814Y-94528D01*
X188868Y-94543D01*
X188916Y-94554D01*
X188959Y-94565D01*
X188999Y-94579D01*
X189036Y-94590D01*
X189065Y-94597D01*
X189087Y-94608D01*
X189105Y-94612D01*
X189116Y-94619D01*
X189120D01*
X189229Y-94674D01*
X189327Y-94736D01*
X189411Y-94801D01*
X189444Y-94834D01*
X189476Y-94863D01*
X189505Y-94892D01*
X189531Y-94921D01*
X189553Y-94947D01*
X189567Y-94969D01*
X189582Y-94983D01*
X189593Y-94998D01*
X189596Y-95005D01*
X189600Y-95009D01*
X189629Y-95060D01*
X189655Y-95111D01*
X189695Y-95220D01*
X189724Y-95329D01*
X189742Y-95434D01*
X189749Y-95486D01*
X189757Y-95529D01*
X189760Y-95569D01*
Y-95602D01*
X189764Y-95631D01*
Y-95671D01*
X189760Y-95744D01*
X189753Y-95813D01*
X189746Y-95879D01*
X189731Y-95941D01*
X189713Y-95999D01*
X189695Y-96053D01*
X189676Y-96104D01*
X189655Y-96152D01*
X189636Y-96192D01*
X189618Y-96232D01*
X189600Y-96261D01*
X189582Y-96290D01*
X189567Y-96308D01*
X189560Y-96326D01*
X189553Y-96334D01*
X189549Y-96337D01*
X189505Y-96388D01*
X189462Y-96432D01*
X189411Y-96472D01*
X189360Y-96512D01*
X189258Y-96578D01*
X189156Y-96628D01*
X189109Y-96650D01*
X189065Y-96668D01*
X189025Y-96683D01*
X188992Y-96694D01*
X188963Y-96705D01*
X188941Y-96712D01*
X188927Y-96716D01*
X188923D01*
X188839Y-96381D01*
X188898Y-96366D01*
X188952Y-96348D01*
X189003Y-96330D01*
X189050Y-96312D01*
X189094Y-96290D01*
X189130Y-96268D01*
X189167Y-96243D01*
X189200Y-96221D01*
X189229Y-96203D01*
X189251Y-96181D01*
X189272Y-96162D01*
X189291Y-96148D01*
X189302Y-96133D01*
X189313Y-96122D01*
X189316Y-96119D01*
X189320Y-96115D01*
X189349Y-96079D01*
X189371Y-96039D01*
X189411Y-95959D01*
X189440Y-95882D01*
X189458Y-95806D01*
X189473Y-95740D01*
X189476Y-95715D01*
Y-95689D01*
X189480Y-95667D01*
Y-95642D01*
X189476Y-95558D01*
X189462Y-95478D01*
X189444Y-95405D01*
X189422Y-95340D01*
X189400Y-95289D01*
X189389Y-95267D01*
X189382Y-95249D01*
X189374Y-95234D01*
X189367Y-95223D01*
X189363Y-95216D01*
Y-95213D01*
X189313Y-95143D01*
X189258Y-95085D01*
X189196Y-95034D01*
X189138Y-94994D01*
X189087Y-94961D01*
X189043Y-94940D01*
X189025Y-94932D01*
X189014Y-94925D01*
X189007Y-94921D01*
X189003D01*
X188908Y-94892D01*
X188814Y-94870D01*
X188719Y-94852D01*
X188632Y-94841D01*
X188592Y-94838D01*
X188555Y-94834D01*
X188523D01*
X188497Y-94830D01*
X188475D01*
X188457D01*
X188446D01*
X188443D01*
X188348Y-94834D01*
X188260Y-94841D01*
X188180Y-94856D01*
X188108Y-94870D01*
X188046Y-94881D01*
X188020Y-94889D01*
X187998Y-94896D01*
X187980Y-94899D01*
X187969Y-94903D01*
X187962Y-94907D01*
X187958D01*
X187875Y-94943D01*
X187798Y-94983D01*
X187736Y-95027D01*
X187682Y-95074D01*
X187638Y-95114D01*
X187609Y-95147D01*
X187591Y-95173D01*
X187583Y-95176D01*
Y-95180D01*
X187536Y-95256D01*
X187500Y-95340D01*
X187474Y-95420D01*
X187460Y-95496D01*
X187449Y-95566D01*
X187445Y-95595D01*
Y-95620D01*
X187442Y-95638D01*
Y-95667D01*
X187445Y-95758D01*
X187460Y-95842D01*
X187481Y-95911D01*
X187503Y-95973D01*
X187529Y-96021D01*
X187547Y-96057D01*
X187562Y-96079D01*
X187569Y-96086D01*
X187624Y-96144D01*
X187685Y-96199D01*
X187751Y-96243D01*
X187816Y-96279D01*
X187875Y-96308D01*
X187904Y-96319D01*
X187926Y-96326D01*
X187944Y-96334D01*
X187958Y-96341D01*
X187966Y-96345D01*
X187969D01*
X187893Y-96672D01*
X187827Y-96650D01*
X187769Y-96628D01*
X187715Y-96599D01*
X187660Y-96574D01*
X187613Y-96545D01*
X187569Y-96512D01*
X187525Y-96483D01*
X187489Y-96454D01*
X187460Y-96425D01*
X187431Y-96399D01*
X187405Y-96374D01*
X187387Y-96355D01*
X187369Y-96337D01*
X187358Y-96323D01*
X187354Y-96315D01*
X187350Y-96312D01*
X187318Y-96261D01*
X187285Y-96210D01*
X187259Y-96159D01*
X187238Y-96104D01*
X187205Y-95995D01*
X187183Y-95897D01*
X187172Y-95850D01*
X187169Y-95810D01*
X187165Y-95769D01*
X187161Y-95737D01*
X187158Y-95711D01*
Y-95675D01*
X187165Y-95555D01*
X187183Y-95438D01*
X187205Y-95336D01*
X187220Y-95289D01*
X187234Y-95245D01*
X187249Y-95205D01*
X187263Y-95169D01*
X187274Y-95140D01*
X187285Y-95111D01*
X187296Y-95092D01*
X187303Y-95078D01*
X187307Y-95067D01*
X187311Y-95063D01*
X187372Y-94965D01*
X187445Y-94881D01*
X187518Y-94809D01*
X187591Y-94747D01*
X187656Y-94699D01*
X187685Y-94681D01*
X187711Y-94666D01*
X187729Y-94652D01*
X187744Y-94645D01*
X187754Y-94641D01*
X187758Y-94637D01*
X187871Y-94586D01*
X187987Y-94550D01*
X188104Y-94525D01*
X188209Y-94506D01*
X188257Y-94499D01*
X188304Y-94495D01*
X188341Y-94492D01*
X188377D01*
X188402Y-94488D01*
X188424D01*
X188439D01*
X188443D01*
X188574Y-94495D01*
D02*
G37*
G36*
X188100Y-97291D02*
X188075Y-97346D01*
X188049Y-97400D01*
X188024Y-97451D01*
X188002Y-97495D01*
X187984Y-97531D01*
X187969Y-97553D01*
X187966Y-97557D01*
Y-97560D01*
X187926Y-97626D01*
X187886Y-97684D01*
X187849Y-97735D01*
X187816Y-97775D01*
X187791Y-97812D01*
X187769Y-97833D01*
X187754Y-97852D01*
X187751Y-97855D01*
X189720D01*
Y-98164D01*
X187190D01*
Y-97964D01*
X187252Y-97928D01*
X187311Y-97888D01*
X187369Y-97841D01*
X187420Y-97797D01*
X187463Y-97753D01*
X187500Y-97720D01*
X187511Y-97706D01*
X187522Y-97695D01*
X187525Y-97691D01*
X187529Y-97688D01*
X187591Y-97611D01*
X187649Y-97535D01*
X187700Y-97462D01*
X187740Y-97389D01*
X187776Y-97327D01*
X187791Y-97302D01*
X187802Y-97280D01*
X187813Y-97262D01*
X187816Y-97247D01*
X187824Y-97240D01*
Y-97236D01*
X188122D01*
X188100Y-97291D01*
D02*
G37*
G36*
X188606Y-98962D02*
X188726Y-98969D01*
X188836Y-98980D01*
X188938Y-98998D01*
X189032Y-99016D01*
X189116Y-99038D01*
X189192Y-99060D01*
X189258Y-99082D01*
X189316Y-99104D01*
X189367Y-99129D01*
X189411Y-99147D01*
X189444Y-99165D01*
X189473Y-99184D01*
X189491Y-99195D01*
X189502Y-99202D01*
X189505Y-99206D01*
X189549Y-99246D01*
X189589Y-99289D01*
X189626Y-99337D01*
X189655Y-99384D01*
X189680Y-99431D01*
X189702Y-99479D01*
X189716Y-99526D01*
X189731Y-99570D01*
X189742Y-99613D01*
X189749Y-99653D01*
X189757Y-99690D01*
X189760Y-99719D01*
X189764Y-99744D01*
Y-99781D01*
X189757Y-99879D01*
X189742Y-99970D01*
X189716Y-100046D01*
X189691Y-100112D01*
X189666Y-100166D01*
X189651Y-100185D01*
X189640Y-100203D01*
X189633Y-100217D01*
X189626Y-100228D01*
X189618Y-100232D01*
Y-100236D01*
X189556Y-100301D01*
X189491Y-100356D01*
X189418Y-100403D01*
X189353Y-100440D01*
X189291Y-100469D01*
X189265Y-100483D01*
X189240Y-100490D01*
X189222Y-100498D01*
X189207Y-100505D01*
X189200Y-100509D01*
X189196D01*
X189141Y-100527D01*
X189087Y-100541D01*
X188970Y-100563D01*
X188850Y-100582D01*
X188734Y-100592D01*
X188683Y-100596D01*
X188635Y-100600D01*
X188592D01*
X188552Y-100603D01*
X188523D01*
X188497D01*
X188482D01*
X188479D01*
X188410D01*
X188344Y-100600D01*
X188286D01*
X188228Y-100596D01*
X188177Y-100589D01*
X188126Y-100585D01*
X188082Y-100582D01*
X188042Y-100574D01*
X188006Y-100571D01*
X187973Y-100563D01*
X187947Y-100560D01*
X187926Y-100556D01*
X187907Y-100552D01*
X187897Y-100549D01*
X187889Y-100545D01*
X187886D01*
X187805Y-100523D01*
X187733Y-100498D01*
X187671Y-100469D01*
X187616Y-100447D01*
X187569Y-100421D01*
X187536Y-100407D01*
X187518Y-100392D01*
X187511Y-100389D01*
X187456Y-100348D01*
X187409Y-100309D01*
X187369Y-100265D01*
X187332Y-100225D01*
X187307Y-100188D01*
X187289Y-100159D01*
X187278Y-100141D01*
X187274Y-100137D01*
Y-100134D01*
X187245Y-100075D01*
X187227Y-100014D01*
X187212Y-99955D01*
X187201Y-99901D01*
X187194Y-99853D01*
X187190Y-99813D01*
Y-99781D01*
X187198Y-99682D01*
X187212Y-99591D01*
X187238Y-99515D01*
X187263Y-99449D01*
X187292Y-99395D01*
X187303Y-99373D01*
X187318Y-99355D01*
X187325Y-99340D01*
X187332Y-99329D01*
X187340Y-99326D01*
Y-99322D01*
X187398Y-99256D01*
X187467Y-99202D01*
X187536Y-99155D01*
X187602Y-99118D01*
X187664Y-99089D01*
X187689Y-99075D01*
X187715Y-99067D01*
X187733Y-99060D01*
X187747Y-99053D01*
X187754Y-99049D01*
X187758D01*
X187813Y-99035D01*
X187867Y-99020D01*
X187987Y-98998D01*
X188108Y-98980D01*
X188221Y-98969D01*
X188275Y-98965D01*
X188322Y-98962D01*
X188366D01*
X188406Y-98958D01*
X188435D01*
X188461D01*
X188475D01*
X188479D01*
X188606Y-98962D01*
D02*
G37*
G36*
X187532Y-102172D02*
X187638Y-102085D01*
X187751Y-102001D01*
X187860Y-101928D01*
X187966Y-101859D01*
X188013Y-101830D01*
X188057Y-101804D01*
X188097Y-101779D01*
X188129Y-101761D01*
X188159Y-101746D01*
X188177Y-101735D01*
X188191Y-101728D01*
X188195Y-101725D01*
X188341Y-101652D01*
X188486Y-101586D01*
X188625Y-101532D01*
X188686Y-101510D01*
X188748Y-101488D01*
X188803Y-101466D01*
X188854Y-101452D01*
X188898Y-101437D01*
X188934Y-101426D01*
X188967Y-101415D01*
X188988Y-101408D01*
X189003Y-101404D01*
X189007D01*
X189156Y-101368D01*
X189229Y-101353D01*
X189294Y-101342D01*
X189356Y-101331D01*
X189418Y-101320D01*
X189469Y-101313D01*
X189520Y-101306D01*
X189564Y-101302D01*
X189604Y-101299D01*
X189640Y-101295D01*
X189669D01*
X189691Y-101291D01*
X189706D01*
X189716D01*
X189720D01*
Y-101608D01*
X189582Y-101619D01*
X189454Y-101637D01*
X189338Y-101655D01*
X189283Y-101666D01*
X189232Y-101677D01*
X189189Y-101684D01*
X189149Y-101695D01*
X189112Y-101703D01*
X189083Y-101710D01*
X189061Y-101717D01*
X189043Y-101721D01*
X189032Y-101725D01*
X189029D01*
X188861Y-101779D01*
X188705Y-101837D01*
X188628Y-101866D01*
X188555Y-101895D01*
X188490Y-101928D01*
X188424Y-101957D01*
X188366Y-101983D01*
X188315Y-102008D01*
X188271Y-102030D01*
X188231Y-102048D01*
X188199Y-102067D01*
X188177Y-102077D01*
X188162Y-102085D01*
X188159Y-102088D01*
X188082Y-102132D01*
X188006Y-102176D01*
X187937Y-102219D01*
X187871Y-102263D01*
X187813Y-102303D01*
X187754Y-102343D01*
X187704Y-102383D01*
X187660Y-102416D01*
X187616Y-102449D01*
X187580Y-102478D01*
X187551Y-102507D01*
X187525Y-102529D01*
X187503Y-102543D01*
X187489Y-102558D01*
X187481Y-102565D01*
X187478Y-102569D01*
X187234D01*
Y-100938D01*
X187532D01*
Y-102172D01*
D02*
G37*
G36*
X150560Y3937D02*
X150688Y3922D01*
X150801Y3904D01*
X150855Y3889D01*
X150902Y3878D01*
X150946Y3867D01*
X150986Y3853D01*
X151023Y3842D01*
X151052Y3835D01*
X151074Y3824D01*
X151092Y3820D01*
X151103Y3813D01*
X151106D01*
X151215Y3758D01*
X151314Y3696D01*
X151397Y3631D01*
X151430Y3598D01*
X151463Y3569D01*
X151492Y3540D01*
X151517Y3511D01*
X151539Y3485D01*
X151554Y3463D01*
X151568Y3449D01*
X151579Y3434D01*
X151583Y3427D01*
X151587Y3423D01*
X151616Y3372D01*
X151641Y3321D01*
X151681Y3212D01*
X151710Y3103D01*
X151729Y2997D01*
X151736Y2946D01*
X151743Y2903D01*
X151747Y2863D01*
Y2830D01*
X151751Y2801D01*
Y2761D01*
X151747Y2688D01*
X151740Y2619D01*
X151732Y2553D01*
X151718Y2491D01*
X151699Y2433D01*
X151681Y2379D01*
X151663Y2328D01*
X151641Y2280D01*
X151623Y2240D01*
X151605Y2200D01*
X151587Y2171D01*
X151568Y2142D01*
X151554Y2124D01*
X151547Y2105D01*
X151539Y2098D01*
X151536Y2095D01*
X151492Y2044D01*
X151448Y2000D01*
X151397Y1960D01*
X151347Y1920D01*
X151244Y1854D01*
X151143Y1803D01*
X151095Y1782D01*
X151052Y1763D01*
X151012Y1749D01*
X150979Y1738D01*
X150950Y1727D01*
X150928Y1720D01*
X150913Y1716D01*
X150910D01*
X150826Y2051D01*
X150884Y2066D01*
X150939Y2084D01*
X150990Y2102D01*
X151037Y2120D01*
X151081Y2142D01*
X151117Y2164D01*
X151154Y2189D01*
X151186Y2211D01*
X151215Y2229D01*
X151237Y2251D01*
X151259Y2269D01*
X151277Y2284D01*
X151288Y2299D01*
X151299Y2309D01*
X151303Y2313D01*
X151306Y2317D01*
X151336Y2353D01*
X151357Y2393D01*
X151397Y2473D01*
X151426Y2550D01*
X151445Y2626D01*
X151459Y2692D01*
X151463Y2717D01*
Y2743D01*
X151467Y2764D01*
Y2790D01*
X151463Y2874D01*
X151448Y2954D01*
X151430Y3026D01*
X151408Y3092D01*
X151386Y3143D01*
X151376Y3165D01*
X151368Y3183D01*
X151361Y3198D01*
X151354Y3209D01*
X151350Y3216D01*
Y3219D01*
X151299Y3289D01*
X151244Y3347D01*
X151183Y3398D01*
X151124Y3438D01*
X151074Y3471D01*
X151030Y3492D01*
X151012Y3500D01*
X151001Y3507D01*
X150993Y3511D01*
X150990D01*
X150895Y3540D01*
X150801Y3562D01*
X150706Y3580D01*
X150619Y3591D01*
X150578Y3594D01*
X150542Y3598D01*
X150509D01*
X150484Y3602D01*
X150462D01*
X150444D01*
X150433D01*
X150429D01*
X150335Y3598D01*
X150247Y3591D01*
X150167Y3576D01*
X150094Y3562D01*
X150032Y3551D01*
X150007Y3543D01*
X149985Y3536D01*
X149967Y3532D01*
X149956Y3529D01*
X149949Y3525D01*
X149945D01*
X149861Y3489D01*
X149785Y3449D01*
X149723Y3405D01*
X149668Y3358D01*
X149625Y3318D01*
X149596Y3285D01*
X149577Y3259D01*
X149570Y3256D01*
Y3252D01*
X149523Y3176D01*
X149486Y3092D01*
X149461Y3012D01*
X149446Y2936D01*
X149435Y2866D01*
X149432Y2837D01*
Y2812D01*
X149428Y2794D01*
Y2764D01*
X149432Y2673D01*
X149446Y2590D01*
X149468Y2520D01*
X149490Y2459D01*
X149515Y2411D01*
X149534Y2375D01*
X149548Y2353D01*
X149556Y2346D01*
X149610Y2287D01*
X149672Y2233D01*
X149738Y2189D01*
X149803Y2153D01*
X149861Y2124D01*
X149890Y2113D01*
X149912Y2105D01*
X149931Y2098D01*
X149945Y2091D01*
X149952Y2087D01*
X149956D01*
X149880Y1760D01*
X149814Y1782D01*
X149756Y1803D01*
X149701Y1833D01*
X149647Y1858D01*
X149599Y1887D01*
X149556Y1920D01*
X149512Y1949D01*
X149476Y1978D01*
X149446Y2007D01*
X149417Y2033D01*
X149392Y2058D01*
X149374Y2076D01*
X149355Y2095D01*
X149345Y2109D01*
X149341Y2117D01*
X149337Y2120D01*
X149304Y2171D01*
X149272Y2222D01*
X149246Y2273D01*
X149224Y2328D01*
X149192Y2437D01*
X149170Y2535D01*
X149159Y2582D01*
X149155Y2622D01*
X149152Y2662D01*
X149148Y2695D01*
X149144Y2721D01*
Y2757D01*
X149152Y2877D01*
X149170Y2994D01*
X149192Y3096D01*
X149206Y3143D01*
X149221Y3187D01*
X149235Y3227D01*
X149250Y3263D01*
X149261Y3292D01*
X149272Y3321D01*
X149283Y3339D01*
X149290Y3354D01*
X149293Y3365D01*
X149297Y3369D01*
X149359Y3467D01*
X149432Y3551D01*
X149505Y3623D01*
X149577Y3685D01*
X149643Y3733D01*
X149672Y3751D01*
X149697Y3765D01*
X149716Y3780D01*
X149730Y3787D01*
X149741Y3791D01*
X149745Y3794D01*
X149858Y3845D01*
X149974Y3882D01*
X150091Y3907D01*
X150196Y3926D01*
X150243Y3933D01*
X150291Y3937D01*
X150327Y3940D01*
X150364D01*
X150389Y3944D01*
X150411D01*
X150426D01*
X150429D01*
X150560Y3937D01*
D02*
G37*
G36*
X150087Y1141D02*
X150062Y1086D01*
X150036Y1032D01*
X150011Y981D01*
X149989Y937D01*
X149970Y901D01*
X149956Y879D01*
X149952Y875D01*
Y872D01*
X149912Y806D01*
X149872Y748D01*
X149836Y697D01*
X149803Y657D01*
X149778Y620D01*
X149756Y599D01*
X149741Y580D01*
X149738Y577D01*
X151707D01*
Y267D01*
X149177D01*
Y468D01*
X149239Y504D01*
X149297Y544D01*
X149355Y591D01*
X149406Y635D01*
X149450Y679D01*
X149486Y711D01*
X149497Y726D01*
X149508Y737D01*
X149512Y741D01*
X149515Y744D01*
X149577Y821D01*
X149636Y897D01*
X149687Y970D01*
X149727Y1043D01*
X149763Y1105D01*
X149778Y1130D01*
X149788Y1152D01*
X149800Y1170D01*
X149803Y1185D01*
X149810Y1192D01*
Y1196D01*
X150109D01*
X150087Y1141D01*
D02*
G37*
G36*
X150593Y-530D02*
X150713Y-537D01*
X150822Y-548D01*
X150924Y-566D01*
X151019Y-584D01*
X151103Y-606D01*
X151179Y-628D01*
X151244Y-650D01*
X151303Y-672D01*
X151354Y-697D01*
X151397Y-715D01*
X151430Y-734D01*
X151459Y-752D01*
X151478Y-763D01*
X151488Y-770D01*
X151492Y-774D01*
X151536Y-814D01*
X151576Y-857D01*
X151612Y-905D01*
X151641Y-952D01*
X151667Y-999D01*
X151689Y-1047D01*
X151703Y-1094D01*
X151718Y-1138D01*
X151729Y-1181D01*
X151736Y-1221D01*
X151743Y-1258D01*
X151747Y-1287D01*
X151751Y-1312D01*
Y-1349D01*
X151743Y-1447D01*
X151729Y-1538D01*
X151703Y-1615D01*
X151678Y-1680D01*
X151652Y-1735D01*
X151638Y-1753D01*
X151627Y-1771D01*
X151620Y-1786D01*
X151612Y-1797D01*
X151605Y-1800D01*
Y-1804D01*
X151543Y-1869D01*
X151478Y-1924D01*
X151405Y-1971D01*
X151339Y-2008D01*
X151277Y-2037D01*
X151252Y-2051D01*
X151226Y-2059D01*
X151208Y-2066D01*
X151194Y-2073D01*
X151186Y-2077D01*
X151183D01*
X151128Y-2095D01*
X151074Y-2110D01*
X150957Y-2131D01*
X150837Y-2150D01*
X150720Y-2160D01*
X150669Y-2164D01*
X150622Y-2168D01*
X150578D01*
X150538Y-2172D01*
X150509D01*
X150484D01*
X150469D01*
X150466D01*
X150396D01*
X150331Y-2168D01*
X150273D01*
X150214Y-2164D01*
X150163Y-2157D01*
X150112Y-2153D01*
X150069Y-2150D01*
X150029Y-2142D01*
X149992Y-2139D01*
X149960Y-2131D01*
X149934Y-2128D01*
X149912Y-2124D01*
X149894Y-2121D01*
X149883Y-2117D01*
X149876Y-2113D01*
X149872D01*
X149792Y-2091D01*
X149719Y-2066D01*
X149657Y-2037D01*
X149603Y-2015D01*
X149556Y-1990D01*
X149523Y-1975D01*
X149505Y-1960D01*
X149497Y-1957D01*
X149443Y-1917D01*
X149395Y-1877D01*
X149355Y-1833D01*
X149319Y-1793D01*
X149293Y-1757D01*
X149275Y-1727D01*
X149264Y-1709D01*
X149261Y-1705D01*
Y-1702D01*
X149232Y-1644D01*
X149213Y-1582D01*
X149199Y-1524D01*
X149188Y-1469D01*
X149181Y-1422D01*
X149177Y-1382D01*
Y-1349D01*
X149184Y-1251D01*
X149199Y-1159D01*
X149224Y-1083D01*
X149250Y-1018D01*
X149279Y-963D01*
X149290Y-941D01*
X149304Y-923D01*
X149312Y-908D01*
X149319Y-898D01*
X149326Y-894D01*
Y-890D01*
X149384Y-825D01*
X149454Y-770D01*
X149523Y-723D01*
X149588Y-686D01*
X149650Y-657D01*
X149676Y-643D01*
X149701Y-635D01*
X149719Y-628D01*
X149734Y-621D01*
X149741Y-617D01*
X149745D01*
X149800Y-603D01*
X149854Y-588D01*
X149974Y-566D01*
X150094Y-548D01*
X150207Y-537D01*
X150262Y-533D01*
X150309Y-530D01*
X150353D01*
X150393Y-526D01*
X150422D01*
X150447D01*
X150462D01*
X150466D01*
X150593Y-530D01*
D02*
G37*
G36*
X150098Y-2488D02*
X150160Y-2495D01*
X150222Y-2503D01*
X150280Y-2517D01*
X150331Y-2536D01*
X150382Y-2554D01*
X150426Y-2572D01*
X150466Y-2594D01*
X150502Y-2612D01*
X150535Y-2630D01*
X150560Y-2648D01*
X150586Y-2667D01*
X150604Y-2681D01*
X150615Y-2688D01*
X150622Y-2696D01*
X150626Y-2699D01*
X150666Y-2739D01*
X150698Y-2783D01*
X150731Y-2827D01*
X150757Y-2874D01*
X150779Y-2918D01*
X150797Y-2961D01*
X150822Y-3045D01*
X150833Y-3081D01*
X150840Y-3118D01*
X150844Y-3147D01*
X150848Y-3176D01*
X150851Y-3198D01*
Y-3227D01*
X150848Y-3296D01*
X150837Y-3362D01*
X150822Y-3420D01*
X150804Y-3475D01*
X150789Y-3515D01*
X150775Y-3547D01*
X150764Y-3569D01*
X150760Y-3576D01*
X150724Y-3635D01*
X150684Y-3686D01*
X150644Y-3729D01*
X150608Y-3766D01*
X150571Y-3791D01*
X150546Y-3813D01*
X150528Y-3828D01*
X150520Y-3831D01*
X150549D01*
X150567D01*
X150578D01*
X150582D01*
X150655Y-3828D01*
X150724Y-3824D01*
X150786Y-3817D01*
X150844Y-3809D01*
X150891Y-3799D01*
X150928Y-3791D01*
X150942Y-3788D01*
X150953D01*
X150957Y-3784D01*
X150961D01*
X151026Y-3766D01*
X151084Y-3748D01*
X151135Y-3729D01*
X151179Y-3711D01*
X151212Y-3697D01*
X151237Y-3682D01*
X151256Y-3675D01*
X151259Y-3671D01*
X151299Y-3642D01*
X151332Y-3613D01*
X151361Y-3584D01*
X151386Y-3555D01*
X151408Y-3533D01*
X151423Y-3511D01*
X151430Y-3496D01*
X151434Y-3493D01*
X151456Y-3453D01*
X151470Y-3409D01*
X151481Y-3369D01*
X151488Y-3329D01*
X151492Y-3296D01*
X151496Y-3271D01*
Y-3245D01*
X151492Y-3187D01*
X151481Y-3132D01*
X151467Y-3085D01*
X151448Y-3045D01*
X151434Y-3016D01*
X151419Y-2990D01*
X151408Y-2976D01*
X151405Y-2972D01*
X151365Y-2936D01*
X151317Y-2907D01*
X151266Y-2881D01*
X151215Y-2863D01*
X151172Y-2849D01*
X151132Y-2838D01*
X151117Y-2834D01*
X151110D01*
X151103Y-2830D01*
X151099D01*
X151124Y-2532D01*
X151230Y-2554D01*
X151321Y-2583D01*
X151401Y-2619D01*
X151467Y-2656D01*
X151517Y-2692D01*
X151539Y-2710D01*
X151558Y-2725D01*
X151568Y-2736D01*
X151579Y-2747D01*
X151583Y-2750D01*
X151587Y-2754D01*
X151616Y-2790D01*
X151641Y-2830D01*
X151681Y-2910D01*
X151710Y-2990D01*
X151729Y-3067D01*
X151743Y-3136D01*
X151747Y-3165D01*
Y-3191D01*
X151751Y-3209D01*
Y-3238D01*
X151743Y-3340D01*
X151729Y-3431D01*
X151703Y-3515D01*
X151674Y-3584D01*
X151663Y-3613D01*
X151649Y-3642D01*
X151634Y-3664D01*
X151623Y-3686D01*
X151616Y-3700D01*
X151609Y-3711D01*
X151601Y-3718D01*
Y-3722D01*
X151539Y-3795D01*
X151470Y-3860D01*
X151397Y-3911D01*
X151328Y-3955D01*
X151266Y-3991D01*
X151237Y-4006D01*
X151215Y-4017D01*
X151194Y-4024D01*
X151179Y-4031D01*
X151172Y-4035D01*
X151168D01*
X151113Y-4053D01*
X151052Y-4072D01*
X150928Y-4097D01*
X150797Y-4115D01*
X150673Y-4126D01*
X150619Y-4133D01*
X150564Y-4137D01*
X150516D01*
X150477Y-4141D01*
X150444D01*
X150418D01*
X150400D01*
X150396D01*
X150313D01*
X150233Y-4137D01*
X150160Y-4130D01*
X150091Y-4123D01*
X150029Y-4115D01*
X149970Y-4108D01*
X149916Y-4097D01*
X149869Y-4086D01*
X149829Y-4075D01*
X149792Y-4068D01*
X149759Y-4057D01*
X149734Y-4050D01*
X149716Y-4042D01*
X149701Y-4035D01*
X149694Y-4031D01*
X149690D01*
X149603Y-3988D01*
X149527Y-3940D01*
X149461Y-3886D01*
X149406Y-3839D01*
X149366Y-3791D01*
X149337Y-3755D01*
X149326Y-3740D01*
X149319Y-3729D01*
X149312Y-3726D01*
Y-3722D01*
X149268Y-3646D01*
X149235Y-3569D01*
X149210Y-3493D01*
X149195Y-3424D01*
X149184Y-3362D01*
X149181Y-3336D01*
Y-3318D01*
X149177Y-3300D01*
Y-3274D01*
X149181Y-3212D01*
X149188Y-3154D01*
X149199Y-3096D01*
X149213Y-3045D01*
X149253Y-2947D01*
X149272Y-2903D01*
X149293Y-2867D01*
X149319Y-2830D01*
X149337Y-2801D01*
X149359Y-2772D01*
X149377Y-2750D01*
X149392Y-2732D01*
X149403Y-2721D01*
X149410Y-2714D01*
X149414Y-2710D01*
X149457Y-2670D01*
X149508Y-2637D01*
X149556Y-2605D01*
X149607Y-2579D01*
X149661Y-2557D01*
X149712Y-2539D01*
X149807Y-2514D01*
X149854Y-2503D01*
X149894Y-2495D01*
X149934Y-2492D01*
X149967Y-2488D01*
X149992Y-2485D01*
X150011D01*
X150025D01*
X150029D01*
X150098Y-2488D01*
D02*
G37*
G36*
X493804Y-249851D02*
X493844Y-249909D01*
X493892Y-249967D01*
X493935Y-250018D01*
X493979Y-250062D01*
X494012Y-250098D01*
X494026Y-250109D01*
X494037Y-250120D01*
X494041Y-250124D01*
X494045Y-250127D01*
X494121Y-250189D01*
X494198Y-250247D01*
X494270Y-250298D01*
X494343Y-250338D01*
X494405Y-250375D01*
X494430Y-250389D01*
X494452Y-250400D01*
X494471Y-250411D01*
X494485Y-250415D01*
X494492Y-250422D01*
X494496D01*
Y-250721D01*
X494441Y-250699D01*
X494387Y-250673D01*
X494332Y-250648D01*
X494281Y-250622D01*
X494238Y-250601D01*
X494201Y-250582D01*
X494179Y-250568D01*
X494176Y-250564D01*
X494172D01*
X494106Y-250524D01*
X494048Y-250484D01*
X493997Y-250448D01*
X493957Y-250415D01*
X493921Y-250389D01*
X493899Y-250367D01*
X493881Y-250353D01*
X493877Y-250349D01*
Y-252319D01*
X493568D01*
Y-249789D01*
X493768D01*
X493804Y-249851D01*
D02*
G37*
G36*
X489888D02*
X489928Y-249909D01*
X489975Y-249967D01*
X490019Y-250018D01*
X490062Y-250062D01*
X490095Y-250098D01*
X490110Y-250109D01*
X490121Y-250120D01*
X490124Y-250124D01*
X490128Y-250127D01*
X490204Y-250189D01*
X490281Y-250247D01*
X490354Y-250298D01*
X490426Y-250338D01*
X490488Y-250375D01*
X490514Y-250389D01*
X490536Y-250400D01*
X490554Y-250411D01*
X490568Y-250415D01*
X490576Y-250422D01*
X490579D01*
Y-250721D01*
X490525Y-250699D01*
X490470Y-250673D01*
X490415Y-250648D01*
X490365Y-250622D01*
X490321Y-250601D01*
X490284Y-250582D01*
X490263Y-250568D01*
X490259Y-250564D01*
X490255D01*
X490190Y-250524D01*
X490132Y-250484D01*
X490081Y-250448D01*
X490041Y-250415D01*
X490004Y-250389D01*
X489982Y-250367D01*
X489964Y-250353D01*
X489960Y-250349D01*
Y-252319D01*
X489651D01*
Y-249789D01*
X489851D01*
X489888Y-249851D01*
D02*
G37*
G36*
X496178Y-249763D02*
X496294Y-249781D01*
X496396Y-249803D01*
X496443Y-249818D01*
X496487Y-249833D01*
X496527Y-249847D01*
X496563Y-249862D01*
X496593Y-249872D01*
X496622Y-249883D01*
X496640Y-249894D01*
X496655Y-249902D01*
X496665Y-249905D01*
X496669Y-249909D01*
X496767Y-249971D01*
X496851Y-250044D01*
X496924Y-250116D01*
X496986Y-250189D01*
X497033Y-250255D01*
X497051Y-250284D01*
X497066Y-250309D01*
X497080Y-250327D01*
X497088Y-250342D01*
X497091Y-250353D01*
X497095Y-250357D01*
X497146Y-250469D01*
X497182Y-250586D01*
X497208Y-250702D01*
X497226Y-250808D01*
X497233Y-250855D01*
X497237Y-250903D01*
X497240Y-250939D01*
Y-250975D01*
X497244Y-251001D01*
Y-251023D01*
Y-251037D01*
Y-251041D01*
X497237Y-251172D01*
X497222Y-251299D01*
X497204Y-251412D01*
X497190Y-251467D01*
X497179Y-251514D01*
X497168Y-251558D01*
X497153Y-251598D01*
X497142Y-251634D01*
X497135Y-251663D01*
X497124Y-251685D01*
X497120Y-251703D01*
X497113Y-251714D01*
Y-251718D01*
X497058Y-251827D01*
X496997Y-251925D01*
X496931Y-252009D01*
X496898Y-252042D01*
X496869Y-252075D01*
X496840Y-252104D01*
X496811Y-252129D01*
X496785Y-252151D01*
X496764Y-252166D01*
X496749Y-252180D01*
X496735Y-252191D01*
X496727Y-252195D01*
X496724Y-252199D01*
X496673Y-252228D01*
X496622Y-252253D01*
X496513Y-252293D01*
X496403Y-252322D01*
X496298Y-252340D01*
X496247Y-252348D01*
X496203Y-252355D01*
X496163Y-252359D01*
X496130D01*
X496101Y-252362D01*
X496061D01*
X495988Y-252359D01*
X495919Y-252351D01*
X495854Y-252344D01*
X495792Y-252329D01*
X495733Y-252311D01*
X495679Y-252293D01*
X495628Y-252275D01*
X495581Y-252253D01*
X495541Y-252235D01*
X495501Y-252217D01*
X495471Y-252199D01*
X495442Y-252180D01*
X495424Y-252166D01*
X495406Y-252158D01*
X495399Y-252151D01*
X495395Y-252148D01*
X495344Y-252104D01*
X495300Y-252060D01*
X495260Y-252009D01*
X495220Y-251958D01*
X495155Y-251856D01*
X495104Y-251754D01*
X495082Y-251707D01*
X495064Y-251663D01*
X495049Y-251623D01*
X495038Y-251591D01*
X495027Y-251561D01*
X495020Y-251540D01*
X495016Y-251525D01*
Y-251521D01*
X495351Y-251438D01*
X495366Y-251496D01*
X495384Y-251551D01*
X495402Y-251602D01*
X495421Y-251649D01*
X495442Y-251693D01*
X495464Y-251729D01*
X495490Y-251765D01*
X495511Y-251798D01*
X495530Y-251827D01*
X495551Y-251849D01*
X495570Y-251871D01*
X495584Y-251889D01*
X495599Y-251900D01*
X495610Y-251911D01*
X495613Y-251915D01*
X495617Y-251918D01*
X495653Y-251947D01*
X495693Y-251969D01*
X495774Y-252009D01*
X495850Y-252038D01*
X495927Y-252057D01*
X495992Y-252071D01*
X496018Y-252075D01*
X496043D01*
X496065Y-252078D01*
X496090D01*
X496174Y-252075D01*
X496254Y-252060D01*
X496327Y-252042D01*
X496392Y-252020D01*
X496443Y-251998D01*
X496465Y-251987D01*
X496483Y-251980D01*
X496498Y-251973D01*
X496509Y-251965D01*
X496516Y-251962D01*
X496520D01*
X496589Y-251911D01*
X496647Y-251856D01*
X496698Y-251794D01*
X496738Y-251736D01*
X496771Y-251685D01*
X496793Y-251642D01*
X496800Y-251623D01*
X496807Y-251612D01*
X496811Y-251605D01*
Y-251602D01*
X496840Y-251507D01*
X496862Y-251412D01*
X496880Y-251318D01*
X496891Y-251230D01*
X496895Y-251190D01*
X496898Y-251154D01*
Y-251121D01*
X496902Y-251096D01*
Y-251074D01*
Y-251056D01*
Y-251045D01*
Y-251041D01*
X496898Y-250946D01*
X496891Y-250859D01*
X496876Y-250779D01*
X496862Y-250706D01*
X496851Y-250644D01*
X496844Y-250619D01*
X496837Y-250597D01*
X496833Y-250579D01*
X496829Y-250568D01*
X496826Y-250560D01*
Y-250557D01*
X496789Y-250473D01*
X496749Y-250397D01*
X496705Y-250335D01*
X496658Y-250280D01*
X496618Y-250237D01*
X496585Y-250207D01*
X496560Y-250189D01*
X496556Y-250182D01*
X496553D01*
X496476Y-250135D01*
X496392Y-250098D01*
X496312Y-250073D01*
X496236Y-250058D01*
X496167Y-250047D01*
X496138Y-250044D01*
X496112D01*
X496094Y-250040D01*
X496065D01*
X495974Y-250044D01*
X495890Y-250058D01*
X495821Y-250080D01*
X495759Y-250102D01*
X495712Y-250127D01*
X495675Y-250146D01*
X495653Y-250160D01*
X495646Y-250167D01*
X495588Y-250222D01*
X495533Y-250284D01*
X495490Y-250349D01*
X495453Y-250415D01*
X495424Y-250473D01*
X495413Y-250502D01*
X495406Y-250524D01*
X495399Y-250542D01*
X495391Y-250557D01*
X495388Y-250564D01*
Y-250568D01*
X495060Y-250491D01*
X495082Y-250426D01*
X495104Y-250367D01*
X495133Y-250313D01*
X495158Y-250258D01*
X495188Y-250211D01*
X495220Y-250167D01*
X495249Y-250124D01*
X495279Y-250087D01*
X495308Y-250058D01*
X495333Y-250029D01*
X495359Y-250004D01*
X495377Y-249985D01*
X495395Y-249967D01*
X495410Y-249956D01*
X495417Y-249953D01*
X495421Y-249949D01*
X495471Y-249916D01*
X495522Y-249883D01*
X495573Y-249858D01*
X495628Y-249836D01*
X495737Y-249803D01*
X495835Y-249781D01*
X495883Y-249771D01*
X495923Y-249767D01*
X495963Y-249763D01*
X495996Y-249760D01*
X496021Y-249756D01*
X496058D01*
X496178Y-249763D01*
D02*
G37*
G36*
X492050Y-249796D02*
X492141Y-249811D01*
X492217Y-249836D01*
X492283Y-249862D01*
X492337Y-249891D01*
X492359Y-249902D01*
X492378Y-249916D01*
X492392Y-249923D01*
X492403Y-249931D01*
X492407Y-249938D01*
X492410D01*
X492476Y-249996D01*
X492530Y-250065D01*
X492578Y-250135D01*
X492614Y-250200D01*
X492643Y-250262D01*
X492658Y-250287D01*
X492665Y-250313D01*
X492672Y-250331D01*
X492680Y-250346D01*
X492683Y-250353D01*
Y-250357D01*
X492698Y-250411D01*
X492712Y-250466D01*
X492734Y-250586D01*
X492752Y-250706D01*
X492763Y-250819D01*
X492767Y-250873D01*
X492771Y-250921D01*
Y-250964D01*
X492774Y-251005D01*
Y-251034D01*
Y-251059D01*
Y-251074D01*
Y-251077D01*
X492771Y-251205D01*
X492763Y-251325D01*
X492752Y-251434D01*
X492734Y-251536D01*
X492716Y-251631D01*
X492694Y-251714D01*
X492672Y-251791D01*
X492651Y-251856D01*
X492629Y-251915D01*
X492603Y-251965D01*
X492585Y-252009D01*
X492567Y-252042D01*
X492549Y-252071D01*
X492538Y-252089D01*
X492530Y-252100D01*
X492527Y-252104D01*
X492487Y-252148D01*
X492443Y-252187D01*
X492396Y-252224D01*
X492348Y-252253D01*
X492301Y-252278D01*
X492254Y-252300D01*
X492206Y-252315D01*
X492163Y-252329D01*
X492119Y-252340D01*
X492079Y-252348D01*
X492043Y-252355D01*
X492014Y-252359D01*
X491988Y-252362D01*
X491952D01*
X491853Y-252355D01*
X491762Y-252340D01*
X491686Y-252315D01*
X491620Y-252289D01*
X491566Y-252264D01*
X491547Y-252249D01*
X491529Y-252238D01*
X491515Y-252231D01*
X491504Y-252224D01*
X491500Y-252217D01*
X491497D01*
X491431Y-252155D01*
X491376Y-252089D01*
X491329Y-252016D01*
X491293Y-251951D01*
X491264Y-251889D01*
X491249Y-251864D01*
X491242Y-251838D01*
X491234Y-251820D01*
X491227Y-251805D01*
X491224Y-251798D01*
Y-251794D01*
X491205Y-251740D01*
X491191Y-251685D01*
X491169Y-251569D01*
X491151Y-251449D01*
X491140Y-251332D01*
X491136Y-251281D01*
X491133Y-251234D01*
Y-251190D01*
X491129Y-251150D01*
Y-251121D01*
Y-251096D01*
Y-251081D01*
Y-251077D01*
Y-251008D01*
X491133Y-250943D01*
Y-250884D01*
X491136Y-250826D01*
X491144Y-250775D01*
X491147Y-250724D01*
X491151Y-250681D01*
X491158Y-250641D01*
X491162Y-250604D01*
X491169Y-250571D01*
X491173Y-250546D01*
X491176Y-250524D01*
X491180Y-250506D01*
X491184Y-250495D01*
X491187Y-250488D01*
Y-250484D01*
X491209Y-250404D01*
X491234Y-250331D01*
X491264Y-250269D01*
X491286Y-250215D01*
X491311Y-250167D01*
X491326Y-250135D01*
X491340Y-250116D01*
X491344Y-250109D01*
X491384Y-250055D01*
X491424Y-250007D01*
X491468Y-249967D01*
X491507Y-249931D01*
X491544Y-249905D01*
X491573Y-249887D01*
X491591Y-249876D01*
X491595Y-249872D01*
X491599D01*
X491657Y-249843D01*
X491719Y-249825D01*
X491777Y-249811D01*
X491831Y-249800D01*
X491879Y-249792D01*
X491919Y-249789D01*
X491952D01*
X492050Y-249796D01*
D02*
G37*
G36*
X508933Y-260140D02*
X509002Y-260147D01*
X509068Y-260154D01*
X509129Y-260169D01*
X509188Y-260187D01*
X509242Y-260205D01*
X509293Y-260224D01*
X509341Y-260245D01*
X509381Y-260263D01*
X509421Y-260282D01*
X509450Y-260300D01*
X509479Y-260318D01*
X509497Y-260333D01*
X509515Y-260340D01*
X509523Y-260347D01*
X509526Y-260351D01*
X509577Y-260395D01*
X509621Y-260438D01*
X509661Y-260489D01*
X509701Y-260540D01*
X509766Y-260642D01*
X509817Y-260744D01*
X509839Y-260791D01*
X509858Y-260835D01*
X509872Y-260875D01*
X509883Y-260908D01*
X509894Y-260937D01*
X509901Y-260959D01*
X509905Y-260973D01*
Y-260977D01*
X509570Y-261061D01*
X509555Y-261002D01*
X509537Y-260948D01*
X509519Y-260897D01*
X509501Y-260850D01*
X509479Y-260806D01*
X509457Y-260770D01*
X509432Y-260733D01*
X509410Y-260700D01*
X509392Y-260671D01*
X509370Y-260649D01*
X509351Y-260628D01*
X509337Y-260609D01*
X509322Y-260598D01*
X509311Y-260588D01*
X509308Y-260584D01*
X509304Y-260580D01*
X509268Y-260551D01*
X509228Y-260529D01*
X509148Y-260489D01*
X509071Y-260460D01*
X508995Y-260442D01*
X508929Y-260427D01*
X508904Y-260424D01*
X508878D01*
X508856Y-260420D01*
X508831D01*
X508747Y-260424D01*
X508667Y-260438D01*
X508594Y-260456D01*
X508529Y-260478D01*
X508478Y-260500D01*
X508456Y-260511D01*
X508438Y-260518D01*
X508423Y-260526D01*
X508412Y-260533D01*
X508405Y-260537D01*
X508401D01*
X508332Y-260588D01*
X508274Y-260642D01*
X508223Y-260704D01*
X508183Y-260762D01*
X508150Y-260813D01*
X508128Y-260857D01*
X508121Y-260875D01*
X508114Y-260886D01*
X508110Y-260893D01*
Y-260897D01*
X508081Y-260992D01*
X508059Y-261086D01*
X508041Y-261181D01*
X508030Y-261268D01*
X508027Y-261308D01*
X508023Y-261345D01*
Y-261377D01*
X508019Y-261403D01*
Y-261425D01*
Y-261443D01*
Y-261454D01*
Y-261457D01*
X508023Y-261552D01*
X508030Y-261639D01*
X508045Y-261719D01*
X508059Y-261792D01*
X508070Y-261854D01*
X508077Y-261880D01*
X508085Y-261901D01*
X508088Y-261920D01*
X508092Y-261931D01*
X508096Y-261938D01*
Y-261942D01*
X508132Y-262025D01*
X508172Y-262102D01*
X508216Y-262164D01*
X508263Y-262218D01*
X508303Y-262262D01*
X508336Y-262291D01*
X508361Y-262309D01*
X508365Y-262316D01*
X508369D01*
X508445Y-262364D01*
X508529Y-262400D01*
X508609Y-262426D01*
X508685Y-262440D01*
X508755Y-262451D01*
X508784Y-262455D01*
X508809D01*
X508827Y-262458D01*
X508856D01*
X508948Y-262455D01*
X509031Y-262440D01*
X509100Y-262418D01*
X509162Y-262397D01*
X509210Y-262371D01*
X509246Y-262353D01*
X509268Y-262338D01*
X509275Y-262331D01*
X509333Y-262277D01*
X509388Y-262215D01*
X509432Y-262149D01*
X509468Y-262084D01*
X509497Y-262025D01*
X509508Y-261996D01*
X509515Y-261974D01*
X509523Y-261956D01*
X509530Y-261942D01*
X509534Y-261934D01*
Y-261931D01*
X509861Y-262007D01*
X509839Y-262073D01*
X509817Y-262131D01*
X509788Y-262185D01*
X509763Y-262240D01*
X509734Y-262287D01*
X509701Y-262331D01*
X509672Y-262375D01*
X509643Y-262411D01*
X509614Y-262440D01*
X509588Y-262469D01*
X509563Y-262495D01*
X509544Y-262513D01*
X509526Y-262531D01*
X509512Y-262542D01*
X509504Y-262546D01*
X509501Y-262549D01*
X509450Y-262582D01*
X509399Y-262615D01*
X509348Y-262641D01*
X509293Y-262662D01*
X509184Y-262695D01*
X509086Y-262717D01*
X509038Y-262728D01*
X508998Y-262731D01*
X508958Y-262735D01*
X508926Y-262739D01*
X508900Y-262742D01*
X508864D01*
X508744Y-262735D01*
X508627Y-262717D01*
X508525Y-262695D01*
X508478Y-262681D01*
X508434Y-262666D01*
X508394Y-262651D01*
X508358Y-262637D01*
X508329Y-262626D01*
X508299Y-262615D01*
X508281Y-262604D01*
X508267Y-262597D01*
X508256Y-262593D01*
X508252Y-262590D01*
X508154Y-262528D01*
X508070Y-262455D01*
X507997Y-262382D01*
X507935Y-262309D01*
X507888Y-262244D01*
X507870Y-262215D01*
X507856Y-262189D01*
X507841Y-262171D01*
X507834Y-262156D01*
X507830Y-262145D01*
X507826Y-262142D01*
X507775Y-262029D01*
X507739Y-261912D01*
X507714Y-261796D01*
X507695Y-261690D01*
X507688Y-261643D01*
X507684Y-261596D01*
X507681Y-261559D01*
Y-261523D01*
X507677Y-261497D01*
Y-261476D01*
Y-261461D01*
Y-261457D01*
X507684Y-261326D01*
X507699Y-261199D01*
X507717Y-261086D01*
X507732Y-261032D01*
X507743Y-260984D01*
X507754Y-260941D01*
X507768Y-260900D01*
X507779Y-260864D01*
X507786Y-260835D01*
X507797Y-260813D01*
X507801Y-260795D01*
X507808Y-260784D01*
Y-260780D01*
X507863Y-260671D01*
X507925Y-260573D01*
X507990Y-260489D01*
X508023Y-260456D01*
X508052Y-260424D01*
X508081Y-260395D01*
X508110Y-260369D01*
X508136Y-260347D01*
X508158Y-260333D01*
X508172Y-260318D01*
X508187Y-260307D01*
X508194Y-260304D01*
X508198Y-260300D01*
X508249Y-260271D01*
X508299Y-260245D01*
X508409Y-260205D01*
X508518Y-260176D01*
X508624Y-260158D01*
X508674Y-260151D01*
X508718Y-260143D01*
X508758Y-260140D01*
X508791D01*
X508820Y-260136D01*
X508860D01*
X508933Y-260140D01*
D02*
G37*
G36*
X511353Y-262710D02*
X511153D01*
X511117Y-262648D01*
X511077Y-262590D01*
X511030Y-262531D01*
X510986Y-262480D01*
X510942Y-262437D01*
X510909Y-262400D01*
X510895Y-262389D01*
X510884Y-262378D01*
X510880Y-262375D01*
X510877Y-262371D01*
X510800Y-262309D01*
X510724Y-262251D01*
X510651Y-262200D01*
X510578Y-262160D01*
X510516Y-262124D01*
X510491Y-262109D01*
X510469Y-262098D01*
X510451Y-262087D01*
X510436Y-262084D01*
X510429Y-262076D01*
X510425D01*
Y-261778D01*
X510480Y-261800D01*
X510534Y-261825D01*
X510589Y-261851D01*
X510640Y-261876D01*
X510684Y-261898D01*
X510720Y-261916D01*
X510742Y-261931D01*
X510746Y-261934D01*
X510749D01*
X510815Y-261974D01*
X510873Y-262014D01*
X510924Y-262051D01*
X510964Y-262084D01*
X511000Y-262109D01*
X511022Y-262131D01*
X511040Y-262145D01*
X511044Y-262149D01*
Y-260180D01*
X511353D01*
Y-262710D01*
D02*
G37*
G36*
X515732Y-260478D02*
X514491D01*
X514535Y-260540D01*
X514557Y-260566D01*
X514575Y-260591D01*
X514593Y-260613D01*
X514608Y-260628D01*
X514619Y-260638D01*
X514622Y-260642D01*
X514640Y-260660D01*
X514662Y-260679D01*
X514713Y-260726D01*
X514772Y-260780D01*
X514833Y-260835D01*
X514892Y-260882D01*
X514917Y-260904D01*
X514939Y-260926D01*
X514957Y-260941D01*
X514972Y-260951D01*
X514979Y-260959D01*
X514983Y-260962D01*
X515041Y-261013D01*
X515099Y-261061D01*
X515150Y-261108D01*
X515197Y-261148D01*
X515241Y-261188D01*
X515277Y-261225D01*
X515314Y-261257D01*
X515343Y-261286D01*
X515372Y-261315D01*
X515394Y-261337D01*
X515412Y-261355D01*
X515430Y-261374D01*
X515449Y-261396D01*
X515456Y-261403D01*
X515507Y-261465D01*
X515550Y-261519D01*
X515587Y-261574D01*
X515616Y-261618D01*
X515638Y-261658D01*
X515652Y-261687D01*
X515660Y-261705D01*
X515663Y-261712D01*
X515685Y-261767D01*
X515700Y-261822D01*
X515714Y-261872D01*
X515722Y-261916D01*
X515725Y-261956D01*
X515729Y-261985D01*
Y-262003D01*
Y-262011D01*
X515725Y-262065D01*
X515718Y-262116D01*
X515711Y-262167D01*
X515696Y-262211D01*
X515660Y-262298D01*
X515623Y-262368D01*
X515601Y-262400D01*
X515583Y-262426D01*
X515565Y-262451D01*
X515547Y-262469D01*
X515532Y-262484D01*
X515525Y-262498D01*
X515518Y-262502D01*
X515514Y-262506D01*
X515474Y-262542D01*
X515430Y-262575D01*
X515383Y-262600D01*
X515336Y-262622D01*
X515241Y-262659D01*
X515146Y-262684D01*
X515106Y-262691D01*
X515066Y-262699D01*
X515030Y-262702D01*
X515001Y-262706D01*
X514975Y-262710D01*
X514939D01*
X514873Y-262706D01*
X514812Y-262702D01*
X514753Y-262691D01*
X514699Y-262681D01*
X514648Y-262666D01*
X514600Y-262651D01*
X514557Y-262633D01*
X514517Y-262615D01*
X514480Y-262597D01*
X514451Y-262579D01*
X514426Y-262564D01*
X514404Y-262549D01*
X514386Y-262539D01*
X514375Y-262528D01*
X514367Y-262524D01*
X514364Y-262520D01*
X514327Y-262484D01*
X514295Y-262444D01*
X514262Y-262400D01*
X514236Y-262356D01*
X514193Y-262269D01*
X514164Y-262182D01*
X514153Y-262142D01*
X514142Y-262102D01*
X514135Y-262069D01*
X514127Y-262040D01*
X514123Y-262014D01*
Y-261996D01*
X514120Y-261985D01*
Y-261982D01*
X514437Y-261949D01*
X514444Y-262033D01*
X514458Y-262105D01*
X514480Y-262171D01*
X514506Y-262222D01*
X514528Y-262265D01*
X514549Y-262295D01*
X514564Y-262313D01*
X514571Y-262320D01*
X514626Y-262364D01*
X514684Y-262397D01*
X514746Y-262422D01*
X514801Y-262437D01*
X514852Y-262448D01*
X514895Y-262451D01*
X514910Y-262455D01*
X514932D01*
X515008Y-262451D01*
X515077Y-262437D01*
X515135Y-262415D01*
X515186Y-262393D01*
X515227Y-262368D01*
X515252Y-262349D01*
X515270Y-262335D01*
X515277Y-262327D01*
X515321Y-262277D01*
X515354Y-262226D01*
X515379Y-262175D01*
X515394Y-262124D01*
X515405Y-262084D01*
X515409Y-262047D01*
X515412Y-262025D01*
Y-262022D01*
Y-262018D01*
X515405Y-261952D01*
X515390Y-261883D01*
X515365Y-261822D01*
X515339Y-261763D01*
X515310Y-261716D01*
X515285Y-261676D01*
X515277Y-261661D01*
X515270Y-261650D01*
X515263Y-261647D01*
Y-261643D01*
X515234Y-261603D01*
X515197Y-261563D01*
X515157Y-261519D01*
X515114Y-261476D01*
X515023Y-261388D01*
X514932Y-261301D01*
X514884Y-261261D01*
X514844Y-261225D01*
X514804Y-261192D01*
X514772Y-261163D01*
X514746Y-261141D01*
X514724Y-261123D01*
X514710Y-261112D01*
X514706Y-261108D01*
X514615Y-261032D01*
X514531Y-260959D01*
X514462Y-260893D01*
X514407Y-260839D01*
X514360Y-260791D01*
X514327Y-260759D01*
X514309Y-260737D01*
X514302Y-260733D01*
Y-260729D01*
X514251Y-260668D01*
X514211Y-260609D01*
X514175Y-260551D01*
X514145Y-260500D01*
X514123Y-260456D01*
X514109Y-260424D01*
X514102Y-260402D01*
X514098Y-260398D01*
Y-260395D01*
X514083Y-260354D01*
X514076Y-260318D01*
X514069Y-260282D01*
X514065Y-260249D01*
X514062Y-260220D01*
Y-260198D01*
Y-260183D01*
Y-260180D01*
X515732D01*
Y-260478D01*
D02*
G37*
G36*
X513068Y-260143D02*
X513159Y-260158D01*
X513235Y-260183D01*
X513301Y-260209D01*
X513355Y-260234D01*
X513374Y-260249D01*
X513392Y-260260D01*
X513407Y-260267D01*
X513417Y-260274D01*
X513421Y-260282D01*
X513425D01*
X513490Y-260344D01*
X513545Y-260409D01*
X513592Y-260482D01*
X513628Y-260547D01*
X513658Y-260609D01*
X513672Y-260635D01*
X513680Y-260660D01*
X513687Y-260679D01*
X513694Y-260693D01*
X513698Y-260700D01*
Y-260704D01*
X513716Y-260759D01*
X513730Y-260813D01*
X513752Y-260930D01*
X513770Y-261050D01*
X513781Y-261166D01*
X513785Y-261217D01*
X513789Y-261264D01*
Y-261308D01*
X513792Y-261348D01*
Y-261377D01*
Y-261403D01*
Y-261417D01*
Y-261421D01*
Y-261490D01*
X513789Y-261556D01*
Y-261614D01*
X513785Y-261672D01*
X513778Y-261723D01*
X513774Y-261774D01*
X513770Y-261818D01*
X513763Y-261858D01*
X513760Y-261894D01*
X513752Y-261927D01*
X513749Y-261952D01*
X513745Y-261974D01*
X513741Y-261993D01*
X513738Y-262003D01*
X513734Y-262011D01*
Y-262014D01*
X513712Y-262094D01*
X513687Y-262167D01*
X513658Y-262229D01*
X513636Y-262284D01*
X513610Y-262331D01*
X513596Y-262364D01*
X513581Y-262382D01*
X513578Y-262389D01*
X513538Y-262444D01*
X513497Y-262491D01*
X513454Y-262531D01*
X513414Y-262568D01*
X513377Y-262593D01*
X513348Y-262611D01*
X513330Y-262622D01*
X513326Y-262626D01*
X513323D01*
X513265Y-262655D01*
X513203Y-262673D01*
X513144Y-262688D01*
X513090Y-262699D01*
X513042Y-262706D01*
X513002Y-262710D01*
X512970D01*
X512871Y-262702D01*
X512780Y-262688D01*
X512704Y-262662D01*
X512638Y-262637D01*
X512584Y-262608D01*
X512562Y-262597D01*
X512544Y-262582D01*
X512529Y-262575D01*
X512518Y-262568D01*
X512515Y-262560D01*
X512511D01*
X512445Y-262502D01*
X512391Y-262433D01*
X512344Y-262364D01*
X512307Y-262298D01*
X512278Y-262236D01*
X512263Y-262211D01*
X512256Y-262185D01*
X512249Y-262167D01*
X512242Y-262153D01*
X512238Y-262145D01*
Y-262142D01*
X512223Y-262087D01*
X512209Y-262033D01*
X512187Y-261912D01*
X512169Y-261792D01*
X512158Y-261680D01*
X512154Y-261625D01*
X512151Y-261578D01*
Y-261534D01*
X512147Y-261494D01*
Y-261465D01*
Y-261439D01*
Y-261425D01*
Y-261421D01*
X512151Y-261294D01*
X512158Y-261174D01*
X512169Y-261064D01*
X512187Y-260962D01*
X512205Y-260868D01*
X512227Y-260784D01*
X512249Y-260708D01*
X512271Y-260642D01*
X512293Y-260584D01*
X512318Y-260533D01*
X512336Y-260489D01*
X512355Y-260456D01*
X512373Y-260427D01*
X512384Y-260409D01*
X512391Y-260398D01*
X512395Y-260395D01*
X512435Y-260351D01*
X512478Y-260311D01*
X512526Y-260274D01*
X512573Y-260245D01*
X512620Y-260220D01*
X512668Y-260198D01*
X512715Y-260183D01*
X512759Y-260169D01*
X512802Y-260158D01*
X512842Y-260151D01*
X512879Y-260143D01*
X512908Y-260140D01*
X512933Y-260136D01*
X512970D01*
X513068Y-260143D01*
D02*
G37*
G36*
X490525Y-257276D02*
X490624Y-257295D01*
X490707Y-257324D01*
X490780Y-257353D01*
X490813Y-257371D01*
X490838Y-257386D01*
X490864Y-257400D01*
X490882Y-257415D01*
X490897Y-257426D01*
X490907Y-257433D01*
X490915Y-257436D01*
X490918Y-257440D01*
X490988Y-257509D01*
X491042Y-257586D01*
X491086Y-257666D01*
X491122Y-257746D01*
X491144Y-257815D01*
X491155Y-257844D01*
X491162Y-257870D01*
X491166Y-257892D01*
X491170Y-257906D01*
X491173Y-257917D01*
Y-257921D01*
X490864Y-257975D01*
X490849Y-257895D01*
X490827Y-257826D01*
X490802Y-257768D01*
X490776Y-257720D01*
X490751Y-257684D01*
X490729Y-257659D01*
X490715Y-257640D01*
X490711Y-257637D01*
X490664Y-257600D01*
X490613Y-257571D01*
X490565Y-257553D01*
X490518Y-257539D01*
X490474Y-257531D01*
X490442Y-257524D01*
X490412D01*
X490347Y-257527D01*
X490289Y-257542D01*
X490238Y-257560D01*
X490194Y-257578D01*
X490161Y-257600D01*
X490136Y-257618D01*
X490118Y-257633D01*
X490114Y-257637D01*
X490074Y-257680D01*
X490045Y-257728D01*
X490027Y-257775D01*
X490012Y-257819D01*
X490005Y-257859D01*
X489997Y-257888D01*
Y-257910D01*
Y-257913D01*
Y-257917D01*
Y-257957D01*
X490005Y-257993D01*
X490023Y-258055D01*
X490048Y-258110D01*
X490078Y-258157D01*
X490107Y-258190D01*
X490132Y-258215D01*
X490150Y-258230D01*
X490154Y-258234D01*
X490158D01*
X490219Y-258266D01*
X490278Y-258292D01*
X490340Y-258310D01*
X490394Y-258321D01*
X490442Y-258328D01*
X490482Y-258336D01*
X490529D01*
X490544Y-258332D01*
X490562D01*
X490598Y-258605D01*
X490551Y-258594D01*
X490507Y-258587D01*
X490471Y-258579D01*
X490438Y-258576D01*
X490412Y-258572D01*
X490380D01*
X490303Y-258579D01*
X490234Y-258594D01*
X490172Y-258616D01*
X490121Y-258641D01*
X490081Y-258667D01*
X490052Y-258689D01*
X490034Y-258703D01*
X490027Y-258711D01*
X489979Y-258765D01*
X489943Y-258823D01*
X489917Y-258882D01*
X489903Y-258940D01*
X489892Y-258987D01*
X489888Y-259027D01*
X489885Y-259042D01*
Y-259053D01*
Y-259060D01*
Y-259064D01*
X489892Y-259144D01*
X489910Y-259216D01*
X489932Y-259278D01*
X489961Y-259333D01*
X489990Y-259377D01*
X490012Y-259409D01*
X490030Y-259431D01*
X490037Y-259438D01*
X490096Y-259489D01*
X490158Y-259526D01*
X490219Y-259551D01*
X490278Y-259570D01*
X490329Y-259580D01*
X490369Y-259584D01*
X490383Y-259588D01*
X490405D01*
X490471Y-259584D01*
X490533Y-259570D01*
X490587Y-259551D01*
X490631Y-259529D01*
X490667Y-259511D01*
X490696Y-259493D01*
X490711Y-259479D01*
X490718Y-259475D01*
X490762Y-259424D01*
X490798Y-259366D01*
X490831Y-259304D01*
X490857Y-259238D01*
X490875Y-259184D01*
X490882Y-259158D01*
X490886Y-259136D01*
X490889Y-259118D01*
X490893Y-259104D01*
X490897Y-259096D01*
Y-259093D01*
X491206Y-259133D01*
X491199Y-259191D01*
X491188Y-259246D01*
X491155Y-259348D01*
X491115Y-259435D01*
X491093Y-259471D01*
X491071Y-259508D01*
X491049Y-259541D01*
X491028Y-259566D01*
X491009Y-259591D01*
X490991Y-259610D01*
X490980Y-259624D01*
X490969Y-259635D01*
X490962Y-259642D01*
X490958Y-259646D01*
X490915Y-259679D01*
X490871Y-259712D01*
X490827Y-259737D01*
X490780Y-259759D01*
X490689Y-259795D01*
X490602Y-259817D01*
X490562Y-259824D01*
X490525Y-259832D01*
X490492Y-259835D01*
X490463Y-259839D01*
X490442Y-259843D01*
X490409D01*
X490340Y-259839D01*
X490278Y-259832D01*
X490216Y-259821D01*
X490158Y-259806D01*
X490103Y-259788D01*
X490056Y-259770D01*
X490008Y-259748D01*
X489968Y-259726D01*
X489928Y-259708D01*
X489896Y-259686D01*
X489866Y-259668D01*
X489845Y-259650D01*
X489826Y-259635D01*
X489812Y-259624D01*
X489805Y-259617D01*
X489801Y-259613D01*
X489757Y-259570D01*
X489721Y-259522D01*
X489688Y-259475D01*
X489659Y-259428D01*
X489637Y-259384D01*
X489615Y-259337D01*
X489586Y-259249D01*
X489579Y-259209D01*
X489572Y-259173D01*
X489564Y-259140D01*
X489561Y-259111D01*
X489557Y-259089D01*
Y-259071D01*
Y-259060D01*
Y-259056D01*
X489561Y-258969D01*
X489575Y-258889D01*
X489597Y-258820D01*
X489619Y-258762D01*
X489641Y-258714D01*
X489663Y-258678D01*
X489677Y-258656D01*
X489681Y-258649D01*
X489732Y-258594D01*
X489786Y-258547D01*
X489845Y-258510D01*
X489903Y-258481D01*
X489954Y-258459D01*
X489994Y-258445D01*
X490008Y-258441D01*
X490019Y-258437D01*
X490027Y-258434D01*
X490030D01*
X489968Y-258401D01*
X489917Y-258368D01*
X489874Y-258332D01*
X489837Y-258299D01*
X489808Y-258270D01*
X489786Y-258245D01*
X489776Y-258230D01*
X489772Y-258223D01*
X489743Y-258172D01*
X489721Y-258121D01*
X489703Y-258070D01*
X489692Y-258023D01*
X489684Y-257982D01*
X489681Y-257953D01*
Y-257932D01*
Y-257924D01*
X489684Y-257862D01*
X489695Y-257801D01*
X489710Y-257746D01*
X489728Y-257699D01*
X489746Y-257659D01*
X489761Y-257626D01*
X489772Y-257608D01*
X489776Y-257600D01*
X489812Y-257546D01*
X489855Y-257498D01*
X489899Y-257458D01*
X489943Y-257422D01*
X489979Y-257397D01*
X490012Y-257375D01*
X490034Y-257364D01*
X490037Y-257360D01*
X490041D01*
X490107Y-257331D01*
X490172Y-257309D01*
X490238Y-257291D01*
X490296Y-257280D01*
X490343Y-257273D01*
X490383Y-257269D01*
X490474D01*
X490525Y-257276D01*
D02*
G37*
G36*
X494198Y-257331D02*
X494238Y-257389D01*
X494285Y-257447D01*
X494329Y-257498D01*
X494373Y-257542D01*
X494406Y-257578D01*
X494420Y-257589D01*
X494431Y-257600D01*
X494435Y-257604D01*
X494438Y-257608D01*
X494515Y-257669D01*
X494591Y-257728D01*
X494664Y-257779D01*
X494737Y-257819D01*
X494799Y-257855D01*
X494824Y-257870D01*
X494846Y-257881D01*
X494864Y-257892D01*
X494879Y-257895D01*
X494886Y-257902D01*
X494890D01*
Y-258201D01*
X494835Y-258179D01*
X494780Y-258154D01*
X494726Y-258128D01*
X494675Y-258103D01*
X494631Y-258081D01*
X494595Y-258063D01*
X494573Y-258048D01*
X494569Y-258044D01*
X494566D01*
X494500Y-258004D01*
X494442Y-257964D01*
X494391Y-257928D01*
X494351Y-257895D01*
X494314Y-257870D01*
X494293Y-257848D01*
X494275Y-257833D01*
X494271Y-257830D01*
Y-259799D01*
X493961D01*
Y-257269D01*
X494162D01*
X494198Y-257331D01*
D02*
G37*
G36*
X496571Y-257244D02*
X496688Y-257262D01*
X496790Y-257284D01*
X496837Y-257298D01*
X496881Y-257313D01*
X496921Y-257327D01*
X496957Y-257342D01*
X496986Y-257353D01*
X497015Y-257364D01*
X497034Y-257375D01*
X497048Y-257382D01*
X497059Y-257386D01*
X497063Y-257389D01*
X497161Y-257451D01*
X497245Y-257524D01*
X497318Y-257597D01*
X497379Y-257669D01*
X497427Y-257735D01*
X497445Y-257764D01*
X497460Y-257790D01*
X497474Y-257808D01*
X497481Y-257822D01*
X497485Y-257833D01*
X497489Y-257837D01*
X497540Y-257950D01*
X497576Y-258066D01*
X497602Y-258183D01*
X497620Y-258288D01*
X497627Y-258336D01*
X497631Y-258383D01*
X497634Y-258419D01*
Y-258456D01*
X497638Y-258481D01*
Y-258503D01*
Y-258518D01*
Y-258521D01*
X497631Y-258652D01*
X497616Y-258780D01*
X497598Y-258892D01*
X497583Y-258947D01*
X497572Y-258995D01*
X497561Y-259038D01*
X497547Y-259078D01*
X497536Y-259115D01*
X497529Y-259144D01*
X497518Y-259166D01*
X497514Y-259184D01*
X497507Y-259195D01*
Y-259198D01*
X497452Y-259308D01*
X497390Y-259406D01*
X497325Y-259489D01*
X497292Y-259522D01*
X497263Y-259555D01*
X497234Y-259584D01*
X497205Y-259610D01*
X497179Y-259631D01*
X497157Y-259646D01*
X497143Y-259661D01*
X497128Y-259671D01*
X497121Y-259675D01*
X497117Y-259679D01*
X497066Y-259708D01*
X497015Y-259733D01*
X496906Y-259773D01*
X496797Y-259803D01*
X496691Y-259821D01*
X496640Y-259828D01*
X496597Y-259835D01*
X496557Y-259839D01*
X496524D01*
X496495Y-259843D01*
X496455D01*
X496382Y-259839D01*
X496313Y-259832D01*
X496247Y-259824D01*
X496185Y-259810D01*
X496127Y-259792D01*
X496073Y-259773D01*
X496022Y-259755D01*
X495974Y-259733D01*
X495934Y-259715D01*
X495894Y-259697D01*
X495865Y-259679D01*
X495836Y-259661D01*
X495818Y-259646D01*
X495800Y-259639D01*
X495792Y-259631D01*
X495789Y-259628D01*
X495738Y-259584D01*
X495694Y-259541D01*
X495654Y-259489D01*
X495614Y-259438D01*
X495548Y-259337D01*
X495498Y-259235D01*
X495476Y-259187D01*
X495458Y-259144D01*
X495443Y-259104D01*
X495432Y-259071D01*
X495421Y-259042D01*
X495414Y-259020D01*
X495410Y-259005D01*
Y-259002D01*
X495745Y-258918D01*
X495760Y-258976D01*
X495778Y-259031D01*
X495796Y-259082D01*
X495814Y-259129D01*
X495836Y-259173D01*
X495858Y-259209D01*
X495883Y-259246D01*
X495905Y-259278D01*
X495923Y-259308D01*
X495945Y-259329D01*
X495963Y-259351D01*
X495978Y-259369D01*
X495993Y-259380D01*
X496003Y-259391D01*
X496007Y-259395D01*
X496011Y-259399D01*
X496047Y-259428D01*
X496087Y-259449D01*
X496167Y-259489D01*
X496244Y-259519D01*
X496320Y-259537D01*
X496386Y-259551D01*
X496411Y-259555D01*
X496437D01*
X496458Y-259559D01*
X496484D01*
X496568Y-259555D01*
X496648Y-259541D01*
X496721Y-259522D01*
X496786Y-259500D01*
X496837Y-259479D01*
X496859Y-259468D01*
X496877Y-259460D01*
X496892Y-259453D01*
X496903Y-259446D01*
X496910Y-259442D01*
X496913D01*
X496983Y-259391D01*
X497041Y-259337D01*
X497092Y-259275D01*
X497132Y-259216D01*
X497165Y-259166D01*
X497187Y-259122D01*
X497194Y-259104D01*
X497201Y-259093D01*
X497205Y-259085D01*
Y-259082D01*
X497234Y-258987D01*
X497256Y-258892D01*
X497274Y-258798D01*
X497285Y-258711D01*
X497288Y-258670D01*
X497292Y-258634D01*
Y-258601D01*
X497296Y-258576D01*
Y-258554D01*
Y-258536D01*
Y-258525D01*
Y-258521D01*
X497292Y-258427D01*
X497285Y-258339D01*
X497270Y-258259D01*
X497256Y-258186D01*
X497245Y-258124D01*
X497237Y-258099D01*
X497230Y-258077D01*
X497226Y-258059D01*
X497223Y-258048D01*
X497219Y-258041D01*
Y-258037D01*
X497183Y-257953D01*
X497143Y-257877D01*
X497099Y-257815D01*
X497052Y-257761D01*
X497012Y-257717D01*
X496979Y-257688D01*
X496953Y-257669D01*
X496950Y-257662D01*
X496946D01*
X496870Y-257615D01*
X496786Y-257578D01*
X496706Y-257553D01*
X496630Y-257539D01*
X496560Y-257527D01*
X496531Y-257524D01*
X496506D01*
X496488Y-257520D01*
X496458D01*
X496368Y-257524D01*
X496284Y-257539D01*
X496215Y-257560D01*
X496153Y-257582D01*
X496105Y-257608D01*
X496069Y-257626D01*
X496047Y-257640D01*
X496040Y-257648D01*
X495982Y-257702D01*
X495927Y-257764D01*
X495883Y-257830D01*
X495847Y-257895D01*
X495818Y-257953D01*
X495807Y-257982D01*
X495800Y-258004D01*
X495792Y-258023D01*
X495785Y-258037D01*
X495782Y-258044D01*
Y-258048D01*
X495454Y-257972D01*
X495476Y-257906D01*
X495498Y-257848D01*
X495527Y-257793D01*
X495552Y-257739D01*
X495581Y-257691D01*
X495614Y-257648D01*
X495643Y-257604D01*
X495672Y-257568D01*
X495701Y-257539D01*
X495727Y-257509D01*
X495752Y-257484D01*
X495771Y-257466D01*
X495789Y-257447D01*
X495803Y-257436D01*
X495811Y-257433D01*
X495814Y-257429D01*
X495865Y-257397D01*
X495916Y-257364D01*
X495967Y-257338D01*
X496022Y-257316D01*
X496131Y-257284D01*
X496229Y-257262D01*
X496277Y-257251D01*
X496316Y-257247D01*
X496357Y-257244D01*
X496389Y-257240D01*
X496415Y-257236D01*
X496451D01*
X496571Y-257244D01*
D02*
G37*
G36*
X492444Y-257276D02*
X492535Y-257291D01*
X492611Y-257316D01*
X492676Y-257342D01*
X492731Y-257371D01*
X492753Y-257382D01*
X492771Y-257397D01*
X492786Y-257404D01*
X492797Y-257411D01*
X492800Y-257418D01*
X492804D01*
X492869Y-257477D01*
X492924Y-257546D01*
X492971Y-257615D01*
X493008Y-257680D01*
X493037Y-257742D01*
X493051Y-257768D01*
X493059Y-257793D01*
X493066Y-257811D01*
X493073Y-257826D01*
X493077Y-257833D01*
Y-257837D01*
X493091Y-257892D01*
X493106Y-257946D01*
X493128Y-258066D01*
X493146Y-258186D01*
X493157Y-258299D01*
X493161Y-258354D01*
X493164Y-258401D01*
Y-258445D01*
X493168Y-258485D01*
Y-258514D01*
Y-258539D01*
Y-258554D01*
Y-258558D01*
X493164Y-258685D01*
X493157Y-258805D01*
X493146Y-258914D01*
X493128Y-259016D01*
X493110Y-259111D01*
X493088Y-259195D01*
X493066Y-259271D01*
X493044Y-259337D01*
X493022Y-259395D01*
X492997Y-259446D01*
X492979Y-259489D01*
X492961Y-259522D01*
X492942Y-259551D01*
X492931Y-259570D01*
X492924Y-259580D01*
X492920Y-259584D01*
X492880Y-259628D01*
X492837Y-259668D01*
X492789Y-259704D01*
X492742Y-259733D01*
X492695Y-259759D01*
X492647Y-259781D01*
X492600Y-259795D01*
X492556Y-259810D01*
X492513Y-259821D01*
X492473Y-259828D01*
X492436Y-259835D01*
X492407Y-259839D01*
X492382Y-259843D01*
X492345D01*
X492247Y-259835D01*
X492156Y-259821D01*
X492080Y-259795D01*
X492014Y-259770D01*
X491959Y-259744D01*
X491941Y-259730D01*
X491923Y-259719D01*
X491909Y-259712D01*
X491898Y-259704D01*
X491894Y-259697D01*
X491890D01*
X491825Y-259635D01*
X491770Y-259570D01*
X491723Y-259497D01*
X491686Y-259431D01*
X491657Y-259369D01*
X491643Y-259344D01*
X491636Y-259318D01*
X491628Y-259300D01*
X491621Y-259286D01*
X491617Y-259278D01*
Y-259275D01*
X491599Y-259220D01*
X491584Y-259166D01*
X491563Y-259049D01*
X491544Y-258929D01*
X491534Y-258812D01*
X491530Y-258762D01*
X491526Y-258714D01*
Y-258670D01*
X491523Y-258630D01*
Y-258601D01*
Y-258576D01*
Y-258561D01*
Y-258558D01*
Y-258488D01*
X491526Y-258423D01*
Y-258365D01*
X491530Y-258307D01*
X491537Y-258256D01*
X491541Y-258205D01*
X491544Y-258161D01*
X491552Y-258121D01*
X491555Y-258085D01*
X491563Y-258052D01*
X491566Y-258026D01*
X491570Y-258004D01*
X491574Y-257986D01*
X491577Y-257975D01*
X491581Y-257968D01*
Y-257964D01*
X491603Y-257884D01*
X491628Y-257811D01*
X491657Y-257750D01*
X491679Y-257695D01*
X491705Y-257648D01*
X491719Y-257615D01*
X491734Y-257597D01*
X491737Y-257589D01*
X491778Y-257535D01*
X491818Y-257488D01*
X491861Y-257447D01*
X491901Y-257411D01*
X491938Y-257386D01*
X491967Y-257367D01*
X491985Y-257356D01*
X491989Y-257353D01*
X491992D01*
X492051Y-257324D01*
X492112Y-257306D01*
X492171Y-257291D01*
X492225Y-257280D01*
X492273Y-257273D01*
X492312Y-257269D01*
X492345D01*
X492444Y-257276D01*
D02*
G37*
G36*
X562505Y-258608D02*
X562545Y-258666D01*
X562593Y-258724D01*
X562636Y-258775D01*
X562680Y-258819D01*
X562713Y-258855D01*
X562727Y-258866D01*
X562738Y-258877D01*
X562742Y-258881D01*
X562745Y-258884D01*
X562822Y-258946D01*
X562898Y-259004D01*
X562971Y-259055D01*
X563044Y-259096D01*
X563106Y-259132D01*
X563131Y-259146D01*
X563153Y-259157D01*
X563171Y-259168D01*
X563186Y-259172D01*
X563193Y-259179D01*
X563197D01*
Y-259478D01*
X563142Y-259456D01*
X563088Y-259430D01*
X563033Y-259405D01*
X562982Y-259379D01*
X562938Y-259358D01*
X562902Y-259339D01*
X562880Y-259325D01*
X562876Y-259321D01*
X562873D01*
X562807Y-259281D01*
X562749Y-259241D01*
X562698Y-259205D01*
X562658Y-259172D01*
X562622Y-259146D01*
X562600Y-259125D01*
X562582Y-259110D01*
X562578Y-259106D01*
Y-261076D01*
X562268D01*
Y-258546D01*
X562469D01*
X562505Y-258608D01*
D02*
G37*
G36*
X564878Y-258520D02*
X564995Y-258539D01*
X565097Y-258560D01*
X565144Y-258575D01*
X565188Y-258590D01*
X565228Y-258604D01*
X565264Y-258619D01*
X565293Y-258630D01*
X565322Y-258641D01*
X565341Y-258651D01*
X565355Y-258659D01*
X565366Y-258662D01*
X565370Y-258666D01*
X565468Y-258728D01*
X565552Y-258801D01*
X565625Y-258874D01*
X565687Y-258946D01*
X565734Y-259012D01*
X565752Y-259041D01*
X565767Y-259066D01*
X565781Y-259085D01*
X565788Y-259099D01*
X565792Y-259110D01*
X565796Y-259114D01*
X565847Y-259226D01*
X565883Y-259343D01*
X565908Y-259459D01*
X565927Y-259565D01*
X565934Y-259612D01*
X565938Y-259660D01*
X565941Y-259696D01*
Y-259733D01*
X565945Y-259758D01*
Y-259780D01*
Y-259794D01*
Y-259798D01*
X565938Y-259929D01*
X565923Y-260056D01*
X565905Y-260169D01*
X565890Y-260224D01*
X565879Y-260271D01*
X565869Y-260315D01*
X565854Y-260355D01*
X565843Y-260391D01*
X565836Y-260420D01*
X565825Y-260442D01*
X565821Y-260460D01*
X565814Y-260471D01*
Y-260475D01*
X565759Y-260584D01*
X565697Y-260683D01*
X565632Y-260766D01*
X565599Y-260799D01*
X565570Y-260832D01*
X565541Y-260861D01*
X565512Y-260886D01*
X565486Y-260908D01*
X565464Y-260923D01*
X565450Y-260937D01*
X565435Y-260948D01*
X565428Y-260952D01*
X565424Y-260956D01*
X565373Y-260985D01*
X565322Y-261010D01*
X565213Y-261050D01*
X565104Y-261079D01*
X564998Y-261098D01*
X564948Y-261105D01*
X564904Y-261112D01*
X564864Y-261116D01*
X564831D01*
X564802Y-261119D01*
X564762D01*
X564689Y-261116D01*
X564620Y-261108D01*
X564554Y-261101D01*
X564493Y-261087D01*
X564434Y-261068D01*
X564380Y-261050D01*
X564329Y-261032D01*
X564282Y-261010D01*
X564241Y-260992D01*
X564201Y-260974D01*
X564172Y-260956D01*
X564143Y-260937D01*
X564125Y-260923D01*
X564107Y-260915D01*
X564099Y-260908D01*
X564096Y-260905D01*
X564045Y-260861D01*
X564001Y-260817D01*
X563961Y-260766D01*
X563921Y-260715D01*
X563856Y-260613D01*
X563805Y-260511D01*
X563783Y-260464D01*
X563765Y-260420D01*
X563750Y-260380D01*
X563739Y-260348D01*
X563728Y-260318D01*
X563721Y-260297D01*
X563717Y-260282D01*
Y-260279D01*
X564052Y-260195D01*
X564067Y-260253D01*
X564085Y-260308D01*
X564103Y-260359D01*
X564121Y-260406D01*
X564143Y-260450D01*
X564165Y-260486D01*
X564190Y-260522D01*
X564212Y-260555D01*
X564230Y-260584D01*
X564252Y-260606D01*
X564270Y-260628D01*
X564285Y-260646D01*
X564300Y-260657D01*
X564311Y-260668D01*
X564314Y-260672D01*
X564318Y-260675D01*
X564354Y-260704D01*
X564394Y-260726D01*
X564474Y-260766D01*
X564551Y-260795D01*
X564627Y-260814D01*
X564693Y-260828D01*
X564718Y-260832D01*
X564744D01*
X564766Y-260835D01*
X564791D01*
X564875Y-260832D01*
X564955Y-260817D01*
X565028Y-260799D01*
X565093Y-260777D01*
X565144Y-260755D01*
X565166Y-260744D01*
X565184Y-260737D01*
X565199Y-260730D01*
X565210Y-260723D01*
X565217Y-260719D01*
X565221D01*
X565290Y-260668D01*
X565348Y-260613D01*
X565399Y-260552D01*
X565439Y-260493D01*
X565472Y-260442D01*
X565494Y-260399D01*
X565501Y-260380D01*
X565508Y-260369D01*
X565512Y-260362D01*
Y-260359D01*
X565541Y-260264D01*
X565563Y-260169D01*
X565581Y-260075D01*
X565592Y-259987D01*
X565595Y-259947D01*
X565599Y-259911D01*
Y-259878D01*
X565603Y-259853D01*
Y-259831D01*
Y-259813D01*
Y-259802D01*
Y-259798D01*
X565599Y-259703D01*
X565592Y-259616D01*
X565577Y-259536D01*
X565563Y-259463D01*
X565552Y-259401D01*
X565545Y-259376D01*
X565537Y-259354D01*
X565534Y-259336D01*
X565530Y-259325D01*
X565526Y-259317D01*
Y-259314D01*
X565490Y-259230D01*
X565450Y-259154D01*
X565406Y-259092D01*
X565359Y-259037D01*
X565319Y-258994D01*
X565286Y-258964D01*
X565261Y-258946D01*
X565257Y-258939D01*
X565253D01*
X565177Y-258892D01*
X565093Y-258855D01*
X565013Y-258830D01*
X564937Y-258815D01*
X564867Y-258804D01*
X564838Y-258801D01*
X564813D01*
X564795Y-258797D01*
X564766D01*
X564675Y-258801D01*
X564591Y-258815D01*
X564522Y-258837D01*
X564460Y-258859D01*
X564412Y-258884D01*
X564376Y-258903D01*
X564354Y-258917D01*
X564347Y-258924D01*
X564289Y-258979D01*
X564234Y-259041D01*
X564190Y-259106D01*
X564154Y-259172D01*
X564125Y-259230D01*
X564114Y-259259D01*
X564107Y-259281D01*
X564099Y-259299D01*
X564092Y-259314D01*
X564088Y-259321D01*
Y-259325D01*
X563761Y-259248D01*
X563783Y-259183D01*
X563805Y-259125D01*
X563834Y-259070D01*
X563859Y-259015D01*
X563888Y-258968D01*
X563921Y-258924D01*
X563950Y-258881D01*
X563979Y-258844D01*
X564008Y-258815D01*
X564034Y-258786D01*
X564059Y-258761D01*
X564078Y-258742D01*
X564096Y-258724D01*
X564110Y-258713D01*
X564118Y-258710D01*
X564121Y-258706D01*
X564172Y-258673D01*
X564223Y-258641D01*
X564274Y-258615D01*
X564329Y-258593D01*
X564438Y-258560D01*
X564536Y-258539D01*
X564584Y-258528D01*
X564624Y-258524D01*
X564664Y-258520D01*
X564696Y-258517D01*
X564722Y-258513D01*
X564758D01*
X564878Y-258520D01*
D02*
G37*
G36*
X559622Y-260188D02*
Y-260471D01*
X558527D01*
Y-261076D01*
X558217D01*
Y-260471D01*
X557875D01*
Y-260188D01*
X558217D01*
Y-258557D01*
X558468D01*
X559622Y-260188D01*
D02*
G37*
G36*
X560751Y-258553D02*
X560842Y-258568D01*
X560918Y-258593D01*
X560984Y-258619D01*
X561038Y-258648D01*
X561060Y-258659D01*
X561078Y-258673D01*
X561093Y-258681D01*
X561104Y-258688D01*
X561107Y-258695D01*
X561111D01*
X561176Y-258753D01*
X561231Y-258822D01*
X561278Y-258892D01*
X561315Y-258957D01*
X561344Y-259019D01*
X561358Y-259045D01*
X561366Y-259070D01*
X561373Y-259088D01*
X561380Y-259103D01*
X561384Y-259110D01*
Y-259114D01*
X561399Y-259168D01*
X561413Y-259223D01*
X561435Y-259343D01*
X561453Y-259463D01*
X561464Y-259576D01*
X561468Y-259631D01*
X561471Y-259678D01*
Y-259722D01*
X561475Y-259762D01*
Y-259791D01*
Y-259816D01*
Y-259831D01*
Y-259834D01*
X561471Y-259962D01*
X561464Y-260082D01*
X561453Y-260191D01*
X561435Y-260293D01*
X561417Y-260388D01*
X561395Y-260471D01*
X561373Y-260548D01*
X561351Y-260613D01*
X561329Y-260672D01*
X561304Y-260723D01*
X561286Y-260766D01*
X561268Y-260799D01*
X561249Y-260828D01*
X561238Y-260846D01*
X561231Y-260857D01*
X561228Y-260861D01*
X561187Y-260905D01*
X561144Y-260945D01*
X561096Y-260981D01*
X561049Y-261010D01*
X561002Y-261036D01*
X560955Y-261057D01*
X560907Y-261072D01*
X560863Y-261087D01*
X560820Y-261098D01*
X560780Y-261105D01*
X560743Y-261112D01*
X560714Y-261116D01*
X560689Y-261119D01*
X560652D01*
X560554Y-261112D01*
X560463Y-261098D01*
X560387Y-261072D01*
X560321Y-261047D01*
X560266Y-261021D01*
X560248Y-261006D01*
X560230Y-260996D01*
X560216Y-260988D01*
X560205Y-260981D01*
X560201Y-260974D01*
X560197D01*
X560132Y-260912D01*
X560077Y-260846D01*
X560030Y-260773D01*
X559994Y-260708D01*
X559964Y-260646D01*
X559950Y-260621D01*
X559943Y-260595D01*
X559935Y-260577D01*
X559928Y-260562D01*
X559924Y-260555D01*
Y-260552D01*
X559906Y-260497D01*
X559892Y-260442D01*
X559870Y-260326D01*
X559852Y-260206D01*
X559841Y-260089D01*
X559837Y-260038D01*
X559833Y-259991D01*
Y-259947D01*
X559830Y-259907D01*
Y-259878D01*
Y-259853D01*
Y-259838D01*
Y-259834D01*
Y-259765D01*
X559833Y-259700D01*
Y-259642D01*
X559837Y-259583D01*
X559844Y-259532D01*
X559848Y-259481D01*
X559852Y-259438D01*
X559859Y-259398D01*
X559863Y-259361D01*
X559870Y-259329D01*
X559873Y-259303D01*
X559877Y-259281D01*
X559881Y-259263D01*
X559884Y-259252D01*
X559888Y-259245D01*
Y-259241D01*
X559910Y-259161D01*
X559935Y-259088D01*
X559964Y-259026D01*
X559986Y-258972D01*
X560012Y-258924D01*
X560026Y-258892D01*
X560041Y-258874D01*
X560044Y-258866D01*
X560084Y-258812D01*
X560125Y-258764D01*
X560168Y-258724D01*
X560208Y-258688D01*
X560245Y-258662D01*
X560274Y-258644D01*
X560292Y-258633D01*
X560296Y-258630D01*
X560299D01*
X560358Y-258600D01*
X560419Y-258582D01*
X560478Y-258568D01*
X560532Y-258557D01*
X560580Y-258549D01*
X560620Y-258546D01*
X560652D01*
X560751Y-258553D01*
D02*
G37*
G36*
X574582Y-261126D02*
X574652Y-261133D01*
X574717Y-261140D01*
X574779Y-261155D01*
X574837Y-261173D01*
X574892Y-261191D01*
X574943Y-261209D01*
X574990Y-261231D01*
X575030Y-261249D01*
X575070Y-261268D01*
X575099Y-261286D01*
X575129Y-261304D01*
X575147Y-261319D01*
X575165Y-261326D01*
X575172Y-261333D01*
X575176Y-261337D01*
X575227Y-261381D01*
X575271Y-261424D01*
X575311Y-261475D01*
X575351Y-261526D01*
X575416Y-261628D01*
X575467Y-261730D01*
X575489Y-261777D01*
X575507Y-261821D01*
X575522Y-261861D01*
X575532Y-261894D01*
X575543Y-261923D01*
X575551Y-261945D01*
X575554Y-261959D01*
Y-261963D01*
X575219Y-262047D01*
X575205Y-261988D01*
X575187Y-261934D01*
X575169Y-261883D01*
X575150Y-261835D01*
X575129Y-261792D01*
X575107Y-261755D01*
X575081Y-261719D01*
X575059Y-261686D01*
X575041Y-261657D01*
X575019Y-261635D01*
X575001Y-261613D01*
X574987Y-261595D01*
X574972Y-261584D01*
X574961Y-261573D01*
X574957Y-261570D01*
X574954Y-261566D01*
X574917Y-261537D01*
X574877Y-261515D01*
X574797Y-261475D01*
X574721Y-261446D01*
X574644Y-261428D01*
X574579Y-261413D01*
X574553Y-261410D01*
X574528D01*
X574506Y-261406D01*
X574481D01*
X574397Y-261410D01*
X574317Y-261424D01*
X574244Y-261442D01*
X574179Y-261464D01*
X574127Y-261486D01*
X574106Y-261497D01*
X574087Y-261504D01*
X574073Y-261511D01*
X574062Y-261519D01*
X574055Y-261522D01*
X574051D01*
X573982Y-261573D01*
X573924Y-261628D01*
X573873Y-261690D01*
X573833Y-261748D01*
X573800Y-261799D01*
X573778Y-261843D01*
X573771Y-261861D01*
X573764Y-261872D01*
X573760Y-261879D01*
Y-261883D01*
X573731Y-261977D01*
X573709Y-262072D01*
X573691Y-262167D01*
X573680Y-262254D01*
X573676Y-262294D01*
X573672Y-262331D01*
Y-262363D01*
X573669Y-262389D01*
Y-262411D01*
Y-262429D01*
Y-262440D01*
Y-262443D01*
X573672Y-262538D01*
X573680Y-262625D01*
X573694Y-262705D01*
X573709Y-262778D01*
X573720Y-262840D01*
X573727Y-262866D01*
X573734Y-262887D01*
X573738Y-262906D01*
X573742Y-262916D01*
X573745Y-262924D01*
Y-262927D01*
X573782Y-263011D01*
X573822Y-263088D01*
X573865Y-263149D01*
X573913Y-263204D01*
X573953Y-263248D01*
X573985Y-263277D01*
X574011Y-263295D01*
X574015Y-263302D01*
X574018D01*
X574095Y-263350D01*
X574179Y-263386D01*
X574259Y-263412D01*
X574335Y-263426D01*
X574404Y-263437D01*
X574433Y-263441D01*
X574459D01*
X574477Y-263444D01*
X574506D01*
X574597Y-263441D01*
X574681Y-263426D01*
X574750Y-263404D01*
X574812Y-263383D01*
X574859Y-263357D01*
X574895Y-263339D01*
X574917Y-263324D01*
X574925Y-263317D01*
X574983Y-263262D01*
X575037Y-263200D01*
X575081Y-263135D01*
X575118Y-263069D01*
X575147Y-263011D01*
X575158Y-262982D01*
X575165Y-262960D01*
X575172Y-262942D01*
X575179Y-262927D01*
X575183Y-262920D01*
Y-262916D01*
X575511Y-262993D01*
X575489Y-263058D01*
X575467Y-263117D01*
X575438Y-263171D01*
X575412Y-263226D01*
X575383Y-263273D01*
X575351Y-263317D01*
X575321Y-263361D01*
X575292Y-263397D01*
X575263Y-263426D01*
X575238Y-263455D01*
X575212Y-263481D01*
X575194Y-263499D01*
X575176Y-263517D01*
X575161Y-263528D01*
X575154Y-263532D01*
X575150Y-263535D01*
X575099Y-263568D01*
X575048Y-263601D01*
X574998Y-263626D01*
X574943Y-263648D01*
X574834Y-263681D01*
X574735Y-263703D01*
X574688Y-263714D01*
X574648Y-263717D01*
X574608Y-263721D01*
X574575Y-263725D01*
X574550Y-263728D01*
X574513D01*
X574393Y-263721D01*
X574277Y-263703D01*
X574175Y-263681D01*
X574127Y-263666D01*
X574084Y-263652D01*
X574044Y-263637D01*
X574007Y-263623D01*
X573978Y-263612D01*
X573949Y-263601D01*
X573931Y-263590D01*
X573916Y-263583D01*
X573906Y-263579D01*
X573902Y-263575D01*
X573804Y-263513D01*
X573720Y-263441D01*
X573647Y-263368D01*
X573585Y-263295D01*
X573538Y-263230D01*
X573520Y-263200D01*
X573505Y-263175D01*
X573490Y-263157D01*
X573483Y-263142D01*
X573480Y-263131D01*
X573476Y-263128D01*
X573425Y-263015D01*
X573389Y-262898D01*
X573363Y-262782D01*
X573345Y-262676D01*
X573338Y-262629D01*
X573334Y-262582D01*
X573330Y-262545D01*
Y-262509D01*
X573327Y-262483D01*
Y-262461D01*
Y-262447D01*
Y-262443D01*
X573334Y-262312D01*
X573349Y-262185D01*
X573367Y-262072D01*
X573381Y-262017D01*
X573392Y-261970D01*
X573403Y-261927D01*
X573418Y-261886D01*
X573429Y-261850D01*
X573436Y-261821D01*
X573447Y-261799D01*
X573451Y-261781D01*
X573458Y-261770D01*
Y-261766D01*
X573512Y-261657D01*
X573574Y-261559D01*
X573640Y-261475D01*
X573672Y-261442D01*
X573702Y-261410D01*
X573731Y-261381D01*
X573760Y-261355D01*
X573785Y-261333D01*
X573807Y-261319D01*
X573822Y-261304D01*
X573836Y-261293D01*
X573844Y-261289D01*
X573847Y-261286D01*
X573898Y-261257D01*
X573949Y-261231D01*
X574058Y-261191D01*
X574167Y-261162D01*
X574273Y-261144D01*
X574324Y-261137D01*
X574368Y-261129D01*
X574408Y-261126D01*
X574440D01*
X574470Y-261122D01*
X574510D01*
X574582Y-261126D01*
D02*
G37*
G36*
X580640D02*
X580712Y-261137D01*
X580781Y-261151D01*
X580843Y-261169D01*
X580901Y-261195D01*
X580956Y-261220D01*
X581007Y-261246D01*
X581051Y-261275D01*
X581091Y-261304D01*
X581127Y-261330D01*
X581156Y-261359D01*
X581182Y-261381D01*
X581200Y-261399D01*
X581215Y-261413D01*
X581222Y-261424D01*
X581225Y-261428D01*
X581262Y-261475D01*
X581291Y-261526D01*
X581320Y-261573D01*
X581342Y-261624D01*
X581378Y-261723D01*
X581400Y-261817D01*
X581407Y-261857D01*
X581415Y-261897D01*
X581418Y-261930D01*
X581422Y-261959D01*
X581426Y-261985D01*
Y-262003D01*
Y-262014D01*
Y-262017D01*
X581422Y-262083D01*
X581415Y-262145D01*
X581404Y-262207D01*
X581389Y-262261D01*
X581371Y-262312D01*
X581353Y-262363D01*
X581331Y-262407D01*
X581313Y-262447D01*
X581291Y-262483D01*
X581269Y-262516D01*
X581251Y-262542D01*
X581233Y-262567D01*
X581218Y-262585D01*
X581207Y-262596D01*
X581200Y-262603D01*
X581196Y-262607D01*
X581153Y-262647D01*
X581109Y-262684D01*
X581062Y-262713D01*
X581014Y-262738D01*
X580967Y-262764D01*
X580920Y-262782D01*
X580832Y-262807D01*
X580792Y-262818D01*
X580756Y-262825D01*
X580723Y-262829D01*
X580694Y-262833D01*
X580672Y-262837D01*
X580592D01*
X580548Y-262829D01*
X580461Y-262811D01*
X580381Y-262786D01*
X580308Y-262756D01*
X580250Y-262727D01*
X580225Y-262713D01*
X580203Y-262702D01*
X580185Y-262691D01*
X580173Y-262684D01*
X580166Y-262680D01*
X580163Y-262676D01*
X580297Y-263357D01*
X581306D01*
Y-263652D01*
X580053D01*
X579810Y-262356D01*
X580101Y-262316D01*
X580126Y-262356D01*
X580159Y-262389D01*
X580188Y-262421D01*
X580217Y-262447D01*
X580246Y-262465D01*
X580268Y-262483D01*
X580283Y-262491D01*
X580286Y-262494D01*
X580334Y-262516D01*
X580381Y-262534D01*
X580425Y-262545D01*
X580468Y-262556D01*
X580505Y-262560D01*
X580534Y-262563D01*
X580603D01*
X580647Y-262556D01*
X580723Y-262538D01*
X580789Y-262512D01*
X580847Y-262487D01*
X580891Y-262458D01*
X580923Y-262432D01*
X580942Y-262414D01*
X580949Y-262411D01*
Y-262407D01*
X581000Y-262345D01*
X581036Y-262280D01*
X581062Y-262210D01*
X581080Y-262141D01*
X581091Y-262083D01*
X581095Y-262057D01*
Y-262036D01*
X581098Y-262017D01*
Y-262003D01*
Y-261996D01*
Y-261992D01*
Y-261941D01*
X581091Y-261894D01*
X581073Y-261803D01*
X581047Y-261726D01*
X581022Y-261664D01*
X580993Y-261613D01*
X580967Y-261573D01*
X580956Y-261562D01*
X580949Y-261551D01*
X580945Y-261548D01*
X580942Y-261544D01*
X580912Y-261515D01*
X580883Y-261490D01*
X580818Y-261446D01*
X580756Y-261417D01*
X580694Y-261399D01*
X580643Y-261384D01*
X580599Y-261381D01*
X580585Y-261377D01*
X580563D01*
X580494Y-261381D01*
X580432Y-261395D01*
X580377Y-261413D01*
X580334Y-261435D01*
X580294Y-261457D01*
X580265Y-261475D01*
X580250Y-261490D01*
X580243Y-261493D01*
X580199Y-261544D01*
X580163Y-261599D01*
X580133Y-261661D01*
X580112Y-261715D01*
X580097Y-261770D01*
X580086Y-261810D01*
X580083Y-261828D01*
X580079Y-261839D01*
Y-261846D01*
Y-261850D01*
X579755Y-261824D01*
X579762Y-261766D01*
X579773Y-261712D01*
X579806Y-261610D01*
X579846Y-261522D01*
X579868Y-261482D01*
X579890Y-261450D01*
X579908Y-261417D01*
X579930Y-261388D01*
X579948Y-261366D01*
X579966Y-261348D01*
X579981Y-261333D01*
X579988Y-261319D01*
X579995Y-261315D01*
X579999Y-261311D01*
X580043Y-261279D01*
X580086Y-261249D01*
X580133Y-261224D01*
X580181Y-261202D01*
X580272Y-261169D01*
X580363Y-261147D01*
X580403Y-261137D01*
X580443Y-261133D01*
X580476Y-261129D01*
X580505Y-261126D01*
X580530Y-261122D01*
X580563D01*
X580640Y-261126D01*
D02*
G37*
G36*
X577003Y-263696D02*
X576803D01*
X576766Y-263634D01*
X576726Y-263575D01*
X576679Y-263517D01*
X576636Y-263466D01*
X576592Y-263422D01*
X576559Y-263386D01*
X576545Y-263375D01*
X576534Y-263364D01*
X576530Y-263361D01*
X576526Y-263357D01*
X576450Y-263295D01*
X576373Y-263237D01*
X576301Y-263186D01*
X576228Y-263146D01*
X576166Y-263109D01*
X576140Y-263095D01*
X576119Y-263084D01*
X576100Y-263073D01*
X576086Y-263069D01*
X576079Y-263062D01*
X576075D01*
Y-262764D01*
X576129Y-262786D01*
X576184Y-262811D01*
X576239Y-262837D01*
X576290Y-262862D01*
X576333Y-262884D01*
X576370Y-262902D01*
X576392Y-262916D01*
X576395Y-262920D01*
X576399D01*
X576464Y-262960D01*
X576523Y-263000D01*
X576574Y-263037D01*
X576614Y-263069D01*
X576650Y-263095D01*
X576672Y-263117D01*
X576690Y-263131D01*
X576694Y-263135D01*
Y-261166D01*
X577003D01*
Y-263696D01*
D02*
G37*
G36*
X578718Y-261129D02*
X578808Y-261144D01*
X578885Y-261169D01*
X578951Y-261195D01*
X579005Y-261220D01*
X579023Y-261235D01*
X579041Y-261246D01*
X579056Y-261253D01*
X579067Y-261260D01*
X579071Y-261268D01*
X579074D01*
X579140Y-261330D01*
X579194Y-261395D01*
X579242Y-261468D01*
X579278Y-261533D01*
X579307Y-261595D01*
X579322Y-261621D01*
X579329Y-261646D01*
X579336Y-261664D01*
X579344Y-261679D01*
X579347Y-261686D01*
Y-261690D01*
X579365Y-261744D01*
X579380Y-261799D01*
X579402Y-261915D01*
X579420Y-262036D01*
X579431Y-262152D01*
X579435Y-262203D01*
X579438Y-262250D01*
Y-262294D01*
X579442Y-262334D01*
Y-262363D01*
Y-262389D01*
Y-262403D01*
Y-262407D01*
Y-262476D01*
X579438Y-262542D01*
Y-262600D01*
X579435Y-262658D01*
X579427Y-262709D01*
X579424Y-262760D01*
X579420Y-262804D01*
X579413Y-262844D01*
X579409Y-262880D01*
X579402Y-262913D01*
X579398Y-262938D01*
X579395Y-262960D01*
X579391Y-262978D01*
X579387Y-262989D01*
X579384Y-262997D01*
Y-263000D01*
X579362Y-263080D01*
X579336Y-263153D01*
X579307Y-263215D01*
X579285Y-263270D01*
X579260Y-263317D01*
X579245Y-263350D01*
X579231Y-263368D01*
X579227Y-263375D01*
X579187Y-263430D01*
X579147Y-263477D01*
X579103Y-263517D01*
X579063Y-263554D01*
X579027Y-263579D01*
X578998Y-263597D01*
X578980Y-263608D01*
X578976Y-263612D01*
X578972D01*
X578914Y-263641D01*
X578852Y-263659D01*
X578794Y-263674D01*
X578739Y-263685D01*
X578692Y-263692D01*
X578652Y-263696D01*
X578619D01*
X578521Y-263688D01*
X578430Y-263674D01*
X578354Y-263648D01*
X578288Y-263623D01*
X578233Y-263594D01*
X578212Y-263583D01*
X578193Y-263568D01*
X578179Y-263561D01*
X578168Y-263554D01*
X578164Y-263546D01*
X578161D01*
X578095Y-263488D01*
X578041Y-263419D01*
X577993Y-263350D01*
X577957Y-263284D01*
X577928Y-263222D01*
X577913Y-263197D01*
X577906Y-263171D01*
X577899Y-263153D01*
X577891Y-263139D01*
X577888Y-263131D01*
Y-263128D01*
X577873Y-263073D01*
X577858Y-263018D01*
X577837Y-262898D01*
X577818Y-262778D01*
X577808Y-262665D01*
X577804Y-262611D01*
X577800Y-262563D01*
Y-262520D01*
X577797Y-262480D01*
Y-262451D01*
Y-262425D01*
Y-262411D01*
Y-262407D01*
X577800Y-262280D01*
X577808Y-262159D01*
X577818Y-262050D01*
X577837Y-261948D01*
X577855Y-261854D01*
X577877Y-261770D01*
X577899Y-261694D01*
X577920Y-261628D01*
X577942Y-261570D01*
X577968Y-261519D01*
X577986Y-261475D01*
X578004Y-261442D01*
X578022Y-261413D01*
X578033Y-261395D01*
X578041Y-261384D01*
X578044Y-261381D01*
X578084Y-261337D01*
X578128Y-261297D01*
X578175Y-261260D01*
X578223Y-261231D01*
X578270Y-261206D01*
X578317Y-261184D01*
X578365Y-261169D01*
X578408Y-261155D01*
X578452Y-261144D01*
X578492Y-261137D01*
X578528Y-261129D01*
X578557Y-261126D01*
X578583Y-261122D01*
X578619D01*
X578718Y-261129D01*
D02*
G37*
G36*
X210381Y8525D02*
X212011D01*
Y8274D01*
X210381Y7120D01*
X210097D01*
Y8216D01*
X209492D01*
Y8525D01*
X210097D01*
Y8867D01*
X210381D01*
Y8525D01*
D02*
G37*
G36*
X211979Y5289D02*
X211680D01*
Y6523D01*
X211575Y6436D01*
X211462Y6352D01*
X211352Y6279D01*
X211247Y6210D01*
X211200Y6181D01*
X211156Y6156D01*
X211116Y6130D01*
X211083Y6112D01*
X211054Y6097D01*
X211036Y6086D01*
X211021Y6079D01*
X211018Y6075D01*
X210872Y6003D01*
X210726Y5937D01*
X210588Y5883D01*
X210526Y5861D01*
X210464Y5839D01*
X210410Y5817D01*
X210359Y5802D01*
X210315Y5788D01*
X210279Y5777D01*
X210246Y5766D01*
X210224Y5759D01*
X210209Y5755D01*
X210206D01*
X210057Y5719D01*
X209984Y5704D01*
X209918Y5693D01*
X209856Y5682D01*
X209795Y5672D01*
X209744Y5664D01*
X209693Y5657D01*
X209649Y5653D01*
X209609Y5650D01*
X209573Y5646D01*
X209543D01*
X209522Y5642D01*
X209507D01*
X209496D01*
X209492D01*
Y5959D01*
X209631Y5970D01*
X209758Y5988D01*
X209875Y6006D01*
X209929Y6017D01*
X209980Y6028D01*
X210024Y6036D01*
X210064Y6046D01*
X210100Y6054D01*
X210129Y6061D01*
X210151Y6068D01*
X210170Y6072D01*
X210180Y6075D01*
X210184D01*
X210351Y6130D01*
X210508Y6188D01*
X210584Y6217D01*
X210657Y6247D01*
X210723Y6279D01*
X210788Y6308D01*
X210846Y6334D01*
X210897Y6359D01*
X210941Y6381D01*
X210981Y6400D01*
X211014Y6418D01*
X211036Y6429D01*
X211050Y6436D01*
X211054Y6440D01*
X211130Y6483D01*
X211207Y6527D01*
X211276Y6571D01*
X211342Y6614D01*
X211400Y6654D01*
X211458Y6694D01*
X211509Y6734D01*
X211553Y6767D01*
X211596Y6800D01*
X211633Y6829D01*
X211662Y6858D01*
X211687Y6880D01*
X211709Y6894D01*
X211724Y6909D01*
X211731Y6916D01*
X211735Y6920D01*
X211979D01*
Y5289D01*
D02*
G37*
G36*
X210373Y4649D02*
X210315Y4634D01*
X210261Y4616D01*
X210209Y4598D01*
X210162Y4580D01*
X210119Y4558D01*
X210082Y4536D01*
X210046Y4510D01*
X210013Y4488D01*
X209984Y4470D01*
X209962Y4448D01*
X209940Y4430D01*
X209922Y4416D01*
X209911Y4401D01*
X209900Y4390D01*
X209896Y4387D01*
X209893Y4383D01*
X209864Y4346D01*
X209842Y4307D01*
X209802Y4226D01*
X209773Y4150D01*
X209754Y4073D01*
X209740Y4008D01*
X209736Y3982D01*
Y3957D01*
X209733Y3935D01*
Y3910D01*
X209736Y3826D01*
X209751Y3746D01*
X209769Y3673D01*
X209791Y3608D01*
X209813Y3557D01*
X209824Y3535D01*
X209831Y3517D01*
X209838Y3502D01*
X209845Y3491D01*
X209849Y3484D01*
Y3480D01*
X209900Y3411D01*
X209955Y3353D01*
X210017Y3302D01*
X210075Y3262D01*
X210126Y3229D01*
X210170Y3207D01*
X210188Y3200D01*
X210199Y3193D01*
X210206Y3189D01*
X210209D01*
X210304Y3160D01*
X210399Y3138D01*
X210493Y3120D01*
X210581Y3109D01*
X210621Y3105D01*
X210657Y3102D01*
X210690D01*
X210716Y3098D01*
X210737D01*
X210755D01*
X210766D01*
X210770D01*
X210865Y3102D01*
X210952Y3109D01*
X211032Y3124D01*
X211105Y3138D01*
X211167Y3149D01*
X211192Y3156D01*
X211214Y3164D01*
X211232Y3167D01*
X211243Y3171D01*
X211251Y3175D01*
X211254D01*
X211338Y3211D01*
X211414Y3251D01*
X211476Y3295D01*
X211531Y3342D01*
X211575Y3382D01*
X211604Y3415D01*
X211622Y3440D01*
X211629Y3444D01*
Y3447D01*
X211677Y3524D01*
X211713Y3608D01*
X211738Y3688D01*
X211753Y3764D01*
X211764Y3833D01*
X211768Y3862D01*
Y3888D01*
X211771Y3906D01*
Y3935D01*
X211768Y4026D01*
X211753Y4110D01*
X211731Y4179D01*
X211709Y4241D01*
X211684Y4288D01*
X211666Y4325D01*
X211651Y4346D01*
X211644Y4354D01*
X211589Y4412D01*
X211527Y4467D01*
X211462Y4510D01*
X211396Y4547D01*
X211338Y4576D01*
X211309Y4587D01*
X211287Y4594D01*
X211269Y4601D01*
X211254Y4609D01*
X211247Y4612D01*
X211243D01*
X211320Y4940D01*
X211385Y4918D01*
X211443Y4896D01*
X211498Y4867D01*
X211553Y4842D01*
X211600Y4812D01*
X211644Y4780D01*
X211687Y4751D01*
X211724Y4721D01*
X211753Y4692D01*
X211782Y4667D01*
X211807Y4641D01*
X211826Y4623D01*
X211844Y4605D01*
X211855Y4590D01*
X211858Y4583D01*
X211862Y4580D01*
X211895Y4529D01*
X211928Y4478D01*
X211953Y4427D01*
X211975Y4372D01*
X212008Y4263D01*
X212030Y4165D01*
X212040Y4117D01*
X212044Y4077D01*
X212048Y4037D01*
X212051Y4004D01*
X212055Y3979D01*
Y3943D01*
X212048Y3822D01*
X212030Y3706D01*
X212008Y3604D01*
X211993Y3557D01*
X211979Y3513D01*
X211964Y3473D01*
X211949Y3436D01*
X211939Y3407D01*
X211928Y3378D01*
X211917Y3360D01*
X211909Y3345D01*
X211906Y3335D01*
X211902Y3331D01*
X211840Y3233D01*
X211768Y3149D01*
X211695Y3076D01*
X211622Y3014D01*
X211556Y2967D01*
X211527Y2949D01*
X211502Y2934D01*
X211484Y2920D01*
X211469Y2912D01*
X211458Y2909D01*
X211454Y2905D01*
X211342Y2854D01*
X211225Y2818D01*
X211109Y2792D01*
X211003Y2774D01*
X210956Y2767D01*
X210908Y2763D01*
X210872Y2760D01*
X210836D01*
X210810Y2756D01*
X210788D01*
X210774D01*
X210770D01*
X210639Y2763D01*
X210512Y2778D01*
X210399Y2796D01*
X210344Y2811D01*
X210297Y2821D01*
X210253Y2832D01*
X210213Y2847D01*
X210177Y2858D01*
X210148Y2865D01*
X210126Y2876D01*
X210108Y2880D01*
X210097Y2887D01*
X210093D01*
X209984Y2942D01*
X209886Y3003D01*
X209802Y3069D01*
X209769Y3102D01*
X209736Y3131D01*
X209707Y3160D01*
X209682Y3189D01*
X209660Y3215D01*
X209645Y3236D01*
X209631Y3251D01*
X209620Y3266D01*
X209616Y3273D01*
X209613Y3276D01*
X209583Y3327D01*
X209558Y3378D01*
X209518Y3488D01*
X209489Y3597D01*
X209471Y3702D01*
X209463Y3753D01*
X209456Y3797D01*
X209452Y3837D01*
Y3870D01*
X209449Y3899D01*
Y3939D01*
X209452Y4012D01*
X209460Y4081D01*
X209467Y4146D01*
X209482Y4208D01*
X209500Y4267D01*
X209518Y4321D01*
X209536Y4372D01*
X209558Y4419D01*
X209576Y4459D01*
X209594Y4499D01*
X209613Y4529D01*
X209631Y4558D01*
X209645Y4576D01*
X209653Y4594D01*
X209660Y4601D01*
X209664Y4605D01*
X209707Y4656D01*
X209751Y4700D01*
X209802Y4740D01*
X209853Y4780D01*
X209955Y4845D01*
X210057Y4896D01*
X210104Y4918D01*
X210148Y4936D01*
X210188Y4951D01*
X210220Y4962D01*
X210250Y4973D01*
X210271Y4980D01*
X210286Y4984D01*
X210290D01*
X210373Y4649D01*
D02*
G37*
G36*
X206368Y1539D02*
X206070D01*
Y2773D01*
X205964Y2685D01*
X205851Y2602D01*
X205742Y2529D01*
X205637Y2460D01*
X205589Y2431D01*
X205546Y2405D01*
X205506Y2380D01*
X205473Y2362D01*
X205444Y2347D01*
X205426Y2336D01*
X205411Y2329D01*
X205407Y2325D01*
X205262Y2252D01*
X205116Y2187D01*
X204978Y2132D01*
X204916Y2110D01*
X204854Y2089D01*
X204800Y2067D01*
X204749Y2052D01*
X204705Y2038D01*
X204668Y2027D01*
X204636Y2016D01*
X204614Y2008D01*
X204599Y2005D01*
X204596D01*
X204446Y1969D01*
X204374Y1954D01*
X204308Y1943D01*
X204246Y1932D01*
X204184Y1921D01*
X204133Y1914D01*
X204082Y1907D01*
X204039Y1903D01*
X203999Y1899D01*
X203962Y1896D01*
X203933D01*
X203911Y1892D01*
X203897D01*
X203886D01*
X203882D01*
Y2209D01*
X204021Y2220D01*
X204148Y2238D01*
X204264Y2256D01*
X204319Y2267D01*
X204370Y2278D01*
X204414Y2285D01*
X204454Y2296D01*
X204490Y2303D01*
X204519Y2311D01*
X204541Y2318D01*
X204559Y2321D01*
X204570Y2325D01*
X204574D01*
X204741Y2380D01*
X204898Y2438D01*
X204974Y2467D01*
X205047Y2496D01*
X205113Y2529D01*
X205178Y2558D01*
X205236Y2584D01*
X205287Y2609D01*
X205331Y2631D01*
X205371Y2649D01*
X205404Y2667D01*
X205426Y2678D01*
X205440Y2685D01*
X205444Y2689D01*
X205520Y2733D01*
X205597Y2777D01*
X205666Y2820D01*
X205731Y2864D01*
X205790Y2904D01*
X205848Y2944D01*
X205899Y2984D01*
X205942Y3017D01*
X205986Y3049D01*
X206023Y3079D01*
X206052Y3108D01*
X206077Y3130D01*
X206099Y3144D01*
X206114Y3159D01*
X206121Y3166D01*
X206124Y3170D01*
X206368D01*
Y1539D01*
D02*
G37*
G36*
X205356Y1211D02*
X205429Y1204D01*
X205498Y1197D01*
X205560Y1190D01*
X205619Y1182D01*
X205673Y1171D01*
X205720Y1160D01*
X205760Y1149D01*
X205797Y1142D01*
X205830Y1131D01*
X205855Y1124D01*
X205873Y1117D01*
X205888Y1109D01*
X205895Y1106D01*
X205899D01*
X205986Y1062D01*
X206063Y1015D01*
X206128Y960D01*
X206183Y913D01*
X206223Y865D01*
X206252Y829D01*
X206263Y815D01*
X206270Y804D01*
X206277Y800D01*
Y796D01*
X206321Y720D01*
X206354Y643D01*
X206379Y567D01*
X206394Y498D01*
X206405Y436D01*
X206408Y410D01*
Y392D01*
X206412Y374D01*
Y349D01*
X206408Y287D01*
X206401Y228D01*
X206390Y170D01*
X206376Y119D01*
X206336Y21D01*
X206317Y-23D01*
X206295Y-59D01*
X206270Y-95D01*
X206252Y-125D01*
X206230Y-154D01*
X206212Y-175D01*
X206197Y-194D01*
X206186Y-205D01*
X206179Y-212D01*
X206175Y-216D01*
X206132Y-256D01*
X206081Y-288D01*
X206033Y-321D01*
X205982Y-347D01*
X205928Y-368D01*
X205877Y-387D01*
X205782Y-412D01*
X205735Y-423D01*
X205695Y-430D01*
X205655Y-434D01*
X205622Y-438D01*
X205597Y-441D01*
X205578D01*
X205564D01*
X205560D01*
X205491Y-438D01*
X205429Y-430D01*
X205367Y-423D01*
X205309Y-409D01*
X205258Y-390D01*
X205207Y-372D01*
X205164Y-354D01*
X205123Y-332D01*
X205087Y-314D01*
X205054Y-296D01*
X205029Y-277D01*
X205003Y-259D01*
X204985Y-245D01*
X204974Y-237D01*
X204967Y-230D01*
X204963Y-227D01*
X204923Y-186D01*
X204890Y-143D01*
X204858Y-99D01*
X204832Y-52D01*
X204810Y-8D01*
X204792Y36D01*
X204767Y119D01*
X204756Y156D01*
X204749Y192D01*
X204745Y221D01*
X204741Y250D01*
X204738Y272D01*
Y301D01*
X204741Y371D01*
X204752Y436D01*
X204767Y494D01*
X204785Y549D01*
X204800Y589D01*
X204814Y622D01*
X204825Y643D01*
X204829Y651D01*
X204865Y709D01*
X204905Y760D01*
X204945Y804D01*
X204981Y840D01*
X205018Y865D01*
X205043Y887D01*
X205062Y902D01*
X205069Y906D01*
X205040D01*
X205022D01*
X205011D01*
X205007D01*
X204934Y902D01*
X204865Y898D01*
X204803Y891D01*
X204745Y884D01*
X204698Y873D01*
X204661Y865D01*
X204647Y862D01*
X204636D01*
X204632Y858D01*
X204628D01*
X204563Y840D01*
X204505Y822D01*
X204454Y804D01*
X204410Y785D01*
X204377Y771D01*
X204352Y756D01*
X204334Y749D01*
X204330Y745D01*
X204290Y716D01*
X204257Y687D01*
X204228Y658D01*
X204203Y629D01*
X204181Y607D01*
X204166Y585D01*
X204159Y571D01*
X204155Y567D01*
X204133Y527D01*
X204119Y483D01*
X204108Y443D01*
X204101Y403D01*
X204097Y371D01*
X204093Y345D01*
Y320D01*
X204097Y261D01*
X204108Y207D01*
X204122Y159D01*
X204141Y119D01*
X204155Y90D01*
X204170Y65D01*
X204181Y50D01*
X204184Y46D01*
X204224Y10D01*
X204272Y-19D01*
X204323Y-45D01*
X204374Y-63D01*
X204417Y-77D01*
X204457Y-88D01*
X204472Y-92D01*
X204479D01*
X204486Y-95D01*
X204490D01*
X204465Y-394D01*
X204359Y-372D01*
X204268Y-343D01*
X204188Y-307D01*
X204122Y-270D01*
X204071Y-234D01*
X204050Y-216D01*
X204031Y-201D01*
X204021Y-190D01*
X204010Y-179D01*
X204006Y-175D01*
X204002Y-172D01*
X203973Y-135D01*
X203948Y-95D01*
X203908Y-15D01*
X203879Y65D01*
X203860Y141D01*
X203846Y210D01*
X203842Y240D01*
Y265D01*
X203838Y283D01*
Y312D01*
X203846Y414D01*
X203860Y505D01*
X203886Y589D01*
X203915Y658D01*
X203926Y687D01*
X203940Y716D01*
X203955Y738D01*
X203966Y760D01*
X203973Y775D01*
X203980Y785D01*
X203988Y793D01*
Y796D01*
X204050Y869D01*
X204119Y935D01*
X204192Y986D01*
X204261Y1029D01*
X204323Y1066D01*
X204352Y1080D01*
X204374Y1091D01*
X204395Y1099D01*
X204410Y1106D01*
X204417Y1109D01*
X204421D01*
X204475Y1128D01*
X204537Y1146D01*
X204661Y1171D01*
X204792Y1190D01*
X204916Y1200D01*
X204971Y1208D01*
X205025Y1211D01*
X205072D01*
X205113Y1215D01*
X205145D01*
X205171D01*
X205189D01*
X205193D01*
X205276D01*
X205356Y1211D01*
D02*
G37*
G36*
X204763Y-1060D02*
X204705Y-1075D01*
X204650Y-1093D01*
X204599Y-1111D01*
X204552Y-1129D01*
X204508Y-1151D01*
X204472Y-1173D01*
X204435Y-1198D01*
X204403Y-1220D01*
X204374Y-1238D01*
X204352Y-1260D01*
X204330Y-1278D01*
X204312Y-1293D01*
X204301Y-1307D01*
X204290Y-1319D01*
X204286Y-1322D01*
X204283Y-1326D01*
X204254Y-1362D01*
X204232Y-1402D01*
X204192Y-1482D01*
X204163Y-1559D01*
X204144Y-1635D01*
X204130Y-1701D01*
X204126Y-1726D01*
Y-1752D01*
X204122Y-1774D01*
Y-1799D01*
X204126Y-1883D01*
X204141Y-1963D01*
X204159Y-2035D01*
X204181Y-2101D01*
X204203Y-2152D01*
X204213Y-2174D01*
X204221Y-2192D01*
X204228Y-2207D01*
X204235Y-2217D01*
X204239Y-2225D01*
Y-2228D01*
X204290Y-2298D01*
X204345Y-2356D01*
X204406Y-2407D01*
X204465Y-2447D01*
X204516Y-2480D01*
X204559Y-2502D01*
X204577Y-2509D01*
X204588Y-2516D01*
X204596Y-2520D01*
X204599D01*
X204694Y-2549D01*
X204789Y-2571D01*
X204883Y-2589D01*
X204971Y-2600D01*
X205011Y-2603D01*
X205047Y-2607D01*
X205080D01*
X205105Y-2611D01*
X205127D01*
X205145D01*
X205156D01*
X205160D01*
X205255Y-2607D01*
X205342Y-2600D01*
X205422Y-2585D01*
X205495Y-2571D01*
X205557Y-2560D01*
X205582Y-2552D01*
X205604Y-2545D01*
X205622Y-2541D01*
X205633Y-2538D01*
X205640Y-2534D01*
X205644D01*
X205728Y-2498D01*
X205804Y-2458D01*
X205866Y-2414D01*
X205921Y-2367D01*
X205964Y-2327D01*
X205993Y-2294D01*
X206012Y-2269D01*
X206019Y-2265D01*
Y-2261D01*
X206066Y-2185D01*
X206103Y-2101D01*
X206128Y-2021D01*
X206143Y-1945D01*
X206154Y-1875D01*
X206157Y-1846D01*
Y-1821D01*
X206161Y-1803D01*
Y-1774D01*
X206157Y-1682D01*
X206143Y-1599D01*
X206121Y-1530D01*
X206099Y-1468D01*
X206073Y-1420D01*
X206055Y-1384D01*
X206041Y-1362D01*
X206033Y-1355D01*
X205979Y-1297D01*
X205917Y-1242D01*
X205851Y-1198D01*
X205786Y-1162D01*
X205728Y-1133D01*
X205699Y-1122D01*
X205677Y-1115D01*
X205659Y-1107D01*
X205644Y-1100D01*
X205637Y-1096D01*
X205633D01*
X205710Y-769D01*
X205775Y-791D01*
X205833Y-812D01*
X205888Y-842D01*
X205942Y-867D01*
X205990Y-896D01*
X206033Y-929D01*
X206077Y-958D01*
X206114Y-987D01*
X206143Y-1016D01*
X206172Y-1042D01*
X206197Y-1067D01*
X206215Y-1085D01*
X206234Y-1104D01*
X206245Y-1118D01*
X206248Y-1125D01*
X206252Y-1129D01*
X206285Y-1180D01*
X206317Y-1231D01*
X206343Y-1282D01*
X206365Y-1337D01*
X206397Y-1446D01*
X206419Y-1544D01*
X206430Y-1592D01*
X206434Y-1632D01*
X206437Y-1671D01*
X206441Y-1704D01*
X206445Y-1730D01*
Y-1766D01*
X206437Y-1886D01*
X206419Y-2003D01*
X206397Y-2105D01*
X206383Y-2152D01*
X206368Y-2196D01*
X206354Y-2236D01*
X206339Y-2272D01*
X206328Y-2301D01*
X206317Y-2330D01*
X206306Y-2349D01*
X206299Y-2363D01*
X206295Y-2374D01*
X206292Y-2378D01*
X206230Y-2476D01*
X206157Y-2560D01*
X206084Y-2633D01*
X206012Y-2694D01*
X205946Y-2742D01*
X205917Y-2760D01*
X205891Y-2774D01*
X205873Y-2789D01*
X205859Y-2796D01*
X205848Y-2800D01*
X205844Y-2804D01*
X205731Y-2854D01*
X205615Y-2891D01*
X205498Y-2916D01*
X205393Y-2935D01*
X205346Y-2942D01*
X205298Y-2946D01*
X205262Y-2949D01*
X205225D01*
X205200Y-2953D01*
X205178D01*
X205164D01*
X205160D01*
X205029Y-2946D01*
X204901Y-2931D01*
X204789Y-2913D01*
X204734Y-2898D01*
X204687Y-2887D01*
X204643Y-2876D01*
X204603Y-2862D01*
X204567Y-2851D01*
X204537Y-2844D01*
X204516Y-2833D01*
X204497Y-2829D01*
X204486Y-2822D01*
X204483D01*
X204374Y-2767D01*
X204275Y-2705D01*
X204192Y-2640D01*
X204159Y-2607D01*
X204126Y-2578D01*
X204097Y-2549D01*
X204071Y-2520D01*
X204050Y-2494D01*
X204035Y-2472D01*
X204021Y-2458D01*
X204010Y-2443D01*
X204006Y-2436D01*
X204002Y-2432D01*
X203973Y-2381D01*
X203948Y-2330D01*
X203908Y-2221D01*
X203879Y-2112D01*
X203860Y-2006D01*
X203853Y-1956D01*
X203846Y-1912D01*
X203842Y-1872D01*
Y-1839D01*
X203838Y-1810D01*
Y-1770D01*
X203842Y-1697D01*
X203849Y-1628D01*
X203857Y-1562D01*
X203871Y-1500D01*
X203889Y-1442D01*
X203908Y-1388D01*
X203926Y-1337D01*
X203948Y-1289D01*
X203966Y-1249D01*
X203984Y-1209D01*
X204002Y-1180D01*
X204021Y-1151D01*
X204035Y-1133D01*
X204042Y-1115D01*
X204050Y-1107D01*
X204053Y-1104D01*
X204097Y-1053D01*
X204141Y-1009D01*
X204192Y-969D01*
X204243Y-929D01*
X204345Y-864D01*
X204446Y-812D01*
X204494Y-791D01*
X204537Y-772D01*
X204577Y-758D01*
X204610Y-747D01*
X204639Y-736D01*
X204661Y-729D01*
X204676Y-725D01*
X204679D01*
X204763Y-1060D01*
D02*
G37*
G36*
X215018Y2973D02*
X215094Y2958D01*
X215163Y2936D01*
X215222Y2915D01*
X215269Y2893D01*
X215305Y2871D01*
X215327Y2856D01*
X215331Y2853D01*
X215334D01*
X215393Y2802D01*
X215444Y2747D01*
X215484Y2689D01*
X215520Y2634D01*
X215546Y2583D01*
X215564Y2540D01*
X215571Y2525D01*
X215575Y2514D01*
X215578Y2507D01*
Y2503D01*
X215607Y2569D01*
X215640Y2623D01*
X215673Y2671D01*
X215706Y2711D01*
X215735Y2740D01*
X215757Y2762D01*
X215771Y2776D01*
X215778Y2780D01*
X215829Y2813D01*
X215880Y2834D01*
X215931Y2853D01*
X215982Y2864D01*
X216022Y2871D01*
X216055Y2874D01*
X216077D01*
X216080D01*
X216084D01*
X216135Y2871D01*
X216182Y2867D01*
X216273Y2842D01*
X216354Y2809D01*
X216423Y2773D01*
X216477Y2736D01*
X216499Y2718D01*
X216521Y2703D01*
X216536Y2689D01*
X216547Y2678D01*
X216550Y2674D01*
X216554Y2671D01*
X216586Y2631D01*
X216619Y2591D01*
X216645Y2547D01*
X216667Y2503D01*
X216699Y2416D01*
X216721Y2328D01*
X216732Y2292D01*
X216736Y2256D01*
X216739Y2223D01*
X216743Y2194D01*
X216747Y2172D01*
Y2139D01*
X216743Y2081D01*
X216739Y2023D01*
X216718Y1921D01*
X216703Y1874D01*
X216688Y1830D01*
X216670Y1790D01*
X216652Y1753D01*
X216634Y1724D01*
X216616Y1695D01*
X216601Y1670D01*
X216586Y1651D01*
X216576Y1637D01*
X216565Y1626D01*
X216561Y1619D01*
X216557Y1615D01*
X216521Y1582D01*
X216485Y1550D01*
X216444Y1524D01*
X216405Y1502D01*
X216328Y1466D01*
X216255Y1444D01*
X216193Y1429D01*
X216164Y1426D01*
X216142Y1422D01*
X216121Y1419D01*
X216106D01*
X216099D01*
X216095D01*
X216030Y1422D01*
X215968Y1433D01*
X215913Y1448D01*
X215866Y1466D01*
X215829Y1480D01*
X215800Y1495D01*
X215786Y1506D01*
X215778Y1510D01*
X215735Y1550D01*
X215695Y1593D01*
X215658Y1641D01*
X215629Y1688D01*
X215607Y1732D01*
X215593Y1764D01*
X215585Y1779D01*
X215582Y1790D01*
X215578Y1793D01*
Y1797D01*
X215553Y1713D01*
X215520Y1644D01*
X215480Y1582D01*
X215444Y1531D01*
X215407Y1491D01*
X215378Y1462D01*
X215360Y1448D01*
X215356Y1440D01*
X215353D01*
X215287Y1400D01*
X215218Y1368D01*
X215152Y1346D01*
X215087Y1331D01*
X215029Y1324D01*
X215003Y1320D01*
X214981D01*
X214967Y1317D01*
X214952D01*
X214945D01*
X214941D01*
X214883Y1320D01*
X214825Y1328D01*
X214770Y1338D01*
X214716Y1353D01*
X214625Y1389D01*
X214581Y1408D01*
X214545Y1429D01*
X214508Y1451D01*
X214479Y1469D01*
X214454Y1491D01*
X214432Y1506D01*
X214413Y1520D01*
X214403Y1531D01*
X214395Y1539D01*
X214392Y1542D01*
X214352Y1586D01*
X214319Y1633D01*
X214290Y1684D01*
X214264Y1735D01*
X214246Y1782D01*
X214228Y1833D01*
X214202Y1932D01*
X214191Y1976D01*
X214184Y2015D01*
X214180Y2052D01*
X214177Y2085D01*
X214173Y2110D01*
Y2146D01*
X214177Y2216D01*
X214184Y2278D01*
X214195Y2340D01*
X214206Y2398D01*
X214224Y2449D01*
X214242Y2500D01*
X214261Y2547D01*
X214282Y2587D01*
X214304Y2623D01*
X214322Y2656D01*
X214341Y2682D01*
X214359Y2707D01*
X214370Y2725D01*
X214381Y2736D01*
X214388Y2743D01*
X214392Y2747D01*
X214435Y2787D01*
X214479Y2824D01*
X214523Y2853D01*
X214570Y2878D01*
X214614Y2904D01*
X214661Y2922D01*
X214745Y2947D01*
X214785Y2958D01*
X214821Y2966D01*
X214854Y2969D01*
X214879Y2973D01*
X214901Y2977D01*
X214919D01*
X214930D01*
X214934D01*
X215018Y2973D01*
D02*
G37*
G36*
X215691Y1015D02*
X215764Y1007D01*
X215833Y1000D01*
X215895Y993D01*
X215953Y985D01*
X216008Y974D01*
X216055Y963D01*
X216095Y953D01*
X216131Y945D01*
X216164Y934D01*
X216190Y927D01*
X216208Y920D01*
X216223Y913D01*
X216230Y909D01*
X216233D01*
X216321Y865D01*
X216397Y818D01*
X216463Y763D01*
X216517Y716D01*
X216557Y669D01*
X216586Y632D01*
X216597Y618D01*
X216605Y607D01*
X216612Y603D01*
Y599D01*
X216656Y523D01*
X216688Y447D01*
X216714Y370D01*
X216728Y301D01*
X216739Y239D01*
X216743Y214D01*
Y195D01*
X216747Y177D01*
Y152D01*
X216743Y90D01*
X216736Y32D01*
X216725Y-27D01*
X216710Y-78D01*
X216670Y-176D01*
X216652Y-219D01*
X216630Y-256D01*
X216605Y-292D01*
X216586Y-321D01*
X216565Y-350D01*
X216547Y-372D01*
X216532Y-391D01*
X216521Y-402D01*
X216514Y-409D01*
X216510Y-412D01*
X216466Y-452D01*
X216415Y-485D01*
X216368Y-518D01*
X216317Y-543D01*
X216263Y-565D01*
X216212Y-583D01*
X216117Y-609D01*
X216070Y-620D01*
X216030Y-627D01*
X215990Y-631D01*
X215957Y-634D01*
X215931Y-638D01*
X215913D01*
X215898D01*
X215895D01*
X215826Y-634D01*
X215764Y-627D01*
X215702Y-620D01*
X215644Y-605D01*
X215593Y-587D01*
X215542Y-569D01*
X215498Y-551D01*
X215458Y-529D01*
X215422Y-511D01*
X215389Y-493D01*
X215364Y-474D01*
X215338Y-456D01*
X215320Y-441D01*
X215309Y-434D01*
X215302Y-427D01*
X215298Y-423D01*
X215258Y-383D01*
X215225Y-340D01*
X215192Y-296D01*
X215167Y-249D01*
X215145Y-205D01*
X215127Y-161D01*
X215101Y-78D01*
X215090Y-41D01*
X215083Y-5D01*
X215080Y24D01*
X215076Y53D01*
X215072Y75D01*
Y105D01*
X215076Y174D01*
X215087Y239D01*
X215101Y297D01*
X215120Y352D01*
X215134Y392D01*
X215149Y425D01*
X215160Y447D01*
X215163Y454D01*
X215200Y512D01*
X215240Y563D01*
X215280Y607D01*
X215316Y643D01*
X215353Y669D01*
X215378Y691D01*
X215396Y705D01*
X215404Y709D01*
X215374D01*
X215356D01*
X215345D01*
X215342D01*
X215269Y705D01*
X215200Y701D01*
X215138Y694D01*
X215080Y687D01*
X215032Y676D01*
X214996Y669D01*
X214981Y665D01*
X214970D01*
X214967Y661D01*
X214963D01*
X214898Y643D01*
X214839Y625D01*
X214788Y607D01*
X214745Y589D01*
X214712Y574D01*
X214686Y559D01*
X214668Y552D01*
X214665Y549D01*
X214625Y519D01*
X214592Y490D01*
X214563Y461D01*
X214537Y432D01*
X214515Y410D01*
X214501Y388D01*
X214493Y374D01*
X214490Y370D01*
X214468Y330D01*
X214454Y286D01*
X214442Y246D01*
X214435Y206D01*
X214432Y174D01*
X214428Y148D01*
Y123D01*
X214432Y64D01*
X214442Y10D01*
X214457Y-38D01*
X214475Y-78D01*
X214490Y-107D01*
X214504Y-132D01*
X214515Y-147D01*
X214519Y-150D01*
X214559Y-187D01*
X214606Y-216D01*
X214657Y-241D01*
X214708Y-259D01*
X214752Y-274D01*
X214792Y-285D01*
X214807Y-289D01*
X214814D01*
X214821Y-292D01*
X214825D01*
X214799Y-591D01*
X214694Y-569D01*
X214603Y-540D01*
X214523Y-503D01*
X214457Y-467D01*
X214406Y-431D01*
X214384Y-412D01*
X214366Y-398D01*
X214355Y-387D01*
X214344Y-376D01*
X214341Y-372D01*
X214337Y-369D01*
X214308Y-332D01*
X214282Y-292D01*
X214242Y-212D01*
X214213Y-132D01*
X214195Y-56D01*
X214180Y13D01*
X214177Y43D01*
Y68D01*
X214173Y86D01*
Y115D01*
X214180Y217D01*
X214195Y308D01*
X214220Y392D01*
X214250Y461D01*
X214261Y490D01*
X214275Y519D01*
X214290Y541D01*
X214301Y563D01*
X214308Y578D01*
X214315Y589D01*
X214322Y596D01*
Y599D01*
X214384Y672D01*
X214454Y738D01*
X214526Y789D01*
X214595Y833D01*
X214657Y869D01*
X214686Y883D01*
X214708Y894D01*
X214730Y902D01*
X214745Y909D01*
X214752Y913D01*
X214756D01*
X214810Y931D01*
X214872Y949D01*
X214996Y974D01*
X215127Y993D01*
X215251Y1004D01*
X215305Y1011D01*
X215360Y1015D01*
X215407D01*
X215447Y1018D01*
X215480D01*
X215505D01*
X215524D01*
X215527D01*
X215611D01*
X215691Y1015D01*
D02*
G37*
G36*
X215098Y-1257D02*
X215039Y-1271D01*
X214985Y-1290D01*
X214934Y-1308D01*
X214887Y-1326D01*
X214843Y-1348D01*
X214807Y-1370D01*
X214770Y-1395D01*
X214737Y-1417D01*
X214708Y-1435D01*
X214686Y-1457D01*
X214665Y-1475D01*
X214646Y-1490D01*
X214635Y-1504D01*
X214625Y-1515D01*
X214621Y-1519D01*
X214617Y-1523D01*
X214588Y-1559D01*
X214566Y-1599D01*
X214526Y-1679D01*
X214497Y-1756D01*
X214479Y-1832D01*
X214464Y-1898D01*
X214461Y-1923D01*
Y-1949D01*
X214457Y-1970D01*
Y-1996D01*
X214461Y-2080D01*
X214475Y-2160D01*
X214493Y-2232D01*
X214515Y-2298D01*
X214537Y-2349D01*
X214548Y-2371D01*
X214555Y-2389D01*
X214563Y-2403D01*
X214570Y-2414D01*
X214574Y-2422D01*
Y-2425D01*
X214625Y-2495D01*
X214679Y-2553D01*
X214741Y-2604D01*
X214799Y-2644D01*
X214850Y-2677D01*
X214894Y-2698D01*
X214912Y-2706D01*
X214923Y-2713D01*
X214930Y-2716D01*
X214934D01*
X215029Y-2746D01*
X215123Y-2767D01*
X215218Y-2786D01*
X215305Y-2797D01*
X215345Y-2800D01*
X215382Y-2804D01*
X215414D01*
X215440Y-2808D01*
X215462D01*
X215480D01*
X215491D01*
X215494D01*
X215589Y-2804D01*
X215676Y-2797D01*
X215757Y-2782D01*
X215829Y-2767D01*
X215891Y-2757D01*
X215917Y-2749D01*
X215939Y-2742D01*
X215957Y-2738D01*
X215968Y-2735D01*
X215975Y-2731D01*
X215979D01*
X216062Y-2695D01*
X216139Y-2655D01*
X216201Y-2611D01*
X216255Y-2564D01*
X216299Y-2524D01*
X216328Y-2491D01*
X216346Y-2465D01*
X216354Y-2462D01*
Y-2458D01*
X216401Y-2382D01*
X216437Y-2298D01*
X216463Y-2218D01*
X216477Y-2141D01*
X216488Y-2072D01*
X216492Y-2043D01*
Y-2018D01*
X216495Y-1999D01*
Y-1970D01*
X216492Y-1879D01*
X216477Y-1796D01*
X216456Y-1726D01*
X216434Y-1664D01*
X216408Y-1617D01*
X216390Y-1581D01*
X216375Y-1559D01*
X216368Y-1552D01*
X216314Y-1493D01*
X216252Y-1439D01*
X216186Y-1395D01*
X216121Y-1359D01*
X216062Y-1330D01*
X216033Y-1319D01*
X216011Y-1311D01*
X215993Y-1304D01*
X215979Y-1297D01*
X215971Y-1293D01*
X215968D01*
X216044Y-966D01*
X216110Y-988D01*
X216168Y-1009D01*
X216223Y-1039D01*
X216277Y-1064D01*
X216324Y-1093D01*
X216368Y-1126D01*
X216412Y-1155D01*
X216448Y-1184D01*
X216477Y-1213D01*
X216506Y-1239D01*
X216532Y-1264D01*
X216550Y-1282D01*
X216568Y-1300D01*
X216579Y-1315D01*
X216583Y-1322D01*
X216586Y-1326D01*
X216619Y-1377D01*
X216652Y-1428D01*
X216677Y-1479D01*
X216699Y-1534D01*
X216732Y-1643D01*
X216754Y-1741D01*
X216765Y-1788D01*
X216769Y-1828D01*
X216772Y-1868D01*
X216776Y-1901D01*
X216779Y-1927D01*
Y-1963D01*
X216772Y-2083D01*
X216754Y-2200D01*
X216732Y-2301D01*
X216718Y-2349D01*
X216703Y-2393D01*
X216688Y-2433D01*
X216674Y-2469D01*
X216663Y-2498D01*
X216652Y-2527D01*
X216641Y-2545D01*
X216634Y-2560D01*
X216630Y-2571D01*
X216627Y-2575D01*
X216565Y-2673D01*
X216492Y-2757D01*
X216419Y-2829D01*
X216346Y-2891D01*
X216281Y-2939D01*
X216252Y-2957D01*
X216226Y-2971D01*
X216208Y-2986D01*
X216193Y-2993D01*
X216182Y-2997D01*
X216179Y-3000D01*
X216066Y-3051D01*
X215950Y-3088D01*
X215833Y-3113D01*
X215727Y-3131D01*
X215680Y-3139D01*
X215633Y-3142D01*
X215596Y-3146D01*
X215560D01*
X215534Y-3150D01*
X215513D01*
X215498D01*
X215494D01*
X215364Y-3142D01*
X215236Y-3128D01*
X215123Y-3110D01*
X215069Y-3095D01*
X215021Y-3084D01*
X214978Y-3073D01*
X214938Y-3059D01*
X214901Y-3048D01*
X214872Y-3040D01*
X214850Y-3030D01*
X214832Y-3026D01*
X214821Y-3019D01*
X214818D01*
X214708Y-2964D01*
X214610Y-2902D01*
X214526Y-2837D01*
X214493Y-2804D01*
X214461Y-2775D01*
X214432Y-2746D01*
X214406Y-2716D01*
X214384Y-2691D01*
X214370Y-2669D01*
X214355Y-2655D01*
X214344Y-2640D01*
X214341Y-2633D01*
X214337Y-2629D01*
X214308Y-2578D01*
X214282Y-2527D01*
X214242Y-2418D01*
X214213Y-2309D01*
X214195Y-2203D01*
X214188Y-2152D01*
X214180Y-2109D01*
X214177Y-2069D01*
Y-2036D01*
X214173Y-2007D01*
Y-1967D01*
X214177Y-1894D01*
X214184Y-1825D01*
X214191Y-1759D01*
X214206Y-1697D01*
X214224Y-1639D01*
X214242Y-1585D01*
X214261Y-1534D01*
X214282Y-1486D01*
X214301Y-1446D01*
X214319Y-1406D01*
X214337Y-1377D01*
X214355Y-1348D01*
X214370Y-1330D01*
X214377Y-1311D01*
X214384Y-1304D01*
X214388Y-1300D01*
X214432Y-1250D01*
X214475Y-1206D01*
X214526Y-1166D01*
X214577Y-1126D01*
X214679Y-1060D01*
X214781Y-1009D01*
X214828Y-988D01*
X214872Y-969D01*
X214912Y-955D01*
X214945Y-944D01*
X214974Y-933D01*
X214996Y-926D01*
X215010Y-922D01*
X215014D01*
X215098Y-1257D01*
D02*
G37*
G36*
X203347Y-75007D02*
X203474Y-75022D01*
X203587Y-75040D01*
X203642Y-75055D01*
X203689Y-75065D01*
X203733Y-75076D01*
X203773Y-75091D01*
X203809Y-75102D01*
X203838Y-75109D01*
X203860Y-75120D01*
X203878Y-75124D01*
X203889Y-75131D01*
X203893D01*
X204002Y-75186D01*
X204100Y-75248D01*
X204184Y-75313D01*
X204217Y-75346D01*
X204250Y-75375D01*
X204279Y-75404D01*
X204304Y-75433D01*
X204326Y-75459D01*
X204341Y-75480D01*
X204355Y-75495D01*
X204366Y-75510D01*
X204370Y-75517D01*
X204374Y-75520D01*
X204403Y-75571D01*
X204428Y-75622D01*
X204468Y-75732D01*
X204497Y-75841D01*
X204516Y-75946D01*
X204523Y-75997D01*
X204530Y-76041D01*
X204534Y-76081D01*
Y-76114D01*
X204537Y-76143D01*
Y-76183D01*
X204534Y-76256D01*
X204526Y-76325D01*
X204519Y-76390D01*
X204504Y-76452D01*
X204486Y-76511D01*
X204468Y-76565D01*
X204450Y-76616D01*
X204428Y-76663D01*
X204410Y-76704D01*
X204392Y-76744D01*
X204374Y-76773D01*
X204355Y-76802D01*
X204341Y-76820D01*
X204333Y-76838D01*
X204326Y-76845D01*
X204323Y-76849D01*
X204279Y-76900D01*
X204235Y-76944D01*
X204184Y-76984D01*
X204133Y-77024D01*
X204031Y-77089D01*
X203929Y-77140D01*
X203882Y-77162D01*
X203838Y-77180D01*
X203798Y-77195D01*
X203766Y-77206D01*
X203736Y-77217D01*
X203715Y-77224D01*
X203700Y-77228D01*
X203696D01*
X203613Y-76893D01*
X203671Y-76878D01*
X203726Y-76860D01*
X203777Y-76842D01*
X203824Y-76824D01*
X203868Y-76802D01*
X203904Y-76780D01*
X203940Y-76754D01*
X203973Y-76733D01*
X204002Y-76714D01*
X204024Y-76693D01*
X204046Y-76674D01*
X204064Y-76660D01*
X204075Y-76645D01*
X204086Y-76634D01*
X204090Y-76631D01*
X204093Y-76627D01*
X204122Y-76591D01*
X204144Y-76551D01*
X204184Y-76471D01*
X204213Y-76394D01*
X204232Y-76318D01*
X204246Y-76252D01*
X204250Y-76227D01*
Y-76201D01*
X204253Y-76179D01*
Y-76154D01*
X204250Y-76070D01*
X204235Y-75990D01*
X204217Y-75917D01*
X204195Y-75852D01*
X204173Y-75801D01*
X204162Y-75779D01*
X204155Y-75761D01*
X204148Y-75746D01*
X204140Y-75735D01*
X204137Y-75728D01*
Y-75724D01*
X204086Y-75655D01*
X204031Y-75597D01*
X203970Y-75546D01*
X203911Y-75506D01*
X203860Y-75473D01*
X203817Y-75451D01*
X203798Y-75444D01*
X203787Y-75437D01*
X203780Y-75433D01*
X203777D01*
X203682Y-75404D01*
X203587Y-75382D01*
X203493Y-75364D01*
X203405Y-75353D01*
X203365Y-75349D01*
X203329Y-75346D01*
X203296D01*
X203271Y-75342D01*
X203249D01*
X203231D01*
X203220D01*
X203216D01*
X203121Y-75346D01*
X203034Y-75353D01*
X202954Y-75368D01*
X202881Y-75382D01*
X202819Y-75393D01*
X202794Y-75400D01*
X202772Y-75408D01*
X202754Y-75411D01*
X202743Y-75415D01*
X202735Y-75419D01*
X202732D01*
X202648Y-75455D01*
X202572Y-75495D01*
X202510Y-75539D01*
X202455Y-75586D01*
X202412Y-75626D01*
X202382Y-75659D01*
X202364Y-75684D01*
X202357Y-75688D01*
Y-75691D01*
X202310Y-75768D01*
X202273Y-75852D01*
X202248Y-75932D01*
X202233Y-76008D01*
X202222Y-76077D01*
X202219Y-76107D01*
Y-76132D01*
X202215Y-76150D01*
Y-76179D01*
X202219Y-76270D01*
X202233Y-76354D01*
X202255Y-76423D01*
X202277Y-76485D01*
X202302Y-76532D01*
X202321Y-76569D01*
X202335Y-76591D01*
X202342Y-76598D01*
X202397Y-76656D01*
X202459Y-76711D01*
X202524Y-76754D01*
X202590Y-76791D01*
X202648Y-76820D01*
X202677Y-76831D01*
X202699Y-76838D01*
X202717Y-76845D01*
X202732Y-76853D01*
X202739Y-76856D01*
X202743D01*
X202666Y-77184D01*
X202601Y-77162D01*
X202543Y-77140D01*
X202488Y-77111D01*
X202433Y-77086D01*
X202386Y-77057D01*
X202342Y-77024D01*
X202299Y-76995D01*
X202262Y-76965D01*
X202233Y-76936D01*
X202204Y-76911D01*
X202179Y-76885D01*
X202160Y-76867D01*
X202142Y-76849D01*
X202131Y-76834D01*
X202128Y-76827D01*
X202124Y-76824D01*
X202091Y-76773D01*
X202059Y-76722D01*
X202033Y-76671D01*
X202011Y-76616D01*
X201978Y-76507D01*
X201957Y-76409D01*
X201946Y-76361D01*
X201942Y-76321D01*
X201938Y-76281D01*
X201935Y-76249D01*
X201931Y-76223D01*
Y-76187D01*
X201938Y-76066D01*
X201957Y-75950D01*
X201978Y-75848D01*
X201993Y-75801D01*
X202008Y-75757D01*
X202022Y-75717D01*
X202037Y-75681D01*
X202047Y-75652D01*
X202059Y-75622D01*
X202069Y-75604D01*
X202077Y-75590D01*
X202080Y-75579D01*
X202084Y-75575D01*
X202146Y-75477D01*
X202219Y-75393D01*
X202291Y-75320D01*
X202364Y-75258D01*
X202430Y-75211D01*
X202459Y-75193D01*
X202484Y-75178D01*
X202502Y-75164D01*
X202517Y-75156D01*
X202528Y-75153D01*
X202532Y-75149D01*
X202644Y-75098D01*
X202761Y-75062D01*
X202877Y-75036D01*
X202983Y-75018D01*
X203030Y-75011D01*
X203078Y-75007D01*
X203114Y-75004D01*
X203151D01*
X203176Y-75000D01*
X203198D01*
X203212D01*
X203216D01*
X203347Y-75007D01*
D02*
G37*
G36*
X202885Y-77515D02*
X202947Y-77522D01*
X203009Y-77530D01*
X203067Y-77544D01*
X203118Y-77562D01*
X203169Y-77581D01*
X203212Y-77599D01*
X203252Y-77621D01*
X203289Y-77639D01*
X203322Y-77657D01*
X203347Y-77675D01*
X203373Y-77694D01*
X203391Y-77708D01*
X203402Y-77715D01*
X203409Y-77723D01*
X203413Y-77726D01*
X203453Y-77766D01*
X203485Y-77810D01*
X203518Y-77854D01*
X203544Y-77901D01*
X203565Y-77945D01*
X203584Y-77988D01*
X203609Y-78072D01*
X203620Y-78109D01*
X203627Y-78145D01*
X203631Y-78174D01*
X203635Y-78203D01*
X203638Y-78225D01*
Y-78254D01*
X203635Y-78323D01*
X203624Y-78389D01*
X203609Y-78447D01*
X203591Y-78502D01*
X203576Y-78542D01*
X203562Y-78574D01*
X203551Y-78596D01*
X203547Y-78604D01*
X203511Y-78662D01*
X203471Y-78713D01*
X203431Y-78756D01*
X203394Y-78793D01*
X203358Y-78818D01*
X203332Y-78840D01*
X203314Y-78855D01*
X203307Y-78858D01*
X203336D01*
X203354D01*
X203365D01*
X203369D01*
X203442Y-78855D01*
X203511Y-78851D01*
X203573Y-78844D01*
X203631Y-78837D01*
X203678Y-78826D01*
X203715Y-78818D01*
X203729Y-78815D01*
X203740D01*
X203744Y-78811D01*
X203747D01*
X203813Y-78793D01*
X203871Y-78775D01*
X203922Y-78756D01*
X203966Y-78738D01*
X203999Y-78724D01*
X204024Y-78709D01*
X204042Y-78702D01*
X204046Y-78698D01*
X204086Y-78669D01*
X204119Y-78640D01*
X204148Y-78611D01*
X204173Y-78582D01*
X204195Y-78560D01*
X204210Y-78538D01*
X204217Y-78523D01*
X204221Y-78520D01*
X204242Y-78480D01*
X204257Y-78436D01*
X204268Y-78396D01*
X204275Y-78356D01*
X204279Y-78323D01*
X204282Y-78298D01*
Y-78272D01*
X204279Y-78214D01*
X204268Y-78159D01*
X204253Y-78112D01*
X204235Y-78072D01*
X204221Y-78043D01*
X204206Y-78017D01*
X204195Y-78003D01*
X204191Y-77999D01*
X204152Y-77963D01*
X204104Y-77934D01*
X204053Y-77908D01*
X204002Y-77890D01*
X203959Y-77876D01*
X203919Y-77865D01*
X203904Y-77861D01*
X203897D01*
X203889Y-77857D01*
X203886D01*
X203911Y-77559D01*
X204017Y-77581D01*
X204108Y-77610D01*
X204188Y-77646D01*
X204253Y-77683D01*
X204304Y-77719D01*
X204326Y-77737D01*
X204344Y-77752D01*
X204355Y-77763D01*
X204366Y-77774D01*
X204370Y-77777D01*
X204374Y-77781D01*
X204403Y-77817D01*
X204428Y-77857D01*
X204468Y-77937D01*
X204497Y-78017D01*
X204516Y-78094D01*
X204530Y-78163D01*
X204534Y-78192D01*
Y-78218D01*
X204537Y-78236D01*
Y-78265D01*
X204530Y-78367D01*
X204516Y-78458D01*
X204490Y-78542D01*
X204461Y-78611D01*
X204450Y-78640D01*
X204435Y-78669D01*
X204421Y-78691D01*
X204410Y-78713D01*
X204403Y-78727D01*
X204395Y-78738D01*
X204388Y-78746D01*
Y-78749D01*
X204326Y-78822D01*
X204257Y-78887D01*
X204184Y-78938D01*
X204115Y-78982D01*
X204053Y-79018D01*
X204024Y-79033D01*
X204002Y-79044D01*
X203980Y-79051D01*
X203966Y-79059D01*
X203959Y-79062D01*
X203955D01*
X203900Y-79080D01*
X203838Y-79099D01*
X203715Y-79124D01*
X203584Y-79142D01*
X203460Y-79153D01*
X203405Y-79160D01*
X203351Y-79164D01*
X203303D01*
X203263Y-79168D01*
X203231D01*
X203205D01*
X203187D01*
X203183D01*
X203099D01*
X203019Y-79164D01*
X202947Y-79157D01*
X202877Y-79150D01*
X202816Y-79142D01*
X202757Y-79135D01*
X202703Y-79124D01*
X202655Y-79113D01*
X202615Y-79102D01*
X202579Y-79095D01*
X202546Y-79084D01*
X202521Y-79077D01*
X202502Y-79070D01*
X202488Y-79062D01*
X202481Y-79059D01*
X202477D01*
X202390Y-79015D01*
X202313Y-78968D01*
X202248Y-78913D01*
X202193Y-78866D01*
X202153Y-78818D01*
X202124Y-78782D01*
X202113Y-78767D01*
X202106Y-78756D01*
X202098Y-78753D01*
Y-78749D01*
X202055Y-78673D01*
X202022Y-78596D01*
X201997Y-78520D01*
X201982Y-78451D01*
X201971Y-78389D01*
X201968Y-78363D01*
Y-78345D01*
X201964Y-78327D01*
Y-78301D01*
X201968Y-78240D01*
X201975Y-78181D01*
X201986Y-78123D01*
X202000Y-78072D01*
X202040Y-77974D01*
X202059Y-77930D01*
X202080Y-77894D01*
X202106Y-77857D01*
X202124Y-77828D01*
X202146Y-77799D01*
X202164Y-77777D01*
X202179Y-77759D01*
X202189Y-77748D01*
X202197Y-77741D01*
X202200Y-77737D01*
X202244Y-77697D01*
X202295Y-77664D01*
X202342Y-77632D01*
X202393Y-77606D01*
X202448Y-77584D01*
X202499Y-77566D01*
X202593Y-77541D01*
X202641Y-77530D01*
X202681Y-77522D01*
X202721Y-77519D01*
X202754Y-77515D01*
X202779Y-77512D01*
X202797D01*
X202812D01*
X202816D01*
X202885Y-77515D01*
D02*
G37*
G36*
Y-79474D02*
X202947Y-79481D01*
X203009Y-79488D01*
X203067Y-79503D01*
X203118Y-79521D01*
X203169Y-79539D01*
X203212Y-79557D01*
X203252Y-79579D01*
X203289Y-79597D01*
X203322Y-79615D01*
X203347Y-79634D01*
X203373Y-79652D01*
X203391Y-79666D01*
X203402Y-79674D01*
X203409Y-79681D01*
X203413Y-79685D01*
X203453Y-79725D01*
X203485Y-79768D01*
X203518Y-79812D01*
X203544Y-79859D01*
X203565Y-79903D01*
X203584Y-79947D01*
X203609Y-80030D01*
X203620Y-80067D01*
X203627Y-80103D01*
X203631Y-80132D01*
X203635Y-80161D01*
X203638Y-80183D01*
Y-80212D01*
X203635Y-80282D01*
X203624Y-80347D01*
X203609Y-80405D01*
X203591Y-80460D01*
X203576Y-80500D01*
X203562Y-80533D01*
X203551Y-80555D01*
X203547Y-80562D01*
X203511Y-80620D01*
X203471Y-80671D01*
X203431Y-80715D01*
X203394Y-80751D01*
X203358Y-80777D01*
X203332Y-80799D01*
X203314Y-80813D01*
X203307Y-80817D01*
X203336D01*
X203354D01*
X203365D01*
X203369D01*
X203442Y-80813D01*
X203511Y-80809D01*
X203573Y-80802D01*
X203631Y-80795D01*
X203678Y-80784D01*
X203715Y-80777D01*
X203729Y-80773D01*
X203740D01*
X203744Y-80769D01*
X203747D01*
X203813Y-80751D01*
X203871Y-80733D01*
X203922Y-80715D01*
X203966Y-80697D01*
X203999Y-80682D01*
X204024Y-80667D01*
X204042Y-80660D01*
X204046Y-80656D01*
X204086Y-80627D01*
X204119Y-80598D01*
X204148Y-80569D01*
X204173Y-80540D01*
X204195Y-80518D01*
X204210Y-80496D01*
X204217Y-80482D01*
X204221Y-80478D01*
X204242Y-80438D01*
X204257Y-80394D01*
X204268Y-80354D01*
X204275Y-80314D01*
X204279Y-80282D01*
X204282Y-80256D01*
Y-80231D01*
X204279Y-80172D01*
X204268Y-80118D01*
X204253Y-80071D01*
X204235Y-80030D01*
X204221Y-80001D01*
X204206Y-79976D01*
X204195Y-79961D01*
X204191Y-79958D01*
X204152Y-79921D01*
X204104Y-79892D01*
X204053Y-79867D01*
X204002Y-79848D01*
X203959Y-79834D01*
X203919Y-79823D01*
X203904Y-79819D01*
X203897D01*
X203889Y-79816D01*
X203886D01*
X203911Y-79517D01*
X204017Y-79539D01*
X204108Y-79568D01*
X204188Y-79605D01*
X204253Y-79641D01*
X204304Y-79677D01*
X204326Y-79696D01*
X204344Y-79710D01*
X204355Y-79721D01*
X204366Y-79732D01*
X204370Y-79736D01*
X204374Y-79739D01*
X204403Y-79776D01*
X204428Y-79816D01*
X204468Y-79896D01*
X204497Y-79976D01*
X204516Y-80052D01*
X204530Y-80121D01*
X204534Y-80151D01*
Y-80176D01*
X204537Y-80194D01*
Y-80223D01*
X204530Y-80325D01*
X204516Y-80416D01*
X204490Y-80500D01*
X204461Y-80569D01*
X204450Y-80598D01*
X204435Y-80627D01*
X204421Y-80649D01*
X204410Y-80671D01*
X204403Y-80686D01*
X204395Y-80697D01*
X204388Y-80704D01*
Y-80708D01*
X204326Y-80780D01*
X204257Y-80846D01*
X204184Y-80897D01*
X204115Y-80940D01*
X204053Y-80977D01*
X204024Y-80991D01*
X204002Y-81002D01*
X203980Y-81010D01*
X203966Y-81017D01*
X203959Y-81020D01*
X203955D01*
X203900Y-81039D01*
X203838Y-81057D01*
X203715Y-81082D01*
X203584Y-81101D01*
X203460Y-81112D01*
X203405Y-81119D01*
X203351Y-81122D01*
X203303D01*
X203263Y-81126D01*
X203231D01*
X203205D01*
X203187D01*
X203183D01*
X203099D01*
X203019Y-81122D01*
X202947Y-81115D01*
X202877Y-81108D01*
X202816Y-81101D01*
X202757Y-81093D01*
X202703Y-81082D01*
X202655Y-81072D01*
X202615Y-81061D01*
X202579Y-81053D01*
X202546Y-81042D01*
X202521Y-81035D01*
X202502Y-81028D01*
X202488Y-81020D01*
X202481Y-81017D01*
X202477D01*
X202390Y-80973D01*
X202313Y-80926D01*
X202248Y-80871D01*
X202193Y-80824D01*
X202153Y-80777D01*
X202124Y-80740D01*
X202113Y-80726D01*
X202106Y-80715D01*
X202098Y-80711D01*
Y-80708D01*
X202055Y-80631D01*
X202022Y-80555D01*
X201997Y-80478D01*
X201982Y-80409D01*
X201971Y-80347D01*
X201968Y-80322D01*
Y-80303D01*
X201964Y-80285D01*
Y-80260D01*
X201968Y-80198D01*
X201975Y-80140D01*
X201986Y-80081D01*
X202000Y-80030D01*
X202040Y-79932D01*
X202059Y-79888D01*
X202080Y-79852D01*
X202106Y-79816D01*
X202124Y-79786D01*
X202146Y-79757D01*
X202164Y-79736D01*
X202179Y-79717D01*
X202189Y-79707D01*
X202197Y-79699D01*
X202200Y-79696D01*
X202244Y-79655D01*
X202295Y-79623D01*
X202342Y-79590D01*
X202393Y-79564D01*
X202448Y-79543D01*
X202499Y-79524D01*
X202593Y-79499D01*
X202641Y-79488D01*
X202681Y-79481D01*
X202721Y-79477D01*
X202754Y-79474D01*
X202779Y-79470D01*
X202797D01*
X202812D01*
X202816D01*
X202885Y-79474D01*
D02*
G37*
G36*
X212983Y-74810D02*
X213110Y-74825D01*
X213223Y-74843D01*
X213278Y-74858D01*
X213325Y-74869D01*
X213369Y-74879D01*
X213409Y-74894D01*
X213445Y-74905D01*
X213474Y-74912D01*
X213496Y-74923D01*
X213514Y-74927D01*
X213525Y-74934D01*
X213529D01*
X213638Y-74989D01*
X213737Y-75051D01*
X213820Y-75116D01*
X213853Y-75149D01*
X213886Y-75178D01*
X213915Y-75207D01*
X213940Y-75236D01*
X213962Y-75262D01*
X213977Y-75284D01*
X213991Y-75298D01*
X214002Y-75313D01*
X214006Y-75320D01*
X214009Y-75324D01*
X214039Y-75375D01*
X214064Y-75425D01*
X214104Y-75535D01*
X214133Y-75644D01*
X214151Y-75749D01*
X214159Y-75801D01*
X214166Y-75844D01*
X214170Y-75884D01*
Y-75917D01*
X214173Y-75946D01*
Y-75986D01*
X214170Y-76059D01*
X214162Y-76128D01*
X214155Y-76194D01*
X214141Y-76256D01*
X214122Y-76314D01*
X214104Y-76368D01*
X214086Y-76419D01*
X214064Y-76467D01*
X214046Y-76507D01*
X214028Y-76547D01*
X214009Y-76576D01*
X213991Y-76605D01*
X213977Y-76623D01*
X213969Y-76641D01*
X213962Y-76649D01*
X213959Y-76652D01*
X213915Y-76703D01*
X213871Y-76747D01*
X213820Y-76787D01*
X213769Y-76827D01*
X213667Y-76893D01*
X213565Y-76943D01*
X213518Y-76965D01*
X213474Y-76983D01*
X213434Y-76998D01*
X213402Y-77009D01*
X213372Y-77020D01*
X213351Y-77027D01*
X213336Y-77031D01*
X213332D01*
X213249Y-76696D01*
X213307Y-76681D01*
X213362Y-76663D01*
X213412Y-76645D01*
X213460Y-76627D01*
X213504Y-76605D01*
X213540Y-76583D01*
X213576Y-76558D01*
X213609Y-76536D01*
X213638Y-76518D01*
X213660Y-76496D01*
X213682Y-76477D01*
X213700Y-76463D01*
X213711Y-76448D01*
X213722Y-76437D01*
X213726Y-76434D01*
X213729Y-76430D01*
X213758Y-76394D01*
X213780Y-76354D01*
X213820Y-76274D01*
X213849Y-76197D01*
X213867Y-76121D01*
X213882Y-76055D01*
X213886Y-76030D01*
Y-76004D01*
X213889Y-75982D01*
Y-75957D01*
X213886Y-75873D01*
X213871Y-75793D01*
X213853Y-75720D01*
X213831Y-75655D01*
X213809Y-75604D01*
X213798Y-75582D01*
X213791Y-75564D01*
X213784Y-75549D01*
X213776Y-75538D01*
X213773Y-75531D01*
Y-75528D01*
X213722Y-75458D01*
X213667Y-75400D01*
X213605Y-75349D01*
X213547Y-75309D01*
X213496Y-75276D01*
X213453Y-75254D01*
X213434Y-75247D01*
X213423Y-75240D01*
X213416Y-75236D01*
X213412D01*
X213318Y-75207D01*
X213223Y-75185D01*
X213129Y-75167D01*
X213041Y-75156D01*
X213001Y-75152D01*
X212965Y-75149D01*
X212932D01*
X212907Y-75145D01*
X212885D01*
X212866D01*
X212856D01*
X212852D01*
X212757Y-75149D01*
X212670Y-75156D01*
X212590Y-75171D01*
X212517Y-75185D01*
X212455Y-75196D01*
X212430Y-75204D01*
X212408Y-75211D01*
X212390Y-75214D01*
X212379Y-75218D01*
X212371Y-75222D01*
X212368D01*
X212284Y-75258D01*
X212208Y-75298D01*
X212146Y-75342D01*
X212091Y-75389D01*
X212048Y-75429D01*
X212018Y-75462D01*
X212000Y-75487D01*
X211993Y-75491D01*
Y-75495D01*
X211946Y-75571D01*
X211909Y-75655D01*
X211884Y-75735D01*
X211869Y-75811D01*
X211858Y-75881D01*
X211855Y-75910D01*
Y-75935D01*
X211851Y-75953D01*
Y-75982D01*
X211855Y-76073D01*
X211869Y-76157D01*
X211891Y-76226D01*
X211913Y-76288D01*
X211938Y-76336D01*
X211957Y-76372D01*
X211971Y-76394D01*
X211978Y-76401D01*
X212033Y-76459D01*
X212095Y-76514D01*
X212160Y-76558D01*
X212226Y-76594D01*
X212284Y-76623D01*
X212313Y-76634D01*
X212335Y-76641D01*
X212353Y-76649D01*
X212368Y-76656D01*
X212375Y-76660D01*
X212379D01*
X212302Y-76987D01*
X212237Y-76965D01*
X212178Y-76943D01*
X212124Y-76914D01*
X212069Y-76889D01*
X212022Y-76860D01*
X211978Y-76827D01*
X211935Y-76798D01*
X211898Y-76769D01*
X211869Y-76740D01*
X211840Y-76714D01*
X211815Y-76689D01*
X211796Y-76670D01*
X211778Y-76652D01*
X211767Y-76638D01*
X211764Y-76630D01*
X211760Y-76627D01*
X211727Y-76576D01*
X211694Y-76525D01*
X211669Y-76474D01*
X211647Y-76419D01*
X211614Y-76310D01*
X211593Y-76212D01*
X211582Y-76165D01*
X211578Y-76124D01*
X211574Y-76084D01*
X211571Y-76052D01*
X211567Y-76026D01*
Y-75990D01*
X211574Y-75870D01*
X211593Y-75753D01*
X211614Y-75651D01*
X211629Y-75604D01*
X211644Y-75560D01*
X211658Y-75520D01*
X211673Y-75484D01*
X211684Y-75455D01*
X211694Y-75425D01*
X211705Y-75407D01*
X211713Y-75393D01*
X211716Y-75382D01*
X211720Y-75378D01*
X211782Y-75280D01*
X211855Y-75196D01*
X211927Y-75123D01*
X212000Y-75062D01*
X212066Y-75014D01*
X212095Y-74996D01*
X212120Y-74981D01*
X212139Y-74967D01*
X212153Y-74960D01*
X212164Y-74956D01*
X212168Y-74952D01*
X212281Y-74901D01*
X212397Y-74865D01*
X212513Y-74840D01*
X212619Y-74821D01*
X212666Y-74814D01*
X212714Y-74810D01*
X212750Y-74807D01*
X212786D01*
X212812Y-74803D01*
X212834D01*
X212848D01*
X212852D01*
X212983Y-74810D01*
D02*
G37*
G36*
X212510Y-77606D02*
X212484Y-77661D01*
X212459Y-77715D01*
X212433Y-77766D01*
X212411Y-77810D01*
X212393Y-77846D01*
X212379Y-77868D01*
X212375Y-77872D01*
Y-77875D01*
X212335Y-77941D01*
X212295Y-77999D01*
X212259Y-78050D01*
X212226Y-78090D01*
X212200Y-78126D01*
X212178Y-78148D01*
X212164Y-78167D01*
X212160Y-78170D01*
X214130D01*
Y-78479D01*
X211600D01*
Y-78279D01*
X211662Y-78243D01*
X211720Y-78203D01*
X211778Y-78156D01*
X211829Y-78112D01*
X211873Y-78068D01*
X211909Y-78035D01*
X211920Y-78021D01*
X211931Y-78010D01*
X211935Y-78006D01*
X211938Y-78003D01*
X212000Y-77926D01*
X212058Y-77850D01*
X212109Y-77777D01*
X212149Y-77704D01*
X212186Y-77642D01*
X212200Y-77617D01*
X212211Y-77595D01*
X212222Y-77577D01*
X212226Y-77562D01*
X212233Y-77555D01*
Y-77551D01*
X212532D01*
X212510Y-77606D01*
D02*
G37*
G36*
X213016Y-79277D02*
X213136Y-79284D01*
X213245Y-79295D01*
X213347Y-79313D01*
X213442Y-79331D01*
X213525Y-79353D01*
X213602Y-79375D01*
X213667Y-79397D01*
X213726Y-79419D01*
X213776Y-79444D01*
X213820Y-79462D01*
X213853Y-79480D01*
X213882Y-79499D01*
X213900Y-79510D01*
X213911Y-79517D01*
X213915Y-79521D01*
X213959Y-79561D01*
X213999Y-79604D01*
X214035Y-79652D01*
X214064Y-79699D01*
X214090Y-79746D01*
X214111Y-79794D01*
X214126Y-79841D01*
X214141Y-79885D01*
X214151Y-79928D01*
X214159Y-79968D01*
X214166Y-80005D01*
X214170Y-80034D01*
X214173Y-80059D01*
Y-80096D01*
X214166Y-80194D01*
X214151Y-80285D01*
X214126Y-80361D01*
X214101Y-80427D01*
X214075Y-80481D01*
X214060Y-80500D01*
X214050Y-80518D01*
X214042Y-80532D01*
X214035Y-80543D01*
X214028Y-80547D01*
Y-80551D01*
X213966Y-80616D01*
X213900Y-80671D01*
X213827Y-80718D01*
X213762Y-80755D01*
X213700Y-80784D01*
X213675Y-80798D01*
X213649Y-80805D01*
X213631Y-80813D01*
X213616Y-80820D01*
X213609Y-80824D01*
X213605D01*
X213551Y-80842D01*
X213496Y-80856D01*
X213380Y-80878D01*
X213260Y-80897D01*
X213143Y-80907D01*
X213092Y-80911D01*
X213045Y-80915D01*
X213001D01*
X212961Y-80918D01*
X212932D01*
X212907D01*
X212892D01*
X212888D01*
X212819D01*
X212754Y-80915D01*
X212695D01*
X212637Y-80911D01*
X212586Y-80904D01*
X212535Y-80900D01*
X212492Y-80897D01*
X212452Y-80889D01*
X212415Y-80886D01*
X212382Y-80878D01*
X212357Y-80875D01*
X212335Y-80871D01*
X212317Y-80867D01*
X212306Y-80864D01*
X212299Y-80860D01*
X212295D01*
X212215Y-80838D01*
X212142Y-80813D01*
X212080Y-80784D01*
X212026Y-80762D01*
X211978Y-80736D01*
X211946Y-80722D01*
X211927Y-80707D01*
X211920Y-80704D01*
X211865Y-80664D01*
X211818Y-80624D01*
X211778Y-80580D01*
X211742Y-80540D01*
X211716Y-80503D01*
X211698Y-80474D01*
X211687Y-80456D01*
X211684Y-80452D01*
Y-80449D01*
X211654Y-80391D01*
X211636Y-80329D01*
X211622Y-80270D01*
X211611Y-80216D01*
X211603Y-80168D01*
X211600Y-80128D01*
Y-80096D01*
X211607Y-79997D01*
X211622Y-79906D01*
X211647Y-79830D01*
X211673Y-79764D01*
X211702Y-79710D01*
X211713Y-79688D01*
X211727Y-79670D01*
X211735Y-79655D01*
X211742Y-79644D01*
X211749Y-79641D01*
Y-79637D01*
X211807Y-79571D01*
X211876Y-79517D01*
X211946Y-79470D01*
X212011Y-79433D01*
X212073Y-79404D01*
X212099Y-79390D01*
X212124Y-79382D01*
X212142Y-79375D01*
X212157Y-79368D01*
X212164Y-79364D01*
X212168D01*
X212222Y-79349D01*
X212277Y-79335D01*
X212397Y-79313D01*
X212517Y-79295D01*
X212630Y-79284D01*
X212684Y-79280D01*
X212732Y-79277D01*
X212775D01*
X212815Y-79273D01*
X212845D01*
X212870D01*
X212885D01*
X212888D01*
X213016Y-79277D01*
D02*
G37*
G36*
Y-81235D02*
X213136Y-81242D01*
X213245Y-81253D01*
X213347Y-81271D01*
X213442Y-81290D01*
X213525Y-81311D01*
X213602Y-81333D01*
X213667Y-81355D01*
X213726Y-81377D01*
X213776Y-81402D01*
X213820Y-81421D01*
X213853Y-81439D01*
X213882Y-81457D01*
X213900Y-81468D01*
X213911Y-81475D01*
X213915Y-81479D01*
X213959Y-81519D01*
X213999Y-81563D01*
X214035Y-81610D01*
X214064Y-81657D01*
X214090Y-81704D01*
X214111Y-81752D01*
X214126Y-81799D01*
X214141Y-81843D01*
X214151Y-81887D01*
X214159Y-81927D01*
X214166Y-81963D01*
X214170Y-81992D01*
X214173Y-82018D01*
Y-82054D01*
X214166Y-82152D01*
X214151Y-82243D01*
X214126Y-82320D01*
X214101Y-82385D01*
X214075Y-82440D01*
X214060Y-82458D01*
X214050Y-82476D01*
X214042Y-82491D01*
X214035Y-82502D01*
X214028Y-82505D01*
Y-82509D01*
X213966Y-82574D01*
X213900Y-82629D01*
X213827Y-82676D01*
X213762Y-82713D01*
X213700Y-82742D01*
X213675Y-82757D01*
X213649Y-82764D01*
X213631Y-82771D01*
X213616Y-82778D01*
X213609Y-82782D01*
X213605D01*
X213551Y-82800D01*
X213496Y-82815D01*
X213380Y-82837D01*
X213260Y-82855D01*
X213143Y-82866D01*
X213092Y-82869D01*
X213045Y-82873D01*
X213001D01*
X212961Y-82877D01*
X212932D01*
X212907D01*
X212892D01*
X212888D01*
X212819D01*
X212754Y-82873D01*
X212695D01*
X212637Y-82869D01*
X212586Y-82862D01*
X212535Y-82858D01*
X212492Y-82855D01*
X212452Y-82847D01*
X212415Y-82844D01*
X212382Y-82837D01*
X212357Y-82833D01*
X212335Y-82829D01*
X212317Y-82826D01*
X212306Y-82822D01*
X212299Y-82818D01*
X212295D01*
X212215Y-82797D01*
X212142Y-82771D01*
X212080Y-82742D01*
X212026Y-82720D01*
X211978Y-82695D01*
X211946Y-82680D01*
X211927Y-82665D01*
X211920Y-82662D01*
X211865Y-82622D01*
X211818Y-82582D01*
X211778Y-82538D01*
X211742Y-82498D01*
X211716Y-82462D01*
X211698Y-82433D01*
X211687Y-82414D01*
X211684Y-82411D01*
Y-82407D01*
X211654Y-82349D01*
X211636Y-82287D01*
X211622Y-82229D01*
X211611Y-82174D01*
X211603Y-82127D01*
X211600Y-82087D01*
Y-82054D01*
X211607Y-81956D01*
X211622Y-81865D01*
X211647Y-81788D01*
X211673Y-81723D01*
X211702Y-81668D01*
X211713Y-81646D01*
X211727Y-81628D01*
X211735Y-81613D01*
X211742Y-81603D01*
X211749Y-81599D01*
Y-81595D01*
X211807Y-81530D01*
X211876Y-81475D01*
X211946Y-81428D01*
X212011Y-81392D01*
X212073Y-81362D01*
X212099Y-81348D01*
X212124Y-81340D01*
X212142Y-81333D01*
X212157Y-81326D01*
X212164Y-81322D01*
X212168D01*
X212222Y-81308D01*
X212277Y-81293D01*
X212397Y-81271D01*
X212517Y-81253D01*
X212630Y-81242D01*
X212684Y-81239D01*
X212732Y-81235D01*
X212775D01*
X212815Y-81231D01*
X212845D01*
X212870D01*
X212885D01*
X212888D01*
X213016Y-81235D01*
D02*
G37*
G36*
X407008Y-126958D02*
X407077Y-126965D01*
X407142Y-126980D01*
X407204Y-126998D01*
X407259Y-127023D01*
X407313Y-127045D01*
X407361Y-127074D01*
X407404Y-127100D01*
X407441Y-127125D01*
X407477Y-127154D01*
X407506Y-127176D01*
X407528Y-127198D01*
X407546Y-127220D01*
X407561Y-127234D01*
X407568Y-127242D01*
X407572Y-127245D01*
X407619Y-127311D01*
X407659Y-127387D01*
X407696Y-127467D01*
X407728Y-127551D01*
X407754Y-127638D01*
X407776Y-127726D01*
X407794Y-127817D01*
X407808Y-127901D01*
X407819Y-127984D01*
X407827Y-128061D01*
X407834Y-128130D01*
X407837Y-128188D01*
Y-128239D01*
X407841Y-128276D01*
Y-128290D01*
Y-128301D01*
Y-128305D01*
Y-128308D01*
X407837Y-128425D01*
X407830Y-128534D01*
X407819Y-128636D01*
X407801Y-128730D01*
X407783Y-128814D01*
X407765Y-128891D01*
X407743Y-128960D01*
X407717Y-129022D01*
X407696Y-129073D01*
X407674Y-129120D01*
X407655Y-129156D01*
X407634Y-129189D01*
X407619Y-129215D01*
X407608Y-129229D01*
X407601Y-129240D01*
X407597Y-129244D01*
X407550Y-129295D01*
X407499Y-129338D01*
X407448Y-129375D01*
X407397Y-129408D01*
X407342Y-129437D01*
X407292Y-129458D01*
X407240Y-129477D01*
X407190Y-129491D01*
X407146Y-129502D01*
X407102Y-129513D01*
X407066Y-129520D01*
X407033Y-129524D01*
X407004D01*
X406986Y-129528D01*
X406967D01*
X406884Y-129524D01*
X406807Y-129509D01*
X406738Y-129495D01*
X406676Y-129473D01*
X406629Y-129455D01*
X406593Y-129437D01*
X406578Y-129433D01*
X406567Y-129426D01*
X406564Y-129422D01*
X406560D01*
X406498Y-129378D01*
X406440Y-129327D01*
X406392Y-129276D01*
X406352Y-129226D01*
X406320Y-129178D01*
X406298Y-129142D01*
X406290Y-129127D01*
X406283Y-129116D01*
X406280Y-129113D01*
Y-129109D01*
X406243Y-129033D01*
X406218Y-128953D01*
X406200Y-128880D01*
X406189Y-128811D01*
X406178Y-128752D01*
Y-128730D01*
X406174Y-128709D01*
Y-128690D01*
Y-128680D01*
Y-128672D01*
Y-128669D01*
X406178Y-128603D01*
X406185Y-128541D01*
X406196Y-128479D01*
X406207Y-128425D01*
X406225Y-128374D01*
X406243Y-128323D01*
X406261Y-128279D01*
X406283Y-128239D01*
X406305Y-128203D01*
X406323Y-128170D01*
X406342Y-128144D01*
X406360Y-128119D01*
X406371Y-128101D01*
X406382Y-128090D01*
X406389Y-128083D01*
X406392Y-128079D01*
X406432Y-128039D01*
X406476Y-128002D01*
X406524Y-127973D01*
X406567Y-127948D01*
X406611Y-127922D01*
X406655Y-127904D01*
X406738Y-127879D01*
X406775Y-127868D01*
X406811Y-127860D01*
X406840Y-127857D01*
X406869Y-127853D01*
X406891Y-127850D01*
X406920D01*
X406986Y-127853D01*
X407048Y-127864D01*
X407106Y-127875D01*
X407157Y-127890D01*
X407200Y-127908D01*
X407233Y-127919D01*
X407255Y-127930D01*
X407259Y-127933D01*
X407262D01*
X407321Y-127970D01*
X407372Y-128010D01*
X407419Y-128050D01*
X407455Y-128094D01*
X407488Y-128130D01*
X407514Y-128159D01*
X407528Y-128181D01*
X407532Y-128184D01*
Y-128119D01*
X407528Y-128053D01*
X407524Y-127995D01*
X407517Y-127937D01*
X407514Y-127886D01*
X407506Y-127839D01*
X407499Y-127795D01*
X407488Y-127755D01*
X407481Y-127718D01*
X407474Y-127689D01*
X407466Y-127664D01*
X407463Y-127642D01*
X407455Y-127628D01*
X407452Y-127617D01*
X407448Y-127609D01*
Y-127606D01*
X407412Y-127533D01*
X407375Y-127467D01*
X407335Y-127416D01*
X407299Y-127373D01*
X407266Y-127336D01*
X407240Y-127311D01*
X407222Y-127296D01*
X407215Y-127293D01*
X407171Y-127263D01*
X407128Y-127245D01*
X407084Y-127231D01*
X407040Y-127220D01*
X407008Y-127213D01*
X406979Y-127209D01*
X406953D01*
X406887Y-127216D01*
X406826Y-127231D01*
X406775Y-127253D01*
X406727Y-127275D01*
X406691Y-127300D01*
X406665Y-127322D01*
X406651Y-127336D01*
X406644Y-127344D01*
X406618Y-127376D01*
X406593Y-127416D01*
X406571Y-127460D01*
X406556Y-127504D01*
X406542Y-127544D01*
X406531Y-127577D01*
X406527Y-127598D01*
X406524Y-127602D01*
Y-127606D01*
X406214Y-127580D01*
X406236Y-127478D01*
X406269Y-127387D01*
X406305Y-127307D01*
X406345Y-127242D01*
X406385Y-127191D01*
X406400Y-127169D01*
X406418Y-127151D01*
X406429Y-127140D01*
X406440Y-127129D01*
X406443Y-127125D01*
X406447Y-127122D01*
X406483Y-127093D01*
X406524Y-127067D01*
X406603Y-127023D01*
X406684Y-126994D01*
X406760Y-126976D01*
X406829Y-126961D01*
X406858Y-126958D01*
X406884D01*
X406906Y-126954D01*
X406935D01*
X407008Y-126958D01*
D02*
G37*
G36*
X410236Y-129484D02*
X409901D01*
Y-128366D01*
X409472D01*
X409432Y-128370D01*
X409403D01*
X409377Y-128374D01*
X409359Y-128377D01*
X409344D01*
X409337Y-128381D01*
X409334D01*
X409275Y-128399D01*
X409250Y-128410D01*
X409228Y-128421D01*
X409206Y-128432D01*
X409192Y-128439D01*
X409184Y-128443D01*
X409181Y-128446D01*
X409152Y-128468D01*
X409122Y-128494D01*
X409068Y-128549D01*
X409042Y-128574D01*
X409024Y-128596D01*
X409013Y-128610D01*
X409010Y-128614D01*
X408973Y-128665D01*
X408933Y-128719D01*
X408893Y-128778D01*
X408853Y-128832D01*
X408820Y-128883D01*
X408795Y-128923D01*
X408784Y-128938D01*
X408777Y-128949D01*
X408769Y-128956D01*
Y-128960D01*
X408438Y-129484D01*
X408023D01*
X408456Y-128800D01*
X408507Y-128727D01*
X408555Y-128661D01*
X408602Y-128607D01*
X408642Y-128556D01*
X408678Y-128519D01*
X408708Y-128490D01*
X408726Y-128472D01*
X408733Y-128465D01*
X408762Y-128443D01*
X408795Y-128417D01*
X408860Y-128377D01*
X408889Y-128363D01*
X408911Y-128348D01*
X408926Y-128341D01*
X408933Y-128337D01*
X408868Y-128326D01*
X408806Y-128315D01*
X408751Y-128297D01*
X408697Y-128283D01*
X408649Y-128264D01*
X408605Y-128243D01*
X408566Y-128225D01*
X408529Y-128206D01*
X408500Y-128184D01*
X408471Y-128166D01*
X408449Y-128152D01*
X408431Y-128137D01*
X408416Y-128126D01*
X408405Y-128115D01*
X408402Y-128112D01*
X408398Y-128108D01*
X408369Y-128072D01*
X408340Y-128035D01*
X408296Y-127959D01*
X408267Y-127882D01*
X408245Y-127810D01*
X408231Y-127748D01*
X408227Y-127722D01*
Y-127697D01*
X408223Y-127679D01*
Y-127664D01*
Y-127657D01*
Y-127653D01*
X408227Y-127577D01*
X408238Y-127507D01*
X408256Y-127442D01*
X408274Y-127387D01*
X408296Y-127340D01*
X408311Y-127304D01*
X408325Y-127282D01*
X408329Y-127278D01*
Y-127275D01*
X408373Y-127216D01*
X408416Y-127165D01*
X408464Y-127122D01*
X408507Y-127089D01*
X408547Y-127063D01*
X408580Y-127049D01*
X408602Y-127038D01*
X408605Y-127034D01*
X408609D01*
X408642Y-127023D01*
X408682Y-127012D01*
X408762Y-126994D01*
X408849Y-126983D01*
X408929Y-126972D01*
X409006Y-126969D01*
X409039D01*
X409068Y-126965D01*
X410236D01*
Y-129484D01*
D02*
G37*
G36*
X405846Y-127296D02*
X404612D01*
X404700Y-127402D01*
X404784Y-127515D01*
X404856Y-127624D01*
X404925Y-127729D01*
X404955Y-127777D01*
X404980Y-127821D01*
X405006Y-127860D01*
X405024Y-127893D01*
X405038Y-127922D01*
X405049Y-127941D01*
X405057Y-127955D01*
X405060Y-127959D01*
X405133Y-128104D01*
X405198Y-128250D01*
X405253Y-128388D01*
X405275Y-128450D01*
X405297Y-128512D01*
X405319Y-128567D01*
X405333Y-128618D01*
X405348Y-128661D01*
X405359Y-128698D01*
X405370Y-128730D01*
X405377Y-128752D01*
X405380Y-128767D01*
Y-128770D01*
X405417Y-128920D01*
X405432Y-128992D01*
X405442Y-129058D01*
X405453Y-129120D01*
X405464Y-129182D01*
X405472Y-129233D01*
X405479Y-129284D01*
X405482Y-129327D01*
X405486Y-129367D01*
X405490Y-129404D01*
Y-129433D01*
X405493Y-129455D01*
Y-129469D01*
Y-129480D01*
Y-129484D01*
X405177D01*
X405166Y-129346D01*
X405148Y-129218D01*
X405129Y-129102D01*
X405118Y-129047D01*
X405107Y-128996D01*
X405100Y-128953D01*
X405089Y-128912D01*
X405082Y-128876D01*
X405075Y-128847D01*
X405067Y-128825D01*
X405064Y-128807D01*
X405060Y-128796D01*
Y-128792D01*
X405006Y-128625D01*
X404947Y-128468D01*
X404918Y-128392D01*
X404889Y-128319D01*
X404856Y-128254D01*
X404827Y-128188D01*
X404802Y-128130D01*
X404776Y-128079D01*
X404754Y-128035D01*
X404736Y-127995D01*
X404718Y-127962D01*
X404707Y-127941D01*
X404700Y-127926D01*
X404696Y-127922D01*
X404653Y-127846D01*
X404609Y-127769D01*
X404565Y-127700D01*
X404522Y-127635D01*
X404481Y-127577D01*
X404441Y-127518D01*
X404401Y-127467D01*
X404369Y-127424D01*
X404336Y-127380D01*
X404307Y-127344D01*
X404278Y-127314D01*
X404256Y-127289D01*
X404241Y-127267D01*
X404227Y-127253D01*
X404219Y-127245D01*
X404216Y-127242D01*
Y-126998D01*
X405846D01*
Y-127296D01*
D02*
G37*
G36*
X413182Y-123176D02*
X412891Y-123216D01*
X412865Y-123176D01*
X412832Y-123143D01*
X412803Y-123110D01*
X412774Y-123084D01*
X412745Y-123066D01*
X412723Y-123048D01*
X412709Y-123041D01*
X412705Y-123037D01*
X412658Y-123015D01*
X412610Y-122997D01*
X412567Y-122986D01*
X412523Y-122975D01*
X412487Y-122972D01*
X412458Y-122968D01*
X412388D01*
X412345Y-122975D01*
X412268Y-122994D01*
X412203Y-123019D01*
X412145Y-123045D01*
X412101Y-123074D01*
X412068Y-123099D01*
X412050Y-123117D01*
X412043Y-123121D01*
Y-123125D01*
X411992Y-123187D01*
X411955Y-123252D01*
X411930Y-123321D01*
X411911Y-123390D01*
X411901Y-123449D01*
X411897Y-123474D01*
Y-123496D01*
X411893Y-123514D01*
Y-123529D01*
Y-123536D01*
Y-123539D01*
Y-123591D01*
X411901Y-123638D01*
X411919Y-123729D01*
X411944Y-123805D01*
X411970Y-123867D01*
X411999Y-123918D01*
X412024Y-123958D01*
X412035Y-123969D01*
X412043Y-123980D01*
X412046Y-123984D01*
X412050Y-123987D01*
X412079Y-124016D01*
X412108Y-124042D01*
X412174Y-124085D01*
X412235Y-124115D01*
X412297Y-124133D01*
X412348Y-124147D01*
X412392Y-124151D01*
X412407Y-124155D01*
X412428D01*
X412498Y-124151D01*
X412559Y-124136D01*
X412614Y-124118D01*
X412658Y-124097D01*
X412698Y-124075D01*
X412727Y-124056D01*
X412741Y-124042D01*
X412749Y-124038D01*
X412792Y-123987D01*
X412829Y-123933D01*
X412858Y-123871D01*
X412880Y-123816D01*
X412894Y-123762D01*
X412905Y-123722D01*
X412909Y-123703D01*
X412913Y-123692D01*
Y-123685D01*
Y-123681D01*
X413237Y-123707D01*
X413229Y-123765D01*
X413218Y-123820D01*
X413186Y-123922D01*
X413145Y-124009D01*
X413124Y-124049D01*
X413102Y-124082D01*
X413084Y-124115D01*
X413062Y-124144D01*
X413044Y-124166D01*
X413025Y-124184D01*
X413011Y-124198D01*
X413003Y-124213D01*
X412996Y-124217D01*
X412993Y-124220D01*
X412949Y-124253D01*
X412905Y-124282D01*
X412858Y-124308D01*
X412811Y-124329D01*
X412720Y-124362D01*
X412629Y-124384D01*
X412589Y-124395D01*
X412548Y-124399D01*
X412516Y-124402D01*
X412487Y-124406D01*
X412461Y-124409D01*
X412428D01*
X412352Y-124406D01*
X412279Y-124395D01*
X412210Y-124380D01*
X412148Y-124362D01*
X412090Y-124337D01*
X412035Y-124311D01*
X411984Y-124286D01*
X411941Y-124257D01*
X411901Y-124227D01*
X411864Y-124202D01*
X411835Y-124173D01*
X411810Y-124151D01*
X411791Y-124133D01*
X411777Y-124118D01*
X411770Y-124107D01*
X411766Y-124104D01*
X411729Y-124056D01*
X411700Y-124005D01*
X411671Y-123958D01*
X411649Y-123907D01*
X411613Y-123809D01*
X411591Y-123714D01*
X411584Y-123674D01*
X411577Y-123634D01*
X411573Y-123601D01*
X411569Y-123572D01*
X411566Y-123547D01*
Y-123529D01*
Y-123518D01*
Y-123514D01*
X411569Y-123449D01*
X411577Y-123387D01*
X411588Y-123325D01*
X411602Y-123270D01*
X411620Y-123219D01*
X411638Y-123168D01*
X411660Y-123125D01*
X411679Y-123084D01*
X411700Y-123048D01*
X411722Y-123015D01*
X411740Y-122990D01*
X411759Y-122964D01*
X411773Y-122946D01*
X411784Y-122935D01*
X411791Y-122928D01*
X411795Y-122924D01*
X411839Y-122884D01*
X411882Y-122848D01*
X411930Y-122819D01*
X411977Y-122793D01*
X412024Y-122768D01*
X412072Y-122750D01*
X412159Y-122724D01*
X412199Y-122713D01*
X412235Y-122706D01*
X412268Y-122702D01*
X412297Y-122699D01*
X412319Y-122695D01*
X412399D01*
X412443Y-122702D01*
X412530Y-122721D01*
X412610Y-122746D01*
X412683Y-122775D01*
X412741Y-122804D01*
X412767Y-122819D01*
X412789Y-122830D01*
X412807Y-122841D01*
X412818Y-122848D01*
X412825Y-122852D01*
X412829Y-122855D01*
X412694Y-122175D01*
X411686D01*
Y-121880D01*
X412938D01*
X413182Y-123176D01*
D02*
G37*
G36*
X414682Y-121810D02*
X414798Y-121829D01*
X414900Y-121851D01*
X414947Y-121865D01*
X414991Y-121880D01*
X415031Y-121894D01*
X415067Y-121909D01*
X415097Y-121920D01*
X415126Y-121931D01*
X415144Y-121942D01*
X415158Y-121949D01*
X415169Y-121952D01*
X415173Y-121956D01*
X415271Y-122018D01*
X415355Y-122091D01*
X415428Y-122164D01*
X415490Y-122236D01*
X415537Y-122302D01*
X415555Y-122331D01*
X415570Y-122356D01*
X415584Y-122375D01*
X415592Y-122389D01*
X415595Y-122400D01*
X415599Y-122404D01*
X415650Y-122517D01*
X415686Y-122633D01*
X415712Y-122750D01*
X415730Y-122855D01*
X415737Y-122903D01*
X415741Y-122950D01*
X415744Y-122986D01*
Y-123023D01*
X415748Y-123048D01*
Y-123070D01*
Y-123084D01*
Y-123088D01*
X415741Y-123219D01*
X415726Y-123347D01*
X415708Y-123459D01*
X415694Y-123514D01*
X415683Y-123561D01*
X415672Y-123605D01*
X415657Y-123645D01*
X415646Y-123681D01*
X415639Y-123711D01*
X415628Y-123732D01*
X415624Y-123751D01*
X415617Y-123762D01*
Y-123765D01*
X415562Y-123874D01*
X415501Y-123973D01*
X415435Y-124056D01*
X415402Y-124089D01*
X415373Y-124122D01*
X415344Y-124151D01*
X415315Y-124177D01*
X415289Y-124198D01*
X415268Y-124213D01*
X415253Y-124227D01*
X415239Y-124238D01*
X415231Y-124242D01*
X415228Y-124246D01*
X415177Y-124275D01*
X415126Y-124300D01*
X415016Y-124340D01*
X414907Y-124370D01*
X414802Y-124388D01*
X414751Y-124395D01*
X414707Y-124402D01*
X414667Y-124406D01*
X414634D01*
X414605Y-124409D01*
X414565D01*
X414492Y-124406D01*
X414423Y-124399D01*
X414358Y-124391D01*
X414296Y-124377D01*
X414237Y-124358D01*
X414183Y-124340D01*
X414132Y-124322D01*
X414085Y-124300D01*
X414045Y-124282D01*
X414005Y-124264D01*
X413975Y-124246D01*
X413946Y-124227D01*
X413928Y-124213D01*
X413910Y-124206D01*
X413903Y-124198D01*
X413899Y-124195D01*
X413848Y-124151D01*
X413804Y-124107D01*
X413764Y-124056D01*
X413724Y-124005D01*
X413659Y-123904D01*
X413608Y-123802D01*
X413586Y-123754D01*
X413568Y-123711D01*
X413553Y-123671D01*
X413542Y-123638D01*
X413531Y-123609D01*
X413524Y-123587D01*
X413520Y-123572D01*
Y-123569D01*
X413855Y-123485D01*
X413870Y-123543D01*
X413888Y-123598D01*
X413906Y-123649D01*
X413924Y-123696D01*
X413946Y-123740D01*
X413968Y-123776D01*
X413994Y-123812D01*
X414015Y-123845D01*
X414034Y-123874D01*
X414055Y-123896D01*
X414074Y-123918D01*
X414088Y-123936D01*
X414103Y-123947D01*
X414114Y-123958D01*
X414117Y-123962D01*
X414121Y-123965D01*
X414157Y-123995D01*
X414197Y-124016D01*
X414278Y-124056D01*
X414354Y-124085D01*
X414430Y-124104D01*
X414496Y-124118D01*
X414521Y-124122D01*
X414547D01*
X414569Y-124126D01*
X414594D01*
X414678Y-124122D01*
X414758Y-124107D01*
X414831Y-124089D01*
X414896Y-124067D01*
X414947Y-124046D01*
X414969Y-124035D01*
X414987Y-124027D01*
X415002Y-124020D01*
X415013Y-124013D01*
X415020Y-124009D01*
X415024D01*
X415093Y-123958D01*
X415151Y-123904D01*
X415202Y-123842D01*
X415242Y-123783D01*
X415275Y-123732D01*
X415297Y-123689D01*
X415304Y-123671D01*
X415311Y-123660D01*
X415315Y-123652D01*
Y-123649D01*
X415344Y-123554D01*
X415366Y-123459D01*
X415384Y-123365D01*
X415395Y-123277D01*
X415399Y-123237D01*
X415402Y-123201D01*
Y-123168D01*
X415406Y-123143D01*
Y-123121D01*
Y-123103D01*
Y-123092D01*
Y-123088D01*
X415402Y-122994D01*
X415395Y-122906D01*
X415380Y-122826D01*
X415366Y-122753D01*
X415355Y-122691D01*
X415348Y-122666D01*
X415340Y-122644D01*
X415337Y-122626D01*
X415333Y-122615D01*
X415330Y-122608D01*
Y-122604D01*
X415293Y-122520D01*
X415253Y-122444D01*
X415209Y-122382D01*
X415162Y-122327D01*
X415122Y-122284D01*
X415089Y-122255D01*
X415064Y-122236D01*
X415060Y-122229D01*
X415057D01*
X414980Y-122182D01*
X414896Y-122145D01*
X414816Y-122120D01*
X414740Y-122105D01*
X414671Y-122095D01*
X414642Y-122091D01*
X414616D01*
X414598Y-122087D01*
X414569D01*
X414478Y-122091D01*
X414394Y-122105D01*
X414325Y-122127D01*
X414263Y-122149D01*
X414216Y-122175D01*
X414179Y-122193D01*
X414157Y-122207D01*
X414150Y-122215D01*
X414092Y-122269D01*
X414037Y-122331D01*
X413994Y-122397D01*
X413957Y-122462D01*
X413928Y-122520D01*
X413917Y-122549D01*
X413910Y-122571D01*
X413903Y-122590D01*
X413895Y-122604D01*
X413892Y-122611D01*
Y-122615D01*
X413564Y-122538D01*
X413586Y-122473D01*
X413608Y-122415D01*
X413637Y-122360D01*
X413662Y-122306D01*
X413692Y-122258D01*
X413724Y-122215D01*
X413753Y-122171D01*
X413783Y-122134D01*
X413812Y-122105D01*
X413837Y-122076D01*
X413863Y-122051D01*
X413881Y-122033D01*
X413899Y-122014D01*
X413913Y-122003D01*
X413921Y-122000D01*
X413924Y-121996D01*
X413975Y-121963D01*
X414026Y-121931D01*
X414077Y-121905D01*
X414132Y-121883D01*
X414241Y-121851D01*
X414339Y-121829D01*
X414387Y-121818D01*
X414427Y-121814D01*
X414467Y-121810D01*
X414500Y-121807D01*
X414525Y-121803D01*
X414561D01*
X414682Y-121810D01*
D02*
G37*
G36*
X424869Y-130111D02*
X424967Y-130129D01*
X425051Y-130158D01*
X425124Y-130187D01*
X425156Y-130206D01*
X425182Y-130220D01*
X425208Y-130235D01*
X425226Y-130249D01*
X425240Y-130260D01*
X425251Y-130268D01*
X425258Y-130271D01*
X425262Y-130275D01*
X425331Y-130344D01*
X425386Y-130420D01*
X425430Y-130500D01*
X425466Y-130581D01*
X425488Y-130650D01*
X425499Y-130679D01*
X425506Y-130704D01*
X425510Y-130726D01*
X425513Y-130741D01*
X425517Y-130752D01*
Y-130755D01*
X425208Y-130810D01*
X425193Y-130730D01*
X425171Y-130661D01*
X425146Y-130602D01*
X425120Y-130555D01*
X425095Y-130519D01*
X425073Y-130493D01*
X425058Y-130475D01*
X425055Y-130471D01*
X425007Y-130435D01*
X424956Y-130406D01*
X424909Y-130388D01*
X424862Y-130373D01*
X424818Y-130366D01*
X424785Y-130359D01*
X424756D01*
X424691Y-130362D01*
X424632Y-130377D01*
X424581Y-130395D01*
X424538Y-130413D01*
X424505Y-130435D01*
X424479Y-130453D01*
X424461Y-130468D01*
X424458Y-130471D01*
X424418Y-130515D01*
X424389Y-130562D01*
X424370Y-130610D01*
X424356Y-130653D01*
X424348Y-130693D01*
X424341Y-130722D01*
Y-130744D01*
Y-130748D01*
Y-130752D01*
Y-130792D01*
X424348Y-130828D01*
X424367Y-130890D01*
X424392Y-130945D01*
X424421Y-130992D01*
X424450Y-131025D01*
X424476Y-131050D01*
X424494Y-131065D01*
X424498Y-131068D01*
X424501D01*
X424563Y-131101D01*
X424621Y-131127D01*
X424683Y-131145D01*
X424738Y-131156D01*
X424785Y-131163D01*
X424825Y-131170D01*
X424873D01*
X424887Y-131167D01*
X424905D01*
X424942Y-131440D01*
X424895Y-131429D01*
X424851Y-131421D01*
X424814Y-131414D01*
X424782Y-131411D01*
X424756Y-131407D01*
X424723D01*
X424647Y-131414D01*
X424578Y-131429D01*
X424516Y-131450D01*
X424465Y-131476D01*
X424425Y-131501D01*
X424396Y-131523D01*
X424378Y-131538D01*
X424370Y-131545D01*
X424323Y-131600D01*
X424287Y-131658D01*
X424261Y-131716D01*
X424247Y-131774D01*
X424236Y-131822D01*
X424232Y-131862D01*
X424228Y-131876D01*
Y-131887D01*
Y-131895D01*
Y-131898D01*
X424236Y-131978D01*
X424254Y-132051D01*
X424276Y-132113D01*
X424305Y-132168D01*
X424334Y-132211D01*
X424356Y-132244D01*
X424374Y-132266D01*
X424381Y-132273D01*
X424439Y-132324D01*
X424501Y-132360D01*
X424563Y-132386D01*
X424621Y-132404D01*
X424672Y-132415D01*
X424713Y-132419D01*
X424727Y-132422D01*
X424749D01*
X424814Y-132419D01*
X424876Y-132404D01*
X424931Y-132386D01*
X424974Y-132364D01*
X425011Y-132346D01*
X425040Y-132328D01*
X425055Y-132313D01*
X425062Y-132310D01*
X425106Y-132259D01*
X425142Y-132200D01*
X425175Y-132139D01*
X425200Y-132073D01*
X425218Y-132018D01*
X425226Y-131993D01*
X425229Y-131971D01*
X425233Y-131953D01*
X425237Y-131938D01*
X425240Y-131931D01*
Y-131927D01*
X425550Y-131967D01*
X425542Y-132026D01*
X425531Y-132080D01*
X425499Y-132182D01*
X425459Y-132270D01*
X425437Y-132306D01*
X425415Y-132342D01*
X425393Y-132375D01*
X425371Y-132401D01*
X425353Y-132426D01*
X425335Y-132444D01*
X425324Y-132459D01*
X425313Y-132470D01*
X425306Y-132477D01*
X425302Y-132481D01*
X425258Y-132513D01*
X425215Y-132546D01*
X425171Y-132572D01*
X425124Y-132594D01*
X425033Y-132630D01*
X424945Y-132652D01*
X424905Y-132659D01*
X424869Y-132666D01*
X424836Y-132670D01*
X424807Y-132674D01*
X424785Y-132677D01*
X424753D01*
X424683Y-132674D01*
X424621Y-132666D01*
X424560Y-132655D01*
X424501Y-132641D01*
X424447Y-132623D01*
X424399Y-132604D01*
X424352Y-132583D01*
X424312Y-132561D01*
X424272Y-132543D01*
X424239Y-132521D01*
X424210Y-132502D01*
X424188Y-132484D01*
X424170Y-132470D01*
X424156Y-132459D01*
X424148Y-132451D01*
X424145Y-132448D01*
X424101Y-132404D01*
X424064Y-132357D01*
X424032Y-132310D01*
X424003Y-132262D01*
X423981Y-132219D01*
X423959Y-132171D01*
X423930Y-132084D01*
X423923Y-132044D01*
X423915Y-132008D01*
X423908Y-131975D01*
X423904Y-131946D01*
X423901Y-131924D01*
Y-131905D01*
Y-131895D01*
Y-131891D01*
X423904Y-131804D01*
X423919Y-131723D01*
X423941Y-131654D01*
X423963Y-131596D01*
X423984Y-131549D01*
X424006Y-131512D01*
X424021Y-131491D01*
X424024Y-131483D01*
X424076Y-131429D01*
X424130Y-131381D01*
X424188Y-131345D01*
X424247Y-131316D01*
X424298Y-131294D01*
X424338Y-131280D01*
X424352Y-131276D01*
X424363Y-131272D01*
X424370Y-131269D01*
X424374D01*
X424312Y-131236D01*
X424261Y-131203D01*
X424217Y-131167D01*
X424181Y-131134D01*
X424152Y-131105D01*
X424130Y-131079D01*
X424119Y-131065D01*
X424116Y-131057D01*
X424086Y-131007D01*
X424064Y-130956D01*
X424046Y-130904D01*
X424035Y-130857D01*
X424028Y-130817D01*
X424024Y-130788D01*
Y-130766D01*
Y-130759D01*
X424028Y-130697D01*
X424039Y-130635D01*
X424054Y-130581D01*
X424072Y-130533D01*
X424090Y-130493D01*
X424105Y-130461D01*
X424116Y-130442D01*
X424119Y-130435D01*
X424156Y-130380D01*
X424199Y-130333D01*
X424243Y-130293D01*
X424287Y-130257D01*
X424323Y-130231D01*
X424356Y-130209D01*
X424378Y-130198D01*
X424381Y-130195D01*
X424385D01*
X424450Y-130166D01*
X424516Y-130144D01*
X424581Y-130126D01*
X424640Y-130115D01*
X424687Y-130107D01*
X424727Y-130104D01*
X424818D01*
X424869Y-130111D01*
D02*
G37*
G36*
X426693Y-130107D02*
X426762Y-130115D01*
X426827Y-130129D01*
X426889Y-130147D01*
X426944Y-130173D01*
X426998Y-130195D01*
X427046Y-130224D01*
X427089Y-130249D01*
X427126Y-130275D01*
X427162Y-130304D01*
X427191Y-130326D01*
X427213Y-130348D01*
X427231Y-130369D01*
X427246Y-130384D01*
X427253Y-130391D01*
X427257Y-130395D01*
X427304Y-130461D01*
X427344Y-130537D01*
X427381Y-130617D01*
X427413Y-130701D01*
X427439Y-130788D01*
X427461Y-130875D01*
X427479Y-130966D01*
X427493Y-131050D01*
X427504Y-131134D01*
X427512Y-131210D01*
X427519Y-131280D01*
X427523Y-131338D01*
Y-131389D01*
X427526Y-131425D01*
Y-131440D01*
Y-131450D01*
Y-131454D01*
Y-131458D01*
X427523Y-131574D01*
X427515Y-131684D01*
X427504Y-131785D01*
X427486Y-131880D01*
X427468Y-131964D01*
X427450Y-132040D01*
X427428Y-132109D01*
X427402Y-132171D01*
X427381Y-132222D01*
X427359Y-132270D01*
X427341Y-132306D01*
X427319Y-132339D01*
X427304Y-132364D01*
X427293Y-132379D01*
X427286Y-132390D01*
X427282Y-132393D01*
X427235Y-132444D01*
X427184Y-132488D01*
X427133Y-132524D01*
X427082Y-132557D01*
X427028Y-132586D01*
X426977Y-132608D01*
X426926Y-132626D01*
X426875Y-132641D01*
X426831Y-132652D01*
X426787Y-132663D01*
X426751Y-132670D01*
X426718Y-132674D01*
X426689D01*
X426671Y-132677D01*
X426653D01*
X426569Y-132674D01*
X426492Y-132659D01*
X426423Y-132644D01*
X426361Y-132623D01*
X426314Y-132604D01*
X426278Y-132586D01*
X426263Y-132583D01*
X426252Y-132575D01*
X426249Y-132572D01*
X426245D01*
X426183Y-132528D01*
X426125Y-132477D01*
X426078Y-132426D01*
X426037Y-132375D01*
X426005Y-132328D01*
X425983Y-132291D01*
X425976Y-132277D01*
X425968Y-132266D01*
X425965Y-132262D01*
Y-132259D01*
X425928Y-132182D01*
X425903Y-132102D01*
X425885Y-132029D01*
X425874Y-131960D01*
X425863Y-131902D01*
Y-131880D01*
X425859Y-131858D01*
Y-131840D01*
Y-131829D01*
Y-131822D01*
Y-131818D01*
X425863Y-131753D01*
X425870Y-131691D01*
X425881Y-131629D01*
X425892Y-131574D01*
X425910Y-131523D01*
X425928Y-131472D01*
X425946Y-131429D01*
X425968Y-131389D01*
X425990Y-131352D01*
X426008Y-131319D01*
X426026Y-131294D01*
X426045Y-131269D01*
X426056Y-131250D01*
X426067Y-131239D01*
X426074Y-131232D01*
X426078Y-131228D01*
X426118Y-131188D01*
X426161Y-131152D01*
X426208Y-131123D01*
X426252Y-131097D01*
X426296Y-131072D01*
X426339Y-131054D01*
X426423Y-131028D01*
X426460Y-131017D01*
X426496Y-131010D01*
X426525Y-131007D01*
X426554Y-131003D01*
X426576Y-130999D01*
X426605D01*
X426671Y-131003D01*
X426733Y-131014D01*
X426791Y-131025D01*
X426842Y-131039D01*
X426886Y-131057D01*
X426918Y-131068D01*
X426940Y-131079D01*
X426944Y-131083D01*
X426947D01*
X427006Y-131119D01*
X427057Y-131159D01*
X427104Y-131199D01*
X427140Y-131243D01*
X427173Y-131280D01*
X427199Y-131309D01*
X427213Y-131330D01*
X427217Y-131334D01*
Y-131269D01*
X427213Y-131203D01*
X427210Y-131145D01*
X427202Y-131087D01*
X427199Y-131036D01*
X427191Y-130988D01*
X427184Y-130945D01*
X427173Y-130904D01*
X427166Y-130868D01*
X427159Y-130839D01*
X427151Y-130814D01*
X427148Y-130792D01*
X427140Y-130777D01*
X427137Y-130766D01*
X427133Y-130759D01*
Y-130755D01*
X427097Y-130683D01*
X427060Y-130617D01*
X427020Y-130566D01*
X426984Y-130522D01*
X426951Y-130486D01*
X426926Y-130461D01*
X426907Y-130446D01*
X426900Y-130442D01*
X426856Y-130413D01*
X426813Y-130395D01*
X426769Y-130380D01*
X426725Y-130369D01*
X426693Y-130362D01*
X426663Y-130359D01*
X426638D01*
X426573Y-130366D01*
X426511Y-130380D01*
X426460Y-130402D01*
X426412Y-130424D01*
X426376Y-130449D01*
X426350Y-130471D01*
X426336Y-130486D01*
X426329Y-130493D01*
X426303Y-130526D01*
X426278Y-130566D01*
X426256Y-130610D01*
X426241Y-130653D01*
X426227Y-130693D01*
X426216Y-130726D01*
X426212Y-130748D01*
X426208Y-130752D01*
Y-130755D01*
X425899Y-130730D01*
X425921Y-130628D01*
X425954Y-130537D01*
X425990Y-130457D01*
X426030Y-130391D01*
X426070Y-130340D01*
X426085Y-130318D01*
X426103Y-130300D01*
X426114Y-130289D01*
X426125Y-130279D01*
X426128Y-130275D01*
X426132Y-130271D01*
X426168Y-130242D01*
X426208Y-130217D01*
X426289Y-130173D01*
X426369Y-130144D01*
X426445Y-130126D01*
X426514Y-130111D01*
X426543Y-130107D01*
X426569D01*
X426591Y-130104D01*
X426620D01*
X426693Y-130107D01*
D02*
G37*
G36*
X429921Y-132633D02*
X429586D01*
Y-131516D01*
X429157D01*
X429117Y-131520D01*
X429088D01*
X429062Y-131523D01*
X429044Y-131527D01*
X429030D01*
X429022Y-131531D01*
X429019D01*
X428960Y-131549D01*
X428935Y-131560D01*
X428913Y-131571D01*
X428891Y-131582D01*
X428877Y-131589D01*
X428869Y-131593D01*
X428866Y-131596D01*
X428837Y-131618D01*
X428807Y-131643D01*
X428753Y-131698D01*
X428727Y-131723D01*
X428709Y-131745D01*
X428698Y-131760D01*
X428695Y-131764D01*
X428658Y-131815D01*
X428618Y-131869D01*
X428578Y-131927D01*
X428538Y-131982D01*
X428505Y-132033D01*
X428480Y-132073D01*
X428469Y-132088D01*
X428462Y-132098D01*
X428454Y-132106D01*
Y-132109D01*
X428123Y-132633D01*
X427708D01*
X428141Y-131949D01*
X428192Y-131876D01*
X428240Y-131811D01*
X428287Y-131756D01*
X428327Y-131705D01*
X428363Y-131669D01*
X428393Y-131640D01*
X428411Y-131622D01*
X428418Y-131614D01*
X428447Y-131593D01*
X428480Y-131567D01*
X428545Y-131527D01*
X428575Y-131512D01*
X428596Y-131498D01*
X428611Y-131491D01*
X428618Y-131487D01*
X428553Y-131476D01*
X428491Y-131465D01*
X428436Y-131447D01*
X428382Y-131432D01*
X428334Y-131414D01*
X428291Y-131392D01*
X428251Y-131374D01*
X428214Y-131356D01*
X428185Y-131334D01*
X428156Y-131316D01*
X428134Y-131301D01*
X428116Y-131287D01*
X428101Y-131276D01*
X428090Y-131265D01*
X428087Y-131261D01*
X428083Y-131258D01*
X428054Y-131221D01*
X428025Y-131185D01*
X427981Y-131108D01*
X427952Y-131032D01*
X427930Y-130959D01*
X427916Y-130897D01*
X427912Y-130872D01*
Y-130846D01*
X427908Y-130828D01*
Y-130814D01*
Y-130806D01*
Y-130803D01*
X427912Y-130726D01*
X427923Y-130657D01*
X427941Y-130591D01*
X427959Y-130537D01*
X427981Y-130490D01*
X427996Y-130453D01*
X428010Y-130431D01*
X428014Y-130428D01*
Y-130424D01*
X428058Y-130366D01*
X428101Y-130315D01*
X428149Y-130271D01*
X428192Y-130238D01*
X428232Y-130213D01*
X428265Y-130198D01*
X428287Y-130187D01*
X428291Y-130184D01*
X428294D01*
X428327Y-130173D01*
X428367Y-130162D01*
X428447Y-130144D01*
X428535Y-130133D01*
X428615Y-130122D01*
X428691Y-130118D01*
X428724D01*
X428753Y-130115D01*
X429921D01*
Y-132633D01*
D02*
G37*
G36*
X59310Y-29173D02*
X59012D01*
Y-27939D01*
X58906Y-28027D01*
X58793Y-28110D01*
X58684Y-28183D01*
X58578Y-28252D01*
X58531Y-28281D01*
X58487Y-28307D01*
X58447Y-28332D01*
X58415Y-28351D01*
X58386Y-28365D01*
X58367Y-28376D01*
X58353Y-28383D01*
X58349Y-28387D01*
X58204Y-28460D01*
X58058Y-28525D01*
X57920Y-28580D01*
X57858Y-28602D01*
X57796Y-28624D01*
X57741Y-28645D01*
X57690Y-28660D01*
X57647Y-28675D01*
X57610Y-28685D01*
X57578Y-28696D01*
X57556Y-28704D01*
X57541Y-28707D01*
X57538D01*
X57388Y-28744D01*
X57315Y-28758D01*
X57250Y-28769D01*
X57188Y-28780D01*
X57126Y-28791D01*
X57075Y-28798D01*
X57024Y-28806D01*
X56981Y-28809D01*
X56941Y-28813D01*
X56904Y-28817D01*
X56875D01*
X56853Y-28820D01*
X56839D01*
X56828D01*
X56824D01*
Y-28503D01*
X56962Y-28493D01*
X57090Y-28474D01*
X57206Y-28456D01*
X57261Y-28445D01*
X57312Y-28434D01*
X57355Y-28427D01*
X57395Y-28416D01*
X57432Y-28409D01*
X57461Y-28401D01*
X57483Y-28394D01*
X57501Y-28391D01*
X57512Y-28387D01*
X57516D01*
X57683Y-28332D01*
X57840Y-28274D01*
X57916Y-28245D01*
X57989Y-28216D01*
X58054Y-28183D01*
X58120Y-28154D01*
X58178Y-28128D01*
X58229Y-28103D01*
X58273Y-28081D01*
X58313Y-28063D01*
X58346Y-28045D01*
X58367Y-28034D01*
X58382Y-28027D01*
X58386Y-28023D01*
X58462Y-27979D01*
X58539Y-27936D01*
X58608Y-27892D01*
X58673Y-27848D01*
X58731Y-27808D01*
X58790Y-27768D01*
X58841Y-27728D01*
X58884Y-27695D01*
X58928Y-27663D01*
X58964Y-27634D01*
X58994Y-27604D01*
X59019Y-27582D01*
X59041Y-27568D01*
X59055Y-27553D01*
X59063Y-27546D01*
X59066Y-27542D01*
X59310D01*
Y-29173D01*
D02*
G37*
G36*
X57122Y-30768D02*
X57184Y-30724D01*
X57210Y-30702D01*
X57235Y-30684D01*
X57257Y-30666D01*
X57272Y-30651D01*
X57283Y-30640D01*
X57286Y-30637D01*
X57305Y-30618D01*
X57323Y-30596D01*
X57370Y-30545D01*
X57425Y-30487D01*
X57479Y-30425D01*
X57526Y-30367D01*
X57548Y-30342D01*
X57570Y-30320D01*
X57585Y-30302D01*
X57596Y-30287D01*
X57603Y-30280D01*
X57607Y-30276D01*
X57658Y-30218D01*
X57705Y-30160D01*
X57752Y-30109D01*
X57792Y-30061D01*
X57832Y-30018D01*
X57869Y-29981D01*
X57902Y-29945D01*
X57931Y-29916D01*
X57960Y-29887D01*
X57982Y-29865D01*
X58000Y-29847D01*
X58018Y-29828D01*
X58040Y-29810D01*
X58047Y-29803D01*
X58109Y-29752D01*
X58163Y-29708D01*
X58218Y-29672D01*
X58262Y-29643D01*
X58302Y-29621D01*
X58331Y-29606D01*
X58349Y-29599D01*
X58356Y-29595D01*
X58411Y-29574D01*
X58466Y-29559D01*
X58517Y-29544D01*
X58560Y-29537D01*
X58600Y-29534D01*
X58630Y-29530D01*
X58648D01*
X58655D01*
X58710Y-29534D01*
X58760Y-29541D01*
X58811Y-29548D01*
X58855Y-29563D01*
X58943Y-29599D01*
X59012Y-29636D01*
X59044Y-29657D01*
X59070Y-29675D01*
X59095Y-29694D01*
X59114Y-29712D01*
X59128Y-29726D01*
X59143Y-29734D01*
X59146Y-29741D01*
X59150Y-29745D01*
X59186Y-29785D01*
X59219Y-29828D01*
X59245Y-29876D01*
X59267Y-29923D01*
X59303Y-30018D01*
X59328Y-30112D01*
X59336Y-30152D01*
X59343Y-30192D01*
X59347Y-30229D01*
X59350Y-30258D01*
X59354Y-30283D01*
Y-30320D01*
X59350Y-30385D01*
X59347Y-30447D01*
X59336Y-30505D01*
X59325Y-30560D01*
X59310Y-30611D01*
X59296Y-30658D01*
X59277Y-30702D01*
X59259Y-30742D01*
X59241Y-30778D01*
X59223Y-30808D01*
X59208Y-30833D01*
X59194Y-30855D01*
X59183Y-30873D01*
X59172Y-30884D01*
X59168Y-30891D01*
X59165Y-30895D01*
X59128Y-30931D01*
X59088Y-30964D01*
X59044Y-30997D01*
X59001Y-31022D01*
X58913Y-31066D01*
X58826Y-31095D01*
X58786Y-31106D01*
X58746Y-31117D01*
X58713Y-31124D01*
X58684Y-31132D01*
X58659Y-31135D01*
X58640D01*
X58630Y-31139D01*
X58626D01*
X58593Y-30822D01*
X58677Y-30815D01*
X58750Y-30800D01*
X58815Y-30778D01*
X58866Y-30753D01*
X58910Y-30731D01*
X58939Y-30709D01*
X58957Y-30695D01*
X58964Y-30687D01*
X59008Y-30633D01*
X59041Y-30575D01*
X59066Y-30513D01*
X59081Y-30458D01*
X59092Y-30407D01*
X59095Y-30364D01*
X59099Y-30349D01*
Y-30327D01*
X59095Y-30251D01*
X59081Y-30182D01*
X59059Y-30123D01*
X59037Y-30072D01*
X59012Y-30032D01*
X58994Y-30007D01*
X58979Y-29989D01*
X58972Y-29981D01*
X58921Y-29938D01*
X58870Y-29905D01*
X58819Y-29879D01*
X58768Y-29865D01*
X58728Y-29854D01*
X58691Y-29850D01*
X58670Y-29847D01*
X58666D01*
X58662D01*
X58597Y-29854D01*
X58527Y-29869D01*
X58466Y-29894D01*
X58407Y-29919D01*
X58360Y-29948D01*
X58320Y-29974D01*
X58306Y-29981D01*
X58295Y-29989D01*
X58291Y-29996D01*
X58287D01*
X58247Y-30025D01*
X58207Y-30061D01*
X58163Y-30101D01*
X58120Y-30145D01*
X58033Y-30236D01*
X57945Y-30327D01*
X57905Y-30374D01*
X57869Y-30414D01*
X57836Y-30454D01*
X57807Y-30487D01*
X57785Y-30513D01*
X57767Y-30535D01*
X57756Y-30549D01*
X57752Y-30553D01*
X57676Y-30644D01*
X57603Y-30727D01*
X57538Y-30797D01*
X57483Y-30851D01*
X57436Y-30899D01*
X57403Y-30931D01*
X57381Y-30950D01*
X57377Y-30957D01*
X57374D01*
X57312Y-31008D01*
X57253Y-31048D01*
X57195Y-31084D01*
X57144Y-31113D01*
X57101Y-31135D01*
X57068Y-31150D01*
X57046Y-31157D01*
X57042Y-31161D01*
X57039D01*
X56999Y-31175D01*
X56962Y-31183D01*
X56926Y-31190D01*
X56893Y-31193D01*
X56864Y-31197D01*
X56842D01*
X56828D01*
X56824D01*
Y-29526D01*
X57122D01*
Y-30768D01*
D02*
G37*
G36*
X57508Y-31783D02*
X57581Y-31834D01*
X57647Y-31881D01*
X57701Y-31929D01*
X57752Y-31969D01*
X57789Y-32005D01*
X57818Y-32034D01*
X57836Y-32052D01*
X57843Y-32060D01*
X57865Y-32089D01*
X57890Y-32122D01*
X57931Y-32187D01*
X57945Y-32216D01*
X57960Y-32238D01*
X57967Y-32253D01*
X57971Y-32260D01*
X57982Y-32194D01*
X57993Y-32133D01*
X58011Y-32078D01*
X58025Y-32023D01*
X58043Y-31976D01*
X58065Y-31932D01*
X58083Y-31892D01*
X58102Y-31856D01*
X58123Y-31827D01*
X58142Y-31798D01*
X58156Y-31776D01*
X58171Y-31758D01*
X58182Y-31743D01*
X58193Y-31732D01*
X58196Y-31729D01*
X58200Y-31725D01*
X58236Y-31696D01*
X58273Y-31667D01*
X58349Y-31623D01*
X58426Y-31594D01*
X58498Y-31572D01*
X58560Y-31557D01*
X58586Y-31554D01*
X58611D01*
X58630Y-31550D01*
X58644D01*
X58651D01*
X58655D01*
X58731Y-31554D01*
X58801Y-31565D01*
X58866Y-31583D01*
X58921Y-31601D01*
X58968Y-31623D01*
X59004Y-31637D01*
X59026Y-31652D01*
X59030Y-31656D01*
X59034D01*
X59092Y-31699D01*
X59143Y-31743D01*
X59186Y-31790D01*
X59219Y-31834D01*
X59245Y-31874D01*
X59259Y-31907D01*
X59270Y-31929D01*
X59274Y-31932D01*
Y-31936D01*
X59285Y-31969D01*
X59296Y-32009D01*
X59314Y-32089D01*
X59325Y-32176D01*
X59336Y-32256D01*
X59339Y-32333D01*
Y-32366D01*
X59343Y-32395D01*
Y-33563D01*
X56824D01*
Y-33228D01*
X57942D01*
Y-32799D01*
X57938Y-32759D01*
Y-32730D01*
X57934Y-32704D01*
X57931Y-32686D01*
Y-32671D01*
X57927Y-32664D01*
Y-32660D01*
X57909Y-32602D01*
X57898Y-32577D01*
X57887Y-32555D01*
X57876Y-32533D01*
X57869Y-32518D01*
X57865Y-32511D01*
X57861Y-32508D01*
X57840Y-32478D01*
X57814Y-32449D01*
X57759Y-32395D01*
X57734Y-32369D01*
X57712Y-32351D01*
X57698Y-32340D01*
X57694Y-32336D01*
X57643Y-32300D01*
X57588Y-32260D01*
X57530Y-32220D01*
X57476Y-32180D01*
X57425Y-32147D01*
X57385Y-32122D01*
X57370Y-32111D01*
X57359Y-32103D01*
X57352Y-32096D01*
X57348D01*
X56824Y-31765D01*
Y-31350D01*
X57508Y-31783D01*
D02*
G37*
G36*
X109796Y-13576D02*
X109895Y-13594D01*
X109978Y-13623D01*
X110051Y-13652D01*
X110084Y-13670D01*
X110109Y-13685D01*
X110135Y-13699D01*
X110153Y-13714D01*
X110168Y-13725D01*
X110178Y-13732D01*
X110186Y-13736D01*
X110189Y-13739D01*
X110258Y-13808D01*
X110313Y-13885D01*
X110357Y-13965D01*
X110393Y-14045D01*
X110415Y-14114D01*
X110426Y-14143D01*
X110433Y-14169D01*
X110437Y-14191D01*
X110441Y-14205D01*
X110444Y-14216D01*
Y-14220D01*
X110135Y-14275D01*
X110120Y-14194D01*
X110098Y-14125D01*
X110073Y-14067D01*
X110047Y-14020D01*
X110022Y-13983D01*
X110000Y-13958D01*
X109985Y-13940D01*
X109982Y-13936D01*
X109935Y-13900D01*
X109884Y-13870D01*
X109836Y-13852D01*
X109789Y-13838D01*
X109745Y-13830D01*
X109713Y-13823D01*
X109683D01*
X109618Y-13827D01*
X109560Y-13841D01*
X109509Y-13859D01*
X109465Y-13878D01*
X109432Y-13900D01*
X109407Y-13918D01*
X109389Y-13932D01*
X109385Y-13936D01*
X109345Y-13980D01*
X109316Y-14027D01*
X109298Y-14074D01*
X109283Y-14118D01*
X109276Y-14158D01*
X109268Y-14187D01*
Y-14209D01*
Y-14213D01*
Y-14216D01*
Y-14256D01*
X109276Y-14293D01*
X109294Y-14355D01*
X109319Y-14409D01*
X109348Y-14457D01*
X109378Y-14489D01*
X109403Y-14515D01*
X109421Y-14529D01*
X109425Y-14533D01*
X109429D01*
X109491Y-14566D01*
X109549Y-14591D01*
X109611Y-14609D01*
X109665Y-14620D01*
X109713Y-14627D01*
X109753Y-14635D01*
X109800D01*
X109815Y-14631D01*
X109833D01*
X109869Y-14904D01*
X109822Y-14893D01*
X109778Y-14886D01*
X109742Y-14879D01*
X109709Y-14875D01*
X109683Y-14871D01*
X109651D01*
X109574Y-14879D01*
X109505Y-14893D01*
X109443Y-14915D01*
X109392Y-14941D01*
X109352Y-14966D01*
X109323Y-14988D01*
X109305Y-15002D01*
X109298Y-15010D01*
X109250Y-15064D01*
X109214Y-15123D01*
X109188Y-15181D01*
X109174Y-15239D01*
X109163Y-15286D01*
X109159Y-15326D01*
X109156Y-15341D01*
Y-15352D01*
Y-15359D01*
Y-15363D01*
X109163Y-15443D01*
X109181Y-15516D01*
X109203Y-15578D01*
X109232Y-15632D01*
X109261Y-15676D01*
X109283Y-15709D01*
X109301Y-15731D01*
X109309Y-15738D01*
X109367Y-15789D01*
X109429Y-15825D01*
X109491Y-15851D01*
X109549Y-15869D01*
X109600Y-15880D01*
X109640Y-15883D01*
X109654Y-15887D01*
X109676D01*
X109742Y-15883D01*
X109803Y-15869D01*
X109858Y-15851D01*
X109902Y-15829D01*
X109938Y-15811D01*
X109967Y-15792D01*
X109982Y-15778D01*
X109989Y-15774D01*
X110033Y-15723D01*
X110069Y-15665D01*
X110102Y-15603D01*
X110127Y-15538D01*
X110146Y-15483D01*
X110153Y-15458D01*
X110157Y-15436D01*
X110160Y-15417D01*
X110164Y-15403D01*
X110168Y-15396D01*
Y-15392D01*
X110477Y-15432D01*
X110470Y-15490D01*
X110459Y-15545D01*
X110426Y-15647D01*
X110386Y-15734D01*
X110364Y-15770D01*
X110342Y-15807D01*
X110320Y-15840D01*
X110299Y-15865D01*
X110280Y-15891D01*
X110262Y-15909D01*
X110251Y-15923D01*
X110240Y-15934D01*
X110233Y-15942D01*
X110229Y-15945D01*
X110186Y-15978D01*
X110142Y-16011D01*
X110098Y-16036D01*
X110051Y-16058D01*
X109960Y-16094D01*
X109873Y-16116D01*
X109833Y-16124D01*
X109796Y-16131D01*
X109764Y-16135D01*
X109734Y-16138D01*
X109713Y-16142D01*
X109680D01*
X109611Y-16138D01*
X109549Y-16131D01*
X109487Y-16120D01*
X109429Y-16105D01*
X109374Y-16087D01*
X109327Y-16069D01*
X109279Y-16047D01*
X109239Y-16025D01*
X109199Y-16007D01*
X109167Y-15985D01*
X109137Y-15967D01*
X109116Y-15949D01*
X109097Y-15934D01*
X109083Y-15923D01*
X109075Y-15916D01*
X109072Y-15913D01*
X109028Y-15869D01*
X108992Y-15822D01*
X108959Y-15774D01*
X108930Y-15727D01*
X108908Y-15683D01*
X108886Y-15636D01*
X108857Y-15549D01*
X108850Y-15508D01*
X108843Y-15472D01*
X108835Y-15439D01*
X108832Y-15410D01*
X108828Y-15388D01*
Y-15370D01*
Y-15359D01*
Y-15356D01*
X108832Y-15268D01*
X108846Y-15188D01*
X108868Y-15119D01*
X108890Y-15061D01*
X108912Y-15013D01*
X108934Y-14977D01*
X108948Y-14955D01*
X108952Y-14948D01*
X109003Y-14893D01*
X109057Y-14846D01*
X109116Y-14809D01*
X109174Y-14780D01*
X109225Y-14759D01*
X109265Y-14744D01*
X109279Y-14740D01*
X109290Y-14737D01*
X109298Y-14733D01*
X109301D01*
X109239Y-14700D01*
X109188Y-14668D01*
X109145Y-14631D01*
X109108Y-14598D01*
X109079Y-14569D01*
X109057Y-14544D01*
X109046Y-14529D01*
X109043Y-14522D01*
X109014Y-14471D01*
X108992Y-14420D01*
X108974Y-14369D01*
X108963Y-14322D01*
X108955Y-14282D01*
X108952Y-14253D01*
Y-14231D01*
Y-14223D01*
X108955Y-14162D01*
X108966Y-14100D01*
X108981Y-14045D01*
X108999Y-13998D01*
X109017Y-13958D01*
X109032Y-13925D01*
X109043Y-13907D01*
X109046Y-13900D01*
X109083Y-13845D01*
X109126Y-13798D01*
X109170Y-13758D01*
X109214Y-13721D01*
X109250Y-13696D01*
X109283Y-13674D01*
X109305Y-13663D01*
X109309Y-13659D01*
X109312D01*
X109378Y-13630D01*
X109443Y-13608D01*
X109509Y-13590D01*
X109567Y-13579D01*
X109614Y-13572D01*
X109654Y-13568D01*
X109745D01*
X109796Y-13576D01*
D02*
G37*
G36*
X111926Y-13543D02*
X112042Y-13561D01*
X112144Y-13583D01*
X112191Y-13597D01*
X112235Y-13612D01*
X112275Y-13626D01*
X112311Y-13641D01*
X112341Y-13652D01*
X112370Y-13663D01*
X112388Y-13674D01*
X112402Y-13681D01*
X112413Y-13685D01*
X112417Y-13688D01*
X112515Y-13750D01*
X112599Y-13823D01*
X112672Y-13896D01*
X112734Y-13969D01*
X112781Y-14034D01*
X112799Y-14063D01*
X112814Y-14089D01*
X112828Y-14107D01*
X112836Y-14122D01*
X112839Y-14132D01*
X112843Y-14136D01*
X112894Y-14249D01*
X112930Y-14366D01*
X112956Y-14482D01*
X112974Y-14588D01*
X112981Y-14635D01*
X112985Y-14682D01*
X112988Y-14718D01*
Y-14755D01*
X112992Y-14780D01*
Y-14802D01*
Y-14817D01*
Y-14820D01*
X112985Y-14952D01*
X112970Y-15079D01*
X112952Y-15192D01*
X112938Y-15246D01*
X112927Y-15294D01*
X112916Y-15337D01*
X112901Y-15377D01*
X112890Y-15414D01*
X112883Y-15443D01*
X112872Y-15465D01*
X112868Y-15483D01*
X112861Y-15494D01*
Y-15497D01*
X112806Y-15607D01*
X112745Y-15705D01*
X112679Y-15789D01*
X112646Y-15822D01*
X112617Y-15854D01*
X112588Y-15883D01*
X112559Y-15909D01*
X112533Y-15931D01*
X112512Y-15945D01*
X112497Y-15960D01*
X112483Y-15971D01*
X112475Y-15974D01*
X112472Y-15978D01*
X112421Y-16007D01*
X112370Y-16033D01*
X112260Y-16073D01*
X112151Y-16102D01*
X112046Y-16120D01*
X111995Y-16127D01*
X111951Y-16135D01*
X111911Y-16138D01*
X111878D01*
X111849Y-16142D01*
X111809D01*
X111736Y-16138D01*
X111667Y-16131D01*
X111602Y-16124D01*
X111540Y-16109D01*
X111482Y-16091D01*
X111427Y-16073D01*
X111376Y-16054D01*
X111329Y-16033D01*
X111289Y-16014D01*
X111249Y-15996D01*
X111220Y-15978D01*
X111190Y-15960D01*
X111172Y-15945D01*
X111154Y-15938D01*
X111147Y-15931D01*
X111143Y-15927D01*
X111092Y-15883D01*
X111048Y-15840D01*
X111008Y-15789D01*
X110968Y-15738D01*
X110903Y-15636D01*
X110852Y-15534D01*
X110830Y-15487D01*
X110812Y-15443D01*
X110797Y-15403D01*
X110786Y-15370D01*
X110775Y-15341D01*
X110768Y-15319D01*
X110765Y-15305D01*
Y-15301D01*
X111099Y-15217D01*
X111114Y-15276D01*
X111132Y-15330D01*
X111150Y-15381D01*
X111169Y-15428D01*
X111190Y-15472D01*
X111212Y-15508D01*
X111238Y-15545D01*
X111259Y-15578D01*
X111278Y-15607D01*
X111300Y-15629D01*
X111318Y-15650D01*
X111332Y-15669D01*
X111347Y-15679D01*
X111358Y-15690D01*
X111362Y-15694D01*
X111365Y-15698D01*
X111401Y-15727D01*
X111442Y-15749D01*
X111522Y-15789D01*
X111598Y-15818D01*
X111674Y-15836D01*
X111740Y-15851D01*
X111766Y-15854D01*
X111791D01*
X111813Y-15858D01*
X111838D01*
X111922Y-15854D01*
X112002Y-15840D01*
X112075Y-15822D01*
X112140Y-15800D01*
X112191Y-15778D01*
X112213Y-15767D01*
X112231Y-15760D01*
X112246Y-15752D01*
X112257Y-15745D01*
X112264Y-15741D01*
X112268D01*
X112337Y-15690D01*
X112395Y-15636D01*
X112446Y-15574D01*
X112486Y-15516D01*
X112519Y-15465D01*
X112541Y-15421D01*
X112548Y-15403D01*
X112555Y-15392D01*
X112559Y-15385D01*
Y-15381D01*
X112588Y-15286D01*
X112610Y-15192D01*
X112628Y-15097D01*
X112639Y-15010D01*
X112643Y-14970D01*
X112646Y-14933D01*
Y-14900D01*
X112650Y-14875D01*
Y-14853D01*
Y-14835D01*
Y-14824D01*
Y-14820D01*
X112646Y-14726D01*
X112639Y-14638D01*
X112625Y-14558D01*
X112610Y-14486D01*
X112599Y-14424D01*
X112592Y-14398D01*
X112584Y-14376D01*
X112581Y-14358D01*
X112577Y-14347D01*
X112574Y-14340D01*
Y-14336D01*
X112537Y-14253D01*
X112497Y-14176D01*
X112453Y-14114D01*
X112406Y-14060D01*
X112366Y-14016D01*
X112333Y-13987D01*
X112308Y-13969D01*
X112304Y-13961D01*
X112301D01*
X112224Y-13914D01*
X112140Y-13878D01*
X112060Y-13852D01*
X111984Y-13838D01*
X111915Y-13827D01*
X111886Y-13823D01*
X111860D01*
X111842Y-13819D01*
X111813D01*
X111722Y-13823D01*
X111638Y-13838D01*
X111569Y-13859D01*
X111507Y-13881D01*
X111460Y-13907D01*
X111423Y-13925D01*
X111401Y-13940D01*
X111394Y-13947D01*
X111336Y-14002D01*
X111281Y-14063D01*
X111238Y-14129D01*
X111201Y-14194D01*
X111172Y-14253D01*
X111161Y-14282D01*
X111154Y-14304D01*
X111147Y-14322D01*
X111139Y-14336D01*
X111136Y-14344D01*
Y-14347D01*
X110808Y-14271D01*
X110830Y-14205D01*
X110852Y-14147D01*
X110881Y-14093D01*
X110907Y-14038D01*
X110936Y-13991D01*
X110968Y-13947D01*
X110997Y-13903D01*
X111027Y-13867D01*
X111056Y-13838D01*
X111081Y-13808D01*
X111107Y-13783D01*
X111125Y-13765D01*
X111143Y-13747D01*
X111158Y-13736D01*
X111165Y-13732D01*
X111169Y-13728D01*
X111220Y-13696D01*
X111270Y-13663D01*
X111321Y-13637D01*
X111376Y-13616D01*
X111485Y-13583D01*
X111583Y-13561D01*
X111631Y-13550D01*
X111671Y-13546D01*
X111711Y-13543D01*
X111744Y-13539D01*
X111769Y-13535D01*
X111805D01*
X111926Y-13543D01*
D02*
G37*
G36*
X96925Y-77169D02*
X96994Y-77176D01*
X97060Y-77184D01*
X97122Y-77198D01*
X97180Y-77216D01*
X97234Y-77235D01*
X97285Y-77253D01*
X97333Y-77275D01*
X97373Y-77293D01*
X97413Y-77311D01*
X97442Y-77329D01*
X97471Y-77347D01*
X97489Y-77362D01*
X97507Y-77369D01*
X97515Y-77376D01*
X97518Y-77380D01*
X97569Y-77424D01*
X97613Y-77467D01*
X97653Y-77518D01*
X97693Y-77569D01*
X97759Y-77671D01*
X97809Y-77773D01*
X97831Y-77820D01*
X97850Y-77864D01*
X97864Y-77904D01*
X97875Y-77937D01*
X97886Y-77966D01*
X97893Y-77988D01*
X97897Y-78003D01*
Y-78006D01*
X97562Y-78090D01*
X97548Y-78032D01*
X97529Y-77977D01*
X97511Y-77926D01*
X97493Y-77879D01*
X97471Y-77835D01*
X97449Y-77799D01*
X97424Y-77762D01*
X97402Y-77729D01*
X97384Y-77700D01*
X97362Y-77679D01*
X97344Y-77657D01*
X97329Y-77639D01*
X97315Y-77628D01*
X97304Y-77617D01*
X97300Y-77613D01*
X97296Y-77609D01*
X97260Y-77580D01*
X97220Y-77558D01*
X97140Y-77518D01*
X97063Y-77489D01*
X96987Y-77471D01*
X96921Y-77456D01*
X96896Y-77453D01*
X96870D01*
X96849Y-77449D01*
X96823D01*
X96739Y-77453D01*
X96659Y-77467D01*
X96587Y-77486D01*
X96521Y-77508D01*
X96470Y-77529D01*
X96448Y-77540D01*
X96430Y-77548D01*
X96415Y-77555D01*
X96404Y-77562D01*
X96397Y-77566D01*
X96394D01*
X96324Y-77617D01*
X96266Y-77671D01*
X96215Y-77733D01*
X96175Y-77791D01*
X96142Y-77842D01*
X96121Y-77886D01*
X96113Y-77904D01*
X96106Y-77915D01*
X96102Y-77922D01*
Y-77926D01*
X96073Y-78021D01*
X96051Y-78115D01*
X96033Y-78210D01*
X96022Y-78297D01*
X96019Y-78337D01*
X96015Y-78374D01*
Y-78407D01*
X96011Y-78432D01*
Y-78454D01*
Y-78472D01*
Y-78483D01*
Y-78487D01*
X96015Y-78581D01*
X96022Y-78669D01*
X96037Y-78749D01*
X96051Y-78821D01*
X96062Y-78883D01*
X96070Y-78909D01*
X96077Y-78931D01*
X96080Y-78949D01*
X96084Y-78960D01*
X96088Y-78967D01*
Y-78971D01*
X96124Y-79054D01*
X96164Y-79131D01*
X96208Y-79193D01*
X96255Y-79247D01*
X96295Y-79291D01*
X96328Y-79320D01*
X96354Y-79338D01*
X96357Y-79346D01*
X96361D01*
X96437Y-79393D01*
X96521Y-79429D01*
X96601Y-79455D01*
X96678Y-79469D01*
X96747Y-79480D01*
X96776Y-79484D01*
X96801D01*
X96820Y-79488D01*
X96849D01*
X96940Y-79484D01*
X97023Y-79469D01*
X97092Y-79448D01*
X97154Y-79426D01*
X97202Y-79400D01*
X97238Y-79382D01*
X97260Y-79368D01*
X97267Y-79360D01*
X97325Y-79306D01*
X97380Y-79244D01*
X97424Y-79178D01*
X97460Y-79113D01*
X97489Y-79054D01*
X97500Y-79025D01*
X97507Y-79004D01*
X97515Y-78985D01*
X97522Y-78971D01*
X97526Y-78964D01*
Y-78960D01*
X97853Y-79036D01*
X97831Y-79102D01*
X97809Y-79160D01*
X97780Y-79215D01*
X97755Y-79269D01*
X97726Y-79317D01*
X97693Y-79360D01*
X97664Y-79404D01*
X97635Y-79440D01*
X97606Y-79469D01*
X97580Y-79498D01*
X97555Y-79524D01*
X97536Y-79542D01*
X97518Y-79560D01*
X97504Y-79571D01*
X97496Y-79575D01*
X97493Y-79579D01*
X97442Y-79611D01*
X97391Y-79644D01*
X97340Y-79670D01*
X97285Y-79691D01*
X97176Y-79724D01*
X97078Y-79746D01*
X97031Y-79757D01*
X96991Y-79761D01*
X96951Y-79764D01*
X96918Y-79768D01*
X96892Y-79772D01*
X96856D01*
X96736Y-79764D01*
X96619Y-79746D01*
X96517Y-79724D01*
X96470Y-79710D01*
X96426Y-79695D01*
X96386Y-79681D01*
X96350Y-79666D01*
X96321Y-79655D01*
X96292Y-79644D01*
X96273Y-79633D01*
X96259Y-79626D01*
X96248Y-79622D01*
X96244Y-79619D01*
X96146Y-79557D01*
X96062Y-79484D01*
X95990Y-79411D01*
X95928Y-79338D01*
X95880Y-79273D01*
X95862Y-79244D01*
X95848Y-79218D01*
X95833Y-79200D01*
X95826Y-79185D01*
X95822Y-79175D01*
X95819Y-79171D01*
X95767Y-79058D01*
X95731Y-78942D01*
X95706Y-78825D01*
X95687Y-78720D01*
X95680Y-78672D01*
X95676Y-78625D01*
X95673Y-78588D01*
Y-78552D01*
X95669Y-78527D01*
Y-78505D01*
Y-78490D01*
Y-78487D01*
X95676Y-78356D01*
X95691Y-78228D01*
X95709Y-78115D01*
X95724Y-78061D01*
X95735Y-78013D01*
X95746Y-77970D01*
X95760Y-77930D01*
X95771Y-77893D01*
X95778Y-77864D01*
X95789Y-77842D01*
X95793Y-77824D01*
X95800Y-77813D01*
Y-77810D01*
X95855Y-77700D01*
X95917Y-77602D01*
X95982Y-77518D01*
X96015Y-77486D01*
X96044Y-77453D01*
X96073Y-77424D01*
X96102Y-77398D01*
X96128Y-77376D01*
X96150Y-77362D01*
X96164Y-77347D01*
X96179Y-77336D01*
X96186Y-77333D01*
X96190Y-77329D01*
X96241Y-77300D01*
X96292Y-77275D01*
X96401Y-77235D01*
X96510Y-77205D01*
X96616Y-77187D01*
X96667Y-77180D01*
X96710Y-77173D01*
X96750Y-77169D01*
X96783D01*
X96812Y-77165D01*
X96852D01*
X96925Y-77169D01*
D02*
G37*
G36*
X99346Y-79739D02*
X99145D01*
X99109Y-79677D01*
X99069Y-79619D01*
X99022Y-79560D01*
X98978Y-79510D01*
X98934Y-79466D01*
X98901Y-79429D01*
X98887Y-79418D01*
X98876Y-79408D01*
X98872Y-79404D01*
X98869Y-79400D01*
X98792Y-79338D01*
X98716Y-79280D01*
X98643Y-79229D01*
X98570Y-79189D01*
X98508Y-79153D01*
X98483Y-79138D01*
X98461Y-79127D01*
X98443Y-79116D01*
X98428Y-79113D01*
X98421Y-79105D01*
X98417D01*
Y-78807D01*
X98472Y-78829D01*
X98527Y-78854D01*
X98581Y-78880D01*
X98632Y-78905D01*
X98676Y-78927D01*
X98712Y-78945D01*
X98734Y-78960D01*
X98738Y-78964D01*
X98741D01*
X98807Y-79004D01*
X98865Y-79044D01*
X98916Y-79080D01*
X98956Y-79113D01*
X98993Y-79138D01*
X99014Y-79160D01*
X99033Y-79175D01*
X99036Y-79178D01*
Y-77209D01*
X99346D01*
Y-79739D01*
D02*
G37*
G36*
X100842Y-77347D02*
X100860Y-77475D01*
X100878Y-77591D01*
X100889Y-77646D01*
X100900Y-77697D01*
X100907Y-77740D01*
X100918Y-77780D01*
X100925Y-77817D01*
X100933Y-77846D01*
X100940Y-77868D01*
X100944Y-77886D01*
X100947Y-77897D01*
Y-77901D01*
X101002Y-78068D01*
X101060Y-78224D01*
X101089Y-78301D01*
X101118Y-78374D01*
X101151Y-78439D01*
X101180Y-78505D01*
X101206Y-78563D01*
X101231Y-78614D01*
X101253Y-78658D01*
X101271Y-78698D01*
X101289Y-78730D01*
X101300Y-78752D01*
X101308Y-78767D01*
X101311Y-78771D01*
X101355Y-78847D01*
X101399Y-78923D01*
X101442Y-78993D01*
X101486Y-79058D01*
X101526Y-79116D01*
X101566Y-79175D01*
X101606Y-79225D01*
X101639Y-79269D01*
X101672Y-79313D01*
X101701Y-79349D01*
X101730Y-79378D01*
X101752Y-79404D01*
X101766Y-79426D01*
X101781Y-79440D01*
X101788Y-79448D01*
X101792Y-79451D01*
Y-79695D01*
X100161D01*
Y-79397D01*
X101395D01*
X101308Y-79291D01*
X101224Y-79178D01*
X101151Y-79069D01*
X101082Y-78964D01*
X101053Y-78916D01*
X101027Y-78873D01*
X101002Y-78832D01*
X100984Y-78800D01*
X100969Y-78771D01*
X100958Y-78752D01*
X100951Y-78738D01*
X100947Y-78734D01*
X100874Y-78588D01*
X100809Y-78443D01*
X100754Y-78305D01*
X100733Y-78243D01*
X100711Y-78181D01*
X100689Y-78126D01*
X100674Y-78075D01*
X100660Y-78032D01*
X100649Y-77995D01*
X100638Y-77962D01*
X100630Y-77941D01*
X100627Y-77926D01*
Y-77922D01*
X100591Y-77773D01*
X100576Y-77700D01*
X100565Y-77635D01*
X100554Y-77573D01*
X100543Y-77511D01*
X100536Y-77460D01*
X100529Y-77409D01*
X100525Y-77365D01*
X100521Y-77325D01*
X100518Y-77289D01*
Y-77260D01*
X100514Y-77238D01*
Y-77223D01*
Y-77213D01*
Y-77209D01*
X100831D01*
X100842Y-77347D01*
D02*
G37*
G36*
X107471Y-46206D02*
X107599Y-46220D01*
X107711Y-46239D01*
X107766Y-46253D01*
X107813Y-46264D01*
X107857Y-46275D01*
X107897Y-46290D01*
X107933Y-46301D01*
X107963Y-46308D01*
X107984Y-46319D01*
X108003Y-46322D01*
X108013Y-46330D01*
X108017D01*
X108126Y-46384D01*
X108225Y-46446D01*
X108308Y-46512D01*
X108341Y-46544D01*
X108374Y-46573D01*
X108403Y-46603D01*
X108429Y-46632D01*
X108450Y-46657D01*
X108465Y-46679D01*
X108479Y-46694D01*
X108490Y-46708D01*
X108494Y-46716D01*
X108498Y-46719D01*
X108527Y-46770D01*
X108552Y-46821D01*
X108592Y-46930D01*
X108621Y-47039D01*
X108640Y-47145D01*
X108647Y-47196D01*
X108654Y-47240D01*
X108658Y-47280D01*
Y-47313D01*
X108661Y-47342D01*
Y-47382D01*
X108658Y-47454D01*
X108651Y-47524D01*
X108643Y-47589D01*
X108629Y-47651D01*
X108610Y-47709D01*
X108592Y-47764D01*
X108574Y-47815D01*
X108552Y-47862D01*
X108534Y-47902D01*
X108516Y-47942D01*
X108498Y-47971D01*
X108479Y-48000D01*
X108465Y-48019D01*
X108458Y-48037D01*
X108450Y-48044D01*
X108447Y-48048D01*
X108403Y-48099D01*
X108359Y-48142D01*
X108308Y-48182D01*
X108257Y-48223D01*
X108156Y-48288D01*
X108054Y-48339D01*
X108006Y-48361D01*
X107963Y-48379D01*
X107922Y-48393D01*
X107890Y-48404D01*
X107861Y-48415D01*
X107839Y-48423D01*
X107824Y-48426D01*
X107821D01*
X107737Y-48091D01*
X107795Y-48077D01*
X107850Y-48059D01*
X107901Y-48041D01*
X107948Y-48022D01*
X107992Y-48000D01*
X108028Y-47979D01*
X108064Y-47953D01*
X108097Y-47931D01*
X108126Y-47913D01*
X108148Y-47891D01*
X108170Y-47873D01*
X108188Y-47859D01*
X108199Y-47844D01*
X108210Y-47833D01*
X108214Y-47829D01*
X108217Y-47826D01*
X108247Y-47789D01*
X108268Y-47749D01*
X108308Y-47669D01*
X108337Y-47593D01*
X108356Y-47516D01*
X108370Y-47451D01*
X108374Y-47425D01*
Y-47400D01*
X108378Y-47378D01*
Y-47352D01*
X108374Y-47269D01*
X108359Y-47189D01*
X108341Y-47116D01*
X108319Y-47050D01*
X108298Y-46999D01*
X108286Y-46978D01*
X108279Y-46959D01*
X108272Y-46945D01*
X108265Y-46934D01*
X108261Y-46927D01*
Y-46923D01*
X108210Y-46854D01*
X108156Y-46796D01*
X108094Y-46745D01*
X108035Y-46705D01*
X107984Y-46672D01*
X107941Y-46650D01*
X107922Y-46643D01*
X107912Y-46635D01*
X107904Y-46632D01*
X107901D01*
X107806Y-46603D01*
X107711Y-46581D01*
X107617Y-46563D01*
X107529Y-46552D01*
X107489Y-46548D01*
X107453Y-46544D01*
X107420D01*
X107395Y-46541D01*
X107373D01*
X107355D01*
X107344D01*
X107340D01*
X107246Y-46544D01*
X107158Y-46552D01*
X107078Y-46566D01*
X107005Y-46581D01*
X106943Y-46592D01*
X106918Y-46599D01*
X106896Y-46606D01*
X106878Y-46610D01*
X106867Y-46614D01*
X106860Y-46617D01*
X106856D01*
X106772Y-46654D01*
X106696Y-46694D01*
X106634Y-46737D01*
X106579Y-46785D01*
X106536Y-46825D01*
X106507Y-46858D01*
X106488Y-46883D01*
X106481Y-46887D01*
Y-46890D01*
X106434Y-46967D01*
X106397Y-47050D01*
X106372Y-47131D01*
X106357Y-47207D01*
X106346Y-47276D01*
X106343Y-47305D01*
Y-47331D01*
X106339Y-47349D01*
Y-47378D01*
X106343Y-47469D01*
X106357Y-47553D01*
X106379Y-47622D01*
X106401Y-47684D01*
X106427Y-47731D01*
X106445Y-47767D01*
X106459Y-47789D01*
X106466Y-47797D01*
X106521Y-47855D01*
X106583Y-47909D01*
X106649Y-47953D01*
X106714Y-47989D01*
X106772Y-48019D01*
X106801Y-48030D01*
X106823Y-48037D01*
X106842Y-48044D01*
X106856Y-48051D01*
X106863Y-48055D01*
X106867D01*
X106790Y-48383D01*
X106725Y-48361D01*
X106667Y-48339D01*
X106612Y-48310D01*
X106558Y-48284D01*
X106510Y-48255D01*
X106466Y-48223D01*
X106423Y-48193D01*
X106386Y-48164D01*
X106357Y-48135D01*
X106328Y-48110D01*
X106303Y-48084D01*
X106284Y-48066D01*
X106266Y-48048D01*
X106255Y-48033D01*
X106252Y-48026D01*
X106248Y-48022D01*
X106215Y-47971D01*
X106183Y-47920D01*
X106157Y-47869D01*
X106135Y-47815D01*
X106103Y-47706D01*
X106081Y-47607D01*
X106070Y-47560D01*
X106066Y-47520D01*
X106062Y-47480D01*
X106059Y-47447D01*
X106055Y-47422D01*
Y-47385D01*
X106062Y-47265D01*
X106081Y-47149D01*
X106103Y-47047D01*
X106117Y-46999D01*
X106132Y-46956D01*
X106146Y-46916D01*
X106161Y-46879D01*
X106172Y-46850D01*
X106183Y-46821D01*
X106193Y-46803D01*
X106201Y-46788D01*
X106204Y-46777D01*
X106208Y-46774D01*
X106270Y-46676D01*
X106343Y-46592D01*
X106416Y-46519D01*
X106488Y-46457D01*
X106554Y-46410D01*
X106583Y-46391D01*
X106608Y-46377D01*
X106627Y-46362D01*
X106641Y-46355D01*
X106652Y-46352D01*
X106656Y-46348D01*
X106769Y-46297D01*
X106885Y-46260D01*
X107002Y-46235D01*
X107107Y-46217D01*
X107155Y-46209D01*
X107202Y-46206D01*
X107238Y-46202D01*
X107275D01*
X107300Y-46199D01*
X107322D01*
X107336D01*
X107340D01*
X107471Y-46206D01*
D02*
G37*
G36*
X106998Y-49001D02*
X106973Y-49056D01*
X106947Y-49111D01*
X106922Y-49162D01*
X106900Y-49205D01*
X106881Y-49242D01*
X106867Y-49264D01*
X106863Y-49267D01*
Y-49271D01*
X106823Y-49336D01*
X106783Y-49395D01*
X106747Y-49446D01*
X106714Y-49485D01*
X106689Y-49522D01*
X106667Y-49544D01*
X106652Y-49562D01*
X106649Y-49566D01*
X108618D01*
Y-49875D01*
X106088D01*
Y-49675D01*
X106150Y-49638D01*
X106208Y-49598D01*
X106266Y-49551D01*
X106317Y-49507D01*
X106361Y-49464D01*
X106397Y-49431D01*
X106408Y-49416D01*
X106419Y-49406D01*
X106423Y-49402D01*
X106427Y-49398D01*
X106488Y-49322D01*
X106547Y-49245D01*
X106598Y-49172D01*
X106638Y-49100D01*
X106674Y-49038D01*
X106689Y-49012D01*
X106700Y-48990D01*
X106710Y-48972D01*
X106714Y-48958D01*
X106721Y-48950D01*
Y-48947D01*
X107020D01*
X106998Y-49001D01*
D02*
G37*
G36*
X107952Y-50669D02*
X108010Y-50676D01*
X108064Y-50687D01*
X108119Y-50701D01*
X108210Y-50738D01*
X108254Y-50756D01*
X108290Y-50778D01*
X108327Y-50800D01*
X108356Y-50818D01*
X108381Y-50840D01*
X108403Y-50854D01*
X108421Y-50869D01*
X108432Y-50880D01*
X108439Y-50887D01*
X108443Y-50891D01*
X108483Y-50934D01*
X108516Y-50982D01*
X108545Y-51033D01*
X108571Y-51083D01*
X108589Y-51131D01*
X108607Y-51182D01*
X108632Y-51280D01*
X108643Y-51324D01*
X108651Y-51364D01*
X108654Y-51400D01*
X108658Y-51433D01*
X108661Y-51458D01*
Y-51495D01*
X108658Y-51564D01*
X108651Y-51626D01*
X108640Y-51688D01*
X108629Y-51746D01*
X108610Y-51797D01*
X108592Y-51848D01*
X108574Y-51895D01*
X108552Y-51935D01*
X108530Y-51972D01*
X108512Y-52004D01*
X108494Y-52030D01*
X108476Y-52055D01*
X108465Y-52074D01*
X108454Y-52084D01*
X108447Y-52092D01*
X108443Y-52095D01*
X108399Y-52135D01*
X108356Y-52172D01*
X108312Y-52201D01*
X108265Y-52227D01*
X108221Y-52252D01*
X108174Y-52270D01*
X108090Y-52296D01*
X108050Y-52306D01*
X108013Y-52314D01*
X107981Y-52318D01*
X107955Y-52321D01*
X107933Y-52325D01*
X107915D01*
X107904D01*
X107901D01*
X107817Y-52321D01*
X107740Y-52306D01*
X107671Y-52285D01*
X107613Y-52263D01*
X107566Y-52241D01*
X107529Y-52219D01*
X107508Y-52205D01*
X107504Y-52201D01*
X107500D01*
X107442Y-52150D01*
X107391Y-52095D01*
X107351Y-52037D01*
X107315Y-51983D01*
X107289Y-51932D01*
X107271Y-51888D01*
X107264Y-51873D01*
X107260Y-51863D01*
X107256Y-51855D01*
Y-51851D01*
X107227Y-51917D01*
X107194Y-51972D01*
X107162Y-52019D01*
X107129Y-52059D01*
X107100Y-52088D01*
X107078Y-52110D01*
X107063Y-52125D01*
X107056Y-52128D01*
X107005Y-52161D01*
X106954Y-52183D01*
X106903Y-52201D01*
X106852Y-52212D01*
X106812Y-52219D01*
X106780Y-52223D01*
X106758D01*
X106754D01*
X106751D01*
X106700Y-52219D01*
X106652Y-52215D01*
X106561Y-52190D01*
X106481Y-52157D01*
X106412Y-52121D01*
X106357Y-52084D01*
X106335Y-52066D01*
X106314Y-52052D01*
X106299Y-52037D01*
X106288Y-52026D01*
X106284Y-52023D01*
X106281Y-52019D01*
X106248Y-51979D01*
X106215Y-51939D01*
X106190Y-51895D01*
X106168Y-51851D01*
X106135Y-51764D01*
X106114Y-51677D01*
X106103Y-51640D01*
X106099Y-51604D01*
X106095Y-51571D01*
X106092Y-51542D01*
X106088Y-51520D01*
Y-51487D01*
X106092Y-51429D01*
X106095Y-51371D01*
X106117Y-51269D01*
X106132Y-51222D01*
X106146Y-51178D01*
X106164Y-51138D01*
X106183Y-51102D01*
X106201Y-51073D01*
X106219Y-51043D01*
X106234Y-51018D01*
X106248Y-51000D01*
X106259Y-50985D01*
X106270Y-50974D01*
X106274Y-50967D01*
X106277Y-50963D01*
X106314Y-50931D01*
X106350Y-50898D01*
X106390Y-50872D01*
X106430Y-50850D01*
X106507Y-50814D01*
X106579Y-50792D01*
X106641Y-50778D01*
X106670Y-50774D01*
X106692Y-50770D01*
X106714Y-50767D01*
X106729D01*
X106736D01*
X106739D01*
X106805Y-50770D01*
X106867Y-50781D01*
X106922Y-50796D01*
X106969Y-50814D01*
X107005Y-50829D01*
X107034Y-50843D01*
X107049Y-50854D01*
X107056Y-50858D01*
X107100Y-50898D01*
X107140Y-50941D01*
X107176Y-50989D01*
X107205Y-51036D01*
X107227Y-51080D01*
X107242Y-51113D01*
X107249Y-51127D01*
X107253Y-51138D01*
X107256Y-51142D01*
Y-51145D01*
X107282Y-51062D01*
X107315Y-50993D01*
X107355Y-50931D01*
X107391Y-50880D01*
X107428Y-50840D01*
X107457Y-50810D01*
X107475Y-50796D01*
X107478Y-50789D01*
X107482D01*
X107548Y-50749D01*
X107617Y-50716D01*
X107682Y-50694D01*
X107748Y-50679D01*
X107806Y-50672D01*
X107832Y-50669D01*
X107853D01*
X107868Y-50665D01*
X107882D01*
X107890D01*
X107893D01*
X107952Y-50669D01*
D02*
G37*
G36*
X280699Y-195283D02*
X280827Y-195297D01*
X280940Y-195316D01*
X280994Y-195330D01*
X281042Y-195341D01*
X281085Y-195352D01*
X281125Y-195367D01*
X281162Y-195378D01*
X281191Y-195385D01*
X281213Y-195396D01*
X281231Y-195399D01*
X281242Y-195407D01*
X281245D01*
X281355Y-195461D01*
X281453Y-195523D01*
X281537Y-195589D01*
X281570Y-195621D01*
X281602Y-195650D01*
X281631Y-195680D01*
X281657Y-195709D01*
X281679Y-195734D01*
X281693Y-195756D01*
X281708Y-195771D01*
X281719Y-195785D01*
X281722Y-195792D01*
X281726Y-195796D01*
X281755Y-195847D01*
X281781Y-195898D01*
X281821Y-196007D01*
X281850Y-196116D01*
X281868Y-196222D01*
X281875Y-196273D01*
X281883Y-196317D01*
X281886Y-196357D01*
Y-196389D01*
X281890Y-196418D01*
Y-196458D01*
X281886Y-196531D01*
X281879Y-196600D01*
X281872Y-196666D01*
X281857Y-196728D01*
X281839Y-196786D01*
X281821Y-196841D01*
X281802Y-196892D01*
X281781Y-196939D01*
X281762Y-196979D01*
X281744Y-197019D01*
X281726Y-197048D01*
X281708Y-197077D01*
X281693Y-197096D01*
X281686Y-197114D01*
X281679Y-197121D01*
X281675Y-197125D01*
X281631Y-197176D01*
X281588Y-197219D01*
X281537Y-197259D01*
X281486Y-197299D01*
X281384Y-197365D01*
X281282Y-197416D01*
X281235Y-197438D01*
X281191Y-197456D01*
X281151Y-197470D01*
X281118Y-197481D01*
X281089Y-197492D01*
X281067Y-197500D01*
X281053Y-197503D01*
X281049D01*
X280965Y-197168D01*
X281024Y-197154D01*
X281078Y-197136D01*
X281129Y-197117D01*
X281176Y-197099D01*
X281220Y-197077D01*
X281256Y-197055D01*
X281293Y-197030D01*
X281326Y-197008D01*
X281355Y-196990D01*
X281377Y-196968D01*
X281398Y-196950D01*
X281417Y-196935D01*
X281428Y-196921D01*
X281438Y-196910D01*
X281442Y-196906D01*
X281446Y-196903D01*
X281475Y-196866D01*
X281497Y-196826D01*
X281537Y-196746D01*
X281566Y-196670D01*
X281584Y-196593D01*
X281599Y-196528D01*
X281602Y-196502D01*
Y-196477D01*
X281606Y-196455D01*
Y-196429D01*
X281602Y-196346D01*
X281588Y-196266D01*
X281570Y-196193D01*
X281548Y-196127D01*
X281526Y-196076D01*
X281515Y-196054D01*
X281508Y-196036D01*
X281500Y-196022D01*
X281493Y-196011D01*
X281489Y-196003D01*
Y-196000D01*
X281438Y-195931D01*
X281384Y-195872D01*
X281322Y-195821D01*
X281264Y-195782D01*
X281213Y-195749D01*
X281169Y-195727D01*
X281151Y-195720D01*
X281140Y-195712D01*
X281133Y-195709D01*
X281129D01*
X281034Y-195680D01*
X280940Y-195658D01*
X280845Y-195640D01*
X280758Y-195629D01*
X280718Y-195625D01*
X280681Y-195621D01*
X280649D01*
X280623Y-195618D01*
X280601D01*
X280583D01*
X280572D01*
X280569D01*
X280474Y-195621D01*
X280386Y-195629D01*
X280306Y-195643D01*
X280234Y-195658D01*
X280172Y-195669D01*
X280146Y-195676D01*
X280124Y-195683D01*
X280106Y-195687D01*
X280095Y-195691D01*
X280088Y-195694D01*
X280084D01*
X280001Y-195730D01*
X279924Y-195771D01*
X279862Y-195814D01*
X279808Y-195862D01*
X279764Y-195902D01*
X279735Y-195934D01*
X279717Y-195960D01*
X279710Y-195964D01*
Y-195967D01*
X279662Y-196044D01*
X279626Y-196127D01*
X279600Y-196207D01*
X279586Y-196284D01*
X279575Y-196353D01*
X279571Y-196382D01*
Y-196408D01*
X279568Y-196426D01*
Y-196455D01*
X279571Y-196546D01*
X279586Y-196630D01*
X279608Y-196699D01*
X279629Y-196761D01*
X279655Y-196808D01*
X279673Y-196844D01*
X279688Y-196866D01*
X279695Y-196873D01*
X279749Y-196932D01*
X279811Y-196986D01*
X279877Y-197030D01*
X279942Y-197066D01*
X280001Y-197096D01*
X280030Y-197107D01*
X280052Y-197114D01*
X280070Y-197121D01*
X280084Y-197128D01*
X280092Y-197132D01*
X280095D01*
X280019Y-197459D01*
X279953Y-197438D01*
X279895Y-197416D01*
X279840Y-197387D01*
X279786Y-197361D01*
X279739Y-197332D01*
X279695Y-197299D01*
X279651Y-197270D01*
X279615Y-197241D01*
X279586Y-197212D01*
X279557Y-197187D01*
X279531Y-197161D01*
X279513Y-197143D01*
X279495Y-197125D01*
X279484Y-197110D01*
X279480Y-197103D01*
X279476Y-197099D01*
X279444Y-197048D01*
X279411Y-196997D01*
X279385Y-196946D01*
X279364Y-196892D01*
X279331Y-196783D01*
X279309Y-196684D01*
X279298Y-196637D01*
X279294Y-196597D01*
X279291Y-196557D01*
X279287Y-196524D01*
X279284Y-196499D01*
Y-196462D01*
X279291Y-196342D01*
X279309Y-196226D01*
X279331Y-196124D01*
X279345Y-196076D01*
X279360Y-196033D01*
X279375Y-195993D01*
X279389Y-195956D01*
X279400Y-195927D01*
X279411Y-195898D01*
X279422Y-195880D01*
X279429Y-195865D01*
X279433Y-195854D01*
X279436Y-195851D01*
X279498Y-195752D01*
X279571Y-195669D01*
X279644Y-195596D01*
X279717Y-195534D01*
X279782Y-195487D01*
X279811Y-195468D01*
X279837Y-195454D01*
X279855Y-195439D01*
X279870Y-195432D01*
X279880Y-195428D01*
X279884Y-195425D01*
X279997Y-195374D01*
X280114Y-195337D01*
X280230Y-195312D01*
X280335Y-195294D01*
X280383Y-195287D01*
X280430Y-195283D01*
X280467Y-195279D01*
X280503D01*
X280528Y-195275D01*
X280550D01*
X280565D01*
X280569D01*
X280699Y-195283D01*
D02*
G37*
G36*
X280237Y-197791D02*
X280299Y-197798D01*
X280361Y-197805D01*
X280419Y-197820D01*
X280470Y-197838D01*
X280521Y-197856D01*
X280565Y-197874D01*
X280605Y-197896D01*
X280641Y-197915D01*
X280674Y-197933D01*
X280699Y-197951D01*
X280725Y-197969D01*
X280743Y-197984D01*
X280754Y-197991D01*
X280761Y-197998D01*
X280765Y-198002D01*
X280805Y-198042D01*
X280838Y-198086D01*
X280871Y-198129D01*
X280896Y-198177D01*
X280918Y-198220D01*
X280936Y-198264D01*
X280962Y-198348D01*
X280973Y-198384D01*
X280980Y-198421D01*
X280983Y-198450D01*
X280987Y-198479D01*
X280991Y-198501D01*
Y-198530D01*
X280987Y-198599D01*
X280976Y-198664D01*
X280962Y-198723D01*
X280943Y-198777D01*
X280929Y-198817D01*
X280914Y-198850D01*
X280903Y-198872D01*
X280900Y-198879D01*
X280863Y-198937D01*
X280823Y-198988D01*
X280783Y-199032D01*
X280747Y-199068D01*
X280710Y-199094D01*
X280685Y-199116D01*
X280667Y-199130D01*
X280660Y-199134D01*
X280689D01*
X280707D01*
X280718D01*
X280721D01*
X280794Y-199130D01*
X280863Y-199127D01*
X280925Y-199119D01*
X280983Y-199112D01*
X281031Y-199101D01*
X281067Y-199094D01*
X281082Y-199090D01*
X281093D01*
X281096Y-199087D01*
X281100D01*
X281166Y-199068D01*
X281224Y-199050D01*
X281275Y-199032D01*
X281318Y-199014D01*
X281351Y-198999D01*
X281377Y-198985D01*
X281395Y-198977D01*
X281398Y-198974D01*
X281438Y-198945D01*
X281471Y-198916D01*
X281500Y-198886D01*
X281526Y-198857D01*
X281548Y-198836D01*
X281562Y-198814D01*
X281570Y-198799D01*
X281573Y-198795D01*
X281595Y-198755D01*
X281610Y-198712D01*
X281620Y-198672D01*
X281628Y-198632D01*
X281631Y-198599D01*
X281635Y-198573D01*
Y-198548D01*
X281631Y-198490D01*
X281620Y-198435D01*
X281606Y-198388D01*
X281588Y-198348D01*
X281573Y-198319D01*
X281559Y-198293D01*
X281548Y-198278D01*
X281544Y-198275D01*
X281504Y-198239D01*
X281457Y-198209D01*
X281406Y-198184D01*
X281355Y-198166D01*
X281311Y-198151D01*
X281271Y-198140D01*
X281256Y-198137D01*
X281249D01*
X281242Y-198133D01*
X281238D01*
X281264Y-197835D01*
X281369Y-197856D01*
X281460Y-197885D01*
X281540Y-197922D01*
X281606Y-197958D01*
X281657Y-197995D01*
X281679Y-198013D01*
X281697Y-198027D01*
X281708Y-198038D01*
X281719Y-198049D01*
X281722Y-198053D01*
X281726Y-198056D01*
X281755Y-198093D01*
X281781Y-198133D01*
X281821Y-198213D01*
X281850Y-198293D01*
X281868Y-198370D01*
X281883Y-198439D01*
X281886Y-198468D01*
Y-198493D01*
X281890Y-198512D01*
Y-198541D01*
X281883Y-198643D01*
X281868Y-198733D01*
X281842Y-198817D01*
X281813Y-198886D01*
X281802Y-198916D01*
X281788Y-198945D01*
X281773Y-198967D01*
X281762Y-198988D01*
X281755Y-199003D01*
X281748Y-199014D01*
X281741Y-199021D01*
Y-199025D01*
X281679Y-199098D01*
X281610Y-199163D01*
X281537Y-199214D01*
X281468Y-199258D01*
X281406Y-199294D01*
X281377Y-199309D01*
X281355Y-199320D01*
X281333Y-199327D01*
X281318Y-199334D01*
X281311Y-199338D01*
X281307D01*
X281253Y-199356D01*
X281191Y-199374D01*
X281067Y-199400D01*
X280936Y-199418D01*
X280812Y-199429D01*
X280758Y-199436D01*
X280703Y-199440D01*
X280656D01*
X280616Y-199443D01*
X280583D01*
X280558D01*
X280539D01*
X280536D01*
X280452D01*
X280372Y-199440D01*
X280299Y-199432D01*
X280230Y-199425D01*
X280168Y-199418D01*
X280110Y-199411D01*
X280055Y-199400D01*
X280008Y-199389D01*
X279968Y-199378D01*
X279931Y-199371D01*
X279899Y-199360D01*
X279873Y-199352D01*
X279855Y-199345D01*
X279840Y-199338D01*
X279833Y-199334D01*
X279830D01*
X279742Y-199291D01*
X279666Y-199243D01*
X279600Y-199188D01*
X279546Y-199141D01*
X279506Y-199094D01*
X279476Y-199057D01*
X279466Y-199043D01*
X279458Y-199032D01*
X279451Y-199028D01*
Y-199025D01*
X279407Y-198948D01*
X279375Y-198872D01*
X279349Y-198795D01*
X279334Y-198726D01*
X279324Y-198664D01*
X279320Y-198639D01*
Y-198621D01*
X279316Y-198602D01*
Y-198577D01*
X279320Y-198515D01*
X279327Y-198457D01*
X279338Y-198399D01*
X279353Y-198348D01*
X279393Y-198249D01*
X279411Y-198206D01*
X279433Y-198169D01*
X279458Y-198133D01*
X279476Y-198104D01*
X279498Y-198075D01*
X279517Y-198053D01*
X279531Y-198035D01*
X279542Y-198024D01*
X279549Y-198017D01*
X279553Y-198013D01*
X279597Y-197973D01*
X279648Y-197940D01*
X279695Y-197907D01*
X279746Y-197882D01*
X279801Y-197860D01*
X279851Y-197842D01*
X279946Y-197816D01*
X279993Y-197805D01*
X280033Y-197798D01*
X280073Y-197794D01*
X280106Y-197791D01*
X280132Y-197787D01*
X280150D01*
X280164D01*
X280168D01*
X280237Y-197791D01*
D02*
G37*
G36*
X280787Y-199734D02*
X280896Y-199742D01*
X280998Y-199753D01*
X281093Y-199771D01*
X281176Y-199789D01*
X281253Y-199807D01*
X281322Y-199829D01*
X281384Y-199855D01*
X281435Y-199876D01*
X281482Y-199898D01*
X281519Y-199917D01*
X281551Y-199938D01*
X281577Y-199953D01*
X281591Y-199964D01*
X281602Y-199971D01*
X281606Y-199975D01*
X281657Y-200022D01*
X281700Y-200073D01*
X281737Y-200124D01*
X281770Y-200175D01*
X281799Y-200230D01*
X281821Y-200280D01*
X281839Y-200331D01*
X281853Y-200382D01*
X281864Y-200426D01*
X281875Y-200470D01*
X281883Y-200506D01*
X281886Y-200539D01*
Y-200568D01*
X281890Y-200586D01*
Y-200605D01*
X281886Y-200688D01*
X281872Y-200765D01*
X281857Y-200834D01*
X281835Y-200896D01*
X281817Y-200943D01*
X281799Y-200979D01*
X281795Y-200994D01*
X281788Y-201005D01*
X281784Y-201009D01*
Y-201012D01*
X281741Y-201074D01*
X281690Y-201132D01*
X281639Y-201180D01*
X281588Y-201220D01*
X281540Y-201252D01*
X281504Y-201274D01*
X281489Y-201281D01*
X281479Y-201289D01*
X281475Y-201292D01*
X281471D01*
X281395Y-201329D01*
X281315Y-201354D01*
X281242Y-201373D01*
X281173Y-201383D01*
X281115Y-201394D01*
X281093D01*
X281071Y-201398D01*
X281053D01*
X281042D01*
X281034D01*
X281031D01*
X280965Y-201394D01*
X280903Y-201387D01*
X280841Y-201376D01*
X280787Y-201365D01*
X280736Y-201347D01*
X280685Y-201329D01*
X280641Y-201311D01*
X280601Y-201289D01*
X280565Y-201267D01*
X280532Y-201249D01*
X280507Y-201231D01*
X280481Y-201212D01*
X280463Y-201202D01*
X280452Y-201190D01*
X280445Y-201183D01*
X280441Y-201180D01*
X280401Y-201140D01*
X280365Y-201096D01*
X280335Y-201049D01*
X280310Y-201005D01*
X280285Y-200961D01*
X280266Y-200918D01*
X280241Y-200834D01*
X280230Y-200797D01*
X280223Y-200761D01*
X280219Y-200732D01*
X280215Y-200703D01*
X280212Y-200681D01*
Y-200652D01*
X280215Y-200586D01*
X280226Y-200524D01*
X280237Y-200466D01*
X280252Y-200415D01*
X280270Y-200372D01*
X280281Y-200339D01*
X280292Y-200317D01*
X280295Y-200313D01*
Y-200310D01*
X280332Y-200251D01*
X280372Y-200201D01*
X280412Y-200153D01*
X280456Y-200117D01*
X280492Y-200084D01*
X280521Y-200059D01*
X280543Y-200044D01*
X280547Y-200040D01*
X280481D01*
X280416Y-200044D01*
X280357Y-200048D01*
X280299Y-200055D01*
X280248Y-200059D01*
X280201Y-200066D01*
X280157Y-200073D01*
X280117Y-200084D01*
X280081Y-200091D01*
X280052Y-200098D01*
X280026Y-200106D01*
X280004Y-200110D01*
X279990Y-200117D01*
X279979Y-200120D01*
X279972Y-200124D01*
X279968D01*
X279895Y-200160D01*
X279830Y-200197D01*
X279779Y-200237D01*
X279735Y-200273D01*
X279698Y-200306D01*
X279673Y-200331D01*
X279659Y-200350D01*
X279655Y-200357D01*
X279626Y-200401D01*
X279608Y-200444D01*
X279593Y-200488D01*
X279582Y-200532D01*
X279575Y-200565D01*
X279571Y-200594D01*
Y-200619D01*
X279578Y-200685D01*
X279593Y-200746D01*
X279615Y-200797D01*
X279637Y-200845D01*
X279662Y-200881D01*
X279684Y-200907D01*
X279698Y-200921D01*
X279706Y-200928D01*
X279739Y-200954D01*
X279779Y-200979D01*
X279822Y-201001D01*
X279866Y-201016D01*
X279906Y-201030D01*
X279939Y-201041D01*
X279961Y-201045D01*
X279964Y-201049D01*
X279968D01*
X279942Y-201358D01*
X279840Y-201336D01*
X279749Y-201303D01*
X279669Y-201267D01*
X279604Y-201227D01*
X279553Y-201187D01*
X279531Y-201172D01*
X279513Y-201154D01*
X279502Y-201143D01*
X279491Y-201132D01*
X279487Y-201129D01*
X279484Y-201125D01*
X279455Y-201089D01*
X279429Y-201049D01*
X279385Y-200969D01*
X279356Y-200888D01*
X279338Y-200812D01*
X279324Y-200743D01*
X279320Y-200714D01*
Y-200688D01*
X279316Y-200666D01*
Y-200637D01*
X279320Y-200565D01*
X279327Y-200495D01*
X279342Y-200430D01*
X279360Y-200368D01*
X279385Y-200313D01*
X279407Y-200259D01*
X279436Y-200211D01*
X279462Y-200168D01*
X279487Y-200131D01*
X279517Y-200095D01*
X279538Y-200066D01*
X279560Y-200044D01*
X279582Y-200026D01*
X279597Y-200011D01*
X279604Y-200004D01*
X279608Y-200000D01*
X279673Y-199953D01*
X279749Y-199913D01*
X279830Y-199876D01*
X279913Y-199844D01*
X280001Y-199818D01*
X280088Y-199796D01*
X280179Y-199778D01*
X280263Y-199764D01*
X280346Y-199753D01*
X280423Y-199746D01*
X280492Y-199738D01*
X280550Y-199734D01*
X280601D01*
X280638Y-199731D01*
X280652D01*
X280663D01*
X280667D01*
X280670D01*
X280787Y-199734D01*
D02*
G37*
G36*
X336130Y-290344D02*
X336189Y-290351D01*
X336247Y-290362D01*
X336298Y-290376D01*
X336396Y-290416D01*
X336440Y-290435D01*
X336476Y-290456D01*
X336513Y-290482D01*
X336542Y-290500D01*
X336571Y-290522D01*
X336593Y-290540D01*
X336611Y-290555D01*
X336622Y-290566D01*
X336629Y-290573D01*
X336633Y-290577D01*
X336673Y-290620D01*
X336706Y-290671D01*
X336738Y-290719D01*
X336764Y-290770D01*
X336786Y-290824D01*
X336804Y-290875D01*
X336829Y-290970D01*
X336840Y-291017D01*
X336848Y-291057D01*
X336851Y-291097D01*
X336855Y-291130D01*
X336859Y-291155D01*
Y-291174D01*
Y-291188D01*
Y-291192D01*
X336855Y-291261D01*
X336848Y-291323D01*
X336840Y-291385D01*
X336826Y-291443D01*
X336808Y-291494D01*
X336789Y-291545D01*
X336771Y-291588D01*
X336749Y-291629D01*
X336731Y-291665D01*
X336713Y-291698D01*
X336695Y-291723D01*
X336677Y-291749D01*
X336662Y-291767D01*
X336655Y-291778D01*
X336647Y-291785D01*
X336644Y-291789D01*
X336604Y-291829D01*
X336560Y-291862D01*
X336516Y-291894D01*
X336469Y-291920D01*
X336425Y-291942D01*
X336382Y-291960D01*
X336298Y-291985D01*
X336262Y-291996D01*
X336225Y-292003D01*
X336196Y-292007D01*
X336167Y-292011D01*
X336145Y-292014D01*
X336116D01*
X336047Y-292011D01*
X335981Y-292000D01*
X335923Y-291985D01*
X335868Y-291967D01*
X335828Y-291952D01*
X335796Y-291938D01*
X335774Y-291927D01*
X335767Y-291923D01*
X335708Y-291887D01*
X335657Y-291847D01*
X335614Y-291807D01*
X335577Y-291771D01*
X335552Y-291734D01*
X335530Y-291709D01*
X335515Y-291690D01*
X335512Y-291683D01*
Y-291712D01*
Y-291730D01*
Y-291741D01*
Y-291745D01*
X335515Y-291818D01*
X335519Y-291887D01*
X335526Y-291949D01*
X335534Y-292007D01*
X335544Y-292054D01*
X335552Y-292091D01*
X335555Y-292105D01*
Y-292116D01*
X335559Y-292120D01*
Y-292124D01*
X335577Y-292189D01*
X335595Y-292247D01*
X335614Y-292298D01*
X335632Y-292342D01*
X335646Y-292375D01*
X335661Y-292400D01*
X335668Y-292418D01*
X335672Y-292422D01*
X335701Y-292462D01*
X335730Y-292495D01*
X335759Y-292524D01*
X335788Y-292549D01*
X335810Y-292571D01*
X335832Y-292586D01*
X335847Y-292593D01*
X335850Y-292597D01*
X335890Y-292619D01*
X335934Y-292633D01*
X335974Y-292644D01*
X336014Y-292651D01*
X336047Y-292655D01*
X336072Y-292659D01*
X336098D01*
X336156Y-292655D01*
X336211Y-292644D01*
X336258Y-292630D01*
X336298Y-292611D01*
X336327Y-292597D01*
X336353Y-292582D01*
X336367Y-292571D01*
X336371Y-292568D01*
X336407Y-292528D01*
X336436Y-292480D01*
X336462Y-292429D01*
X336480Y-292378D01*
X336494Y-292335D01*
X336506Y-292295D01*
X336509Y-292280D01*
Y-292273D01*
X336513Y-292266D01*
Y-292262D01*
X336811Y-292287D01*
X336789Y-292393D01*
X336760Y-292484D01*
X336724Y-292564D01*
X336687Y-292630D01*
X336651Y-292681D01*
X336633Y-292702D01*
X336618Y-292721D01*
X336607Y-292731D01*
X336596Y-292742D01*
X336593Y-292746D01*
X336589Y-292750D01*
X336553Y-292779D01*
X336513Y-292804D01*
X336433Y-292844D01*
X336353Y-292873D01*
X336276Y-292892D01*
X336207Y-292906D01*
X336178Y-292910D01*
X336152D01*
X336134Y-292913D01*
X336105D01*
X336003Y-292906D01*
X335912Y-292892D01*
X335828Y-292866D01*
X335759Y-292837D01*
X335730Y-292826D01*
X335701Y-292811D01*
X335679Y-292797D01*
X335657Y-292786D01*
X335643Y-292779D01*
X335632Y-292772D01*
X335625Y-292764D01*
X335621D01*
X335548Y-292702D01*
X335483Y-292633D01*
X335432Y-292560D01*
X335388Y-292491D01*
X335352Y-292429D01*
X335337Y-292400D01*
X335326Y-292378D01*
X335319Y-292356D01*
X335312Y-292342D01*
X335308Y-292335D01*
Y-292331D01*
X335290Y-292276D01*
X335272Y-292215D01*
X335246Y-292091D01*
X335228Y-291960D01*
X335217Y-291836D01*
X335210Y-291781D01*
X335206Y-291727D01*
Y-291680D01*
X335202Y-291639D01*
Y-291607D01*
Y-291581D01*
Y-291563D01*
Y-291559D01*
Y-291476D01*
X335206Y-291396D01*
X335213Y-291323D01*
X335221Y-291254D01*
X335228Y-291192D01*
X335235Y-291133D01*
X335246Y-291079D01*
X335257Y-291032D01*
X335268Y-290991D01*
X335275Y-290955D01*
X335286Y-290922D01*
X335293Y-290897D01*
X335301Y-290879D01*
X335308Y-290864D01*
X335312Y-290857D01*
Y-290853D01*
X335355Y-290766D01*
X335402Y-290689D01*
X335457Y-290624D01*
X335504Y-290569D01*
X335552Y-290529D01*
X335588Y-290500D01*
X335603Y-290489D01*
X335614Y-290482D01*
X335617Y-290475D01*
X335621D01*
X335697Y-290431D01*
X335774Y-290398D01*
X335850Y-290373D01*
X335919Y-290358D01*
X335981Y-290347D01*
X336007Y-290344D01*
X336025D01*
X336043Y-290340D01*
X336069D01*
X336130Y-290344D01*
D02*
G37*
G36*
X338304Y-290315D02*
X338420Y-290333D01*
X338522Y-290354D01*
X338569Y-290369D01*
X338613Y-290384D01*
X338653Y-290398D01*
X338689Y-290413D01*
X338719Y-290424D01*
X338748Y-290435D01*
X338766Y-290445D01*
X338780Y-290453D01*
X338791Y-290456D01*
X338795Y-290460D01*
X338893Y-290522D01*
X338977Y-290595D01*
X339050Y-290668D01*
X339112Y-290740D01*
X339159Y-290806D01*
X339177Y-290835D01*
X339192Y-290861D01*
X339206Y-290879D01*
X339214Y-290893D01*
X339217Y-290904D01*
X339221Y-290908D01*
X339272Y-291021D01*
X339308Y-291137D01*
X339334Y-291254D01*
X339352Y-291359D01*
X339359Y-291406D01*
X339363Y-291454D01*
X339367Y-291490D01*
Y-291527D01*
X339370Y-291552D01*
Y-291574D01*
Y-291588D01*
Y-291592D01*
X339363Y-291723D01*
X339348Y-291851D01*
X339330Y-291963D01*
X339316Y-292018D01*
X339305Y-292065D01*
X339294Y-292109D01*
X339279Y-292149D01*
X339268Y-292185D01*
X339261Y-292215D01*
X339250Y-292236D01*
X339246Y-292255D01*
X339239Y-292266D01*
Y-292269D01*
X339184Y-292378D01*
X339123Y-292477D01*
X339057Y-292560D01*
X339024Y-292593D01*
X338995Y-292626D01*
X338966Y-292655D01*
X338937Y-292681D01*
X338912Y-292702D01*
X338890Y-292717D01*
X338875Y-292731D01*
X338861Y-292742D01*
X338853Y-292746D01*
X338850Y-292750D01*
X338799Y-292779D01*
X338748Y-292804D01*
X338638Y-292844D01*
X338529Y-292873D01*
X338424Y-292892D01*
X338373Y-292899D01*
X338329Y-292906D01*
X338289Y-292910D01*
X338256D01*
X338227Y-292913D01*
X338187D01*
X338114Y-292910D01*
X338045Y-292902D01*
X337980Y-292895D01*
X337918Y-292881D01*
X337860Y-292863D01*
X337805Y-292844D01*
X337754Y-292826D01*
X337707Y-292804D01*
X337667Y-292786D01*
X337627Y-292768D01*
X337597Y-292750D01*
X337568Y-292731D01*
X337550Y-292717D01*
X337532Y-292710D01*
X337525Y-292702D01*
X337521Y-292699D01*
X337470Y-292655D01*
X337426Y-292611D01*
X337386Y-292560D01*
X337346Y-292509D01*
X337281Y-292407D01*
X337230Y-292306D01*
X337208Y-292258D01*
X337190Y-292215D01*
X337175Y-292175D01*
X337164Y-292142D01*
X337153Y-292113D01*
X337146Y-292091D01*
X337142Y-292076D01*
Y-292073D01*
X337477Y-291989D01*
X337492Y-292047D01*
X337510Y-292102D01*
X337528Y-292153D01*
X337546Y-292200D01*
X337568Y-292244D01*
X337590Y-292280D01*
X337616Y-292317D01*
X337637Y-292349D01*
X337656Y-292378D01*
X337678Y-292400D01*
X337696Y-292422D01*
X337710Y-292440D01*
X337725Y-292451D01*
X337736Y-292462D01*
X337739Y-292466D01*
X337743Y-292469D01*
X337779Y-292498D01*
X337820Y-292520D01*
X337900Y-292560D01*
X337976Y-292589D01*
X338052Y-292608D01*
X338118Y-292622D01*
X338143Y-292626D01*
X338169D01*
X338191Y-292630D01*
X338216D01*
X338300Y-292626D01*
X338380Y-292611D01*
X338453Y-292593D01*
X338518Y-292571D01*
X338569Y-292549D01*
X338591Y-292538D01*
X338609Y-292531D01*
X338624Y-292524D01*
X338635Y-292517D01*
X338642Y-292513D01*
X338646D01*
X338715Y-292462D01*
X338773Y-292407D01*
X338824Y-292346D01*
X338864Y-292287D01*
X338897Y-292236D01*
X338919Y-292193D01*
X338926Y-292175D01*
X338933Y-292164D01*
X338937Y-292156D01*
Y-292153D01*
X338966Y-292058D01*
X338988Y-291963D01*
X339006Y-291869D01*
X339017Y-291781D01*
X339021Y-291741D01*
X339024Y-291705D01*
Y-291672D01*
X339028Y-291647D01*
Y-291625D01*
Y-291607D01*
Y-291596D01*
Y-291592D01*
X339024Y-291497D01*
X339017Y-291410D01*
X339002Y-291330D01*
X338988Y-291257D01*
X338977Y-291195D01*
X338970Y-291170D01*
X338962Y-291148D01*
X338959Y-291130D01*
X338955Y-291119D01*
X338951Y-291112D01*
Y-291108D01*
X338915Y-291024D01*
X338875Y-290948D01*
X338831Y-290886D01*
X338784Y-290831D01*
X338744Y-290788D01*
X338711Y-290759D01*
X338686Y-290740D01*
X338682Y-290733D01*
X338679D01*
X338602Y-290686D01*
X338518Y-290649D01*
X338438Y-290624D01*
X338362Y-290609D01*
X338293Y-290598D01*
X338264Y-290595D01*
X338238D01*
X338220Y-290591D01*
X338191D01*
X338100Y-290595D01*
X338016Y-290609D01*
X337947Y-290631D01*
X337885Y-290653D01*
X337838Y-290679D01*
X337801Y-290697D01*
X337779Y-290711D01*
X337772Y-290719D01*
X337714Y-290773D01*
X337659Y-290835D01*
X337616Y-290900D01*
X337579Y-290966D01*
X337550Y-291024D01*
X337539Y-291053D01*
X337532Y-291075D01*
X337525Y-291093D01*
X337517Y-291108D01*
X337514Y-291115D01*
Y-291119D01*
X337186Y-291042D01*
X337208Y-290977D01*
X337230Y-290919D01*
X337259Y-290864D01*
X337284Y-290809D01*
X337314Y-290762D01*
X337346Y-290719D01*
X337375Y-290675D01*
X337404Y-290638D01*
X337434Y-290609D01*
X337459Y-290580D01*
X337485Y-290555D01*
X337503Y-290536D01*
X337521Y-290518D01*
X337536Y-290507D01*
X337543Y-290504D01*
X337546Y-290500D01*
X337597Y-290467D01*
X337648Y-290435D01*
X337699Y-290409D01*
X337754Y-290387D01*
X337863Y-290354D01*
X337962Y-290333D01*
X338009Y-290322D01*
X338049Y-290318D01*
X338089Y-290315D01*
X338122Y-290311D01*
X338147Y-290307D01*
X338183D01*
X338304Y-290315D01*
D02*
G37*
G36*
X335006Y-291982D02*
Y-292266D01*
X333910D01*
Y-292870D01*
X333601D01*
Y-292266D01*
X333259D01*
Y-291982D01*
X333601D01*
Y-290351D01*
X333852D01*
X335006Y-291982D01*
D02*
G37*
G36*
X315948Y-292467D02*
X315657Y-292507D01*
X315631Y-292467D01*
X315599Y-292434D01*
X315569Y-292401D01*
X315540Y-292376D01*
X315511Y-292358D01*
X315489Y-292339D01*
X315475Y-292332D01*
X315471Y-292329D01*
X315424Y-292307D01*
X315376Y-292288D01*
X315333Y-292278D01*
X315289Y-292267D01*
X315253Y-292263D01*
X315224Y-292259D01*
X315154D01*
X315111Y-292267D01*
X315034Y-292285D01*
X314969Y-292310D01*
X314911Y-292336D01*
X314867Y-292365D01*
X314834Y-292390D01*
X314816Y-292409D01*
X314809Y-292412D01*
Y-292416D01*
X314758Y-292478D01*
X314721Y-292543D01*
X314696Y-292613D01*
X314678Y-292682D01*
X314667Y-292740D01*
X314663Y-292765D01*
Y-292787D01*
X314659Y-292805D01*
Y-292820D01*
Y-292827D01*
Y-292831D01*
Y-292882D01*
X314667Y-292929D01*
X314685Y-293020D01*
X314710Y-293097D01*
X314736Y-293159D01*
X314765Y-293209D01*
X314791Y-293250D01*
X314801Y-293260D01*
X314809Y-293271D01*
X314812Y-293275D01*
X314816Y-293279D01*
X314845Y-293308D01*
X314874Y-293333D01*
X314940Y-293377D01*
X315002Y-293406D01*
X315064Y-293424D01*
X315114Y-293439D01*
X315158Y-293442D01*
X315173Y-293446D01*
X315195D01*
X315264Y-293442D01*
X315325Y-293428D01*
X315380Y-293410D01*
X315424Y-293388D01*
X315464Y-293366D01*
X315493Y-293348D01*
X315508Y-293333D01*
X315515Y-293330D01*
X315559Y-293279D01*
X315595Y-293224D01*
X315624Y-293162D01*
X315646Y-293108D01*
X315660Y-293053D01*
X315671Y-293013D01*
X315675Y-292995D01*
X315679Y-292984D01*
Y-292976D01*
Y-292973D01*
X316003Y-292998D01*
X315995Y-293057D01*
X315984Y-293111D01*
X315952Y-293213D01*
X315912Y-293300D01*
X315890Y-293340D01*
X315868Y-293373D01*
X315850Y-293406D01*
X315828Y-293435D01*
X315810Y-293457D01*
X315791Y-293475D01*
X315777Y-293490D01*
X315770Y-293504D01*
X315762Y-293508D01*
X315759Y-293512D01*
X315715Y-293544D01*
X315671Y-293573D01*
X315624Y-293599D01*
X315577Y-293621D01*
X315486Y-293653D01*
X315395Y-293675D01*
X315355Y-293686D01*
X315315Y-293690D01*
X315282Y-293694D01*
X315253Y-293697D01*
X315227Y-293701D01*
X315195D01*
X315118Y-293697D01*
X315045Y-293686D01*
X314976Y-293672D01*
X314914Y-293653D01*
X314856Y-293628D01*
X314801Y-293603D01*
X314750Y-293577D01*
X314707Y-293548D01*
X314667Y-293519D01*
X314630Y-293493D01*
X314601Y-293464D01*
X314576Y-293442D01*
X314558Y-293424D01*
X314543Y-293410D01*
X314536Y-293399D01*
X314532Y-293395D01*
X314496Y-293348D01*
X314467Y-293297D01*
X314437Y-293250D01*
X314416Y-293198D01*
X314379Y-293100D01*
X314357Y-293006D01*
X314350Y-292966D01*
X314343Y-292926D01*
X314339Y-292893D01*
X314335Y-292864D01*
X314332Y-292838D01*
Y-292820D01*
Y-292809D01*
Y-292805D01*
X314335Y-292740D01*
X314343Y-292678D01*
X314354Y-292616D01*
X314368Y-292562D01*
X314386Y-292511D01*
X314405Y-292460D01*
X314426Y-292416D01*
X314445Y-292376D01*
X314467Y-292339D01*
X314488Y-292307D01*
X314507Y-292281D01*
X314525Y-292256D01*
X314539Y-292238D01*
X314550Y-292227D01*
X314558Y-292219D01*
X314561Y-292216D01*
X314605Y-292176D01*
X314649Y-292139D01*
X314696Y-292110D01*
X314743Y-292085D01*
X314791Y-292059D01*
X314838Y-292041D01*
X314925Y-292016D01*
X314965Y-292005D01*
X315002Y-291997D01*
X315034Y-291994D01*
X315064Y-291990D01*
X315085Y-291986D01*
X315165D01*
X315209Y-291994D01*
X315296Y-292012D01*
X315376Y-292037D01*
X315449Y-292067D01*
X315508Y-292096D01*
X315533Y-292110D01*
X315555Y-292121D01*
X315573Y-292132D01*
X315584Y-292139D01*
X315591Y-292143D01*
X315595Y-292147D01*
X315460Y-291466D01*
X314452D01*
Y-291171D01*
X315704D01*
X315948Y-292467D01*
D02*
G37*
G36*
X317233Y-291131D02*
X317291Y-291138D01*
X317349Y-291149D01*
X317400Y-291164D01*
X317499Y-291204D01*
X317542Y-291222D01*
X317579Y-291244D01*
X317615Y-291269D01*
X317644Y-291287D01*
X317673Y-291309D01*
X317695Y-291328D01*
X317713Y-291342D01*
X317724Y-291353D01*
X317732Y-291360D01*
X317735Y-291364D01*
X317775Y-291408D01*
X317808Y-291459D01*
X317841Y-291506D01*
X317866Y-291557D01*
X317888Y-291612D01*
X317906Y-291662D01*
X317932Y-291757D01*
X317943Y-291804D01*
X317950Y-291844D01*
X317954Y-291884D01*
X317957Y-291917D01*
X317961Y-291943D01*
Y-291961D01*
Y-291975D01*
Y-291979D01*
X317957Y-292048D01*
X317950Y-292110D01*
X317943Y-292172D01*
X317928Y-292230D01*
X317910Y-292281D01*
X317892Y-292332D01*
X317874Y-292376D01*
X317852Y-292416D01*
X317833Y-292452D01*
X317815Y-292485D01*
X317797Y-292511D01*
X317779Y-292536D01*
X317764Y-292554D01*
X317757Y-292565D01*
X317750Y-292572D01*
X317746Y-292576D01*
X317706Y-292616D01*
X317662Y-292649D01*
X317619Y-292682D01*
X317571Y-292707D01*
X317528Y-292729D01*
X317484Y-292747D01*
X317400Y-292773D01*
X317364Y-292784D01*
X317327Y-292791D01*
X317298Y-292794D01*
X317269Y-292798D01*
X317247Y-292802D01*
X317218D01*
X317149Y-292798D01*
X317084Y-292787D01*
X317025Y-292773D01*
X316971Y-292754D01*
X316931Y-292740D01*
X316898Y-292725D01*
X316876Y-292714D01*
X316869Y-292711D01*
X316811Y-292674D01*
X316760Y-292634D01*
X316716Y-292594D01*
X316680Y-292558D01*
X316654Y-292522D01*
X316632Y-292496D01*
X316618Y-292478D01*
X316614Y-292471D01*
Y-292500D01*
Y-292518D01*
Y-292529D01*
Y-292532D01*
X316618Y-292605D01*
X316621Y-292674D01*
X316629Y-292736D01*
X316636Y-292794D01*
X316647Y-292842D01*
X316654Y-292878D01*
X316658Y-292893D01*
Y-292904D01*
X316661Y-292907D01*
Y-292911D01*
X316680Y-292976D01*
X316698Y-293035D01*
X316716Y-293086D01*
X316734Y-293129D01*
X316749Y-293162D01*
X316763Y-293188D01*
X316771Y-293206D01*
X316774Y-293209D01*
X316803Y-293250D01*
X316832Y-293282D01*
X316862Y-293311D01*
X316891Y-293337D01*
X316913Y-293359D01*
X316934Y-293373D01*
X316949Y-293380D01*
X316953Y-293384D01*
X316993Y-293406D01*
X317036Y-293421D01*
X317076Y-293431D01*
X317116Y-293439D01*
X317149Y-293442D01*
X317175Y-293446D01*
X317200D01*
X317258Y-293442D01*
X317313Y-293431D01*
X317360Y-293417D01*
X317400Y-293399D01*
X317429Y-293384D01*
X317455Y-293370D01*
X317470Y-293359D01*
X317473Y-293355D01*
X317510Y-293315D01*
X317539Y-293268D01*
X317564Y-293217D01*
X317582Y-293166D01*
X317597Y-293122D01*
X317608Y-293082D01*
X317612Y-293068D01*
Y-293060D01*
X317615Y-293053D01*
Y-293049D01*
X317914Y-293075D01*
X317892Y-293180D01*
X317863Y-293271D01*
X317826Y-293351D01*
X317790Y-293417D01*
X317753Y-293468D01*
X317735Y-293490D01*
X317721Y-293508D01*
X317710Y-293519D01*
X317699Y-293530D01*
X317695Y-293533D01*
X317691Y-293537D01*
X317655Y-293566D01*
X317615Y-293592D01*
X317535Y-293632D01*
X317455Y-293661D01*
X317378Y-293679D01*
X317309Y-293694D01*
X317280Y-293697D01*
X317255D01*
X317236Y-293701D01*
X317207D01*
X317106Y-293694D01*
X317015Y-293679D01*
X316931Y-293653D01*
X316862Y-293624D01*
X316832Y-293614D01*
X316803Y-293599D01*
X316781Y-293584D01*
X316760Y-293573D01*
X316745Y-293566D01*
X316734Y-293559D01*
X316727Y-293552D01*
X316723D01*
X316651Y-293490D01*
X316585Y-293421D01*
X316534Y-293348D01*
X316490Y-293279D01*
X316454Y-293217D01*
X316439Y-293188D01*
X316428Y-293166D01*
X316421Y-293144D01*
X316414Y-293129D01*
X316410Y-293122D01*
Y-293118D01*
X316392Y-293064D01*
X316374Y-293002D01*
X316348Y-292878D01*
X316330Y-292747D01*
X316319Y-292623D01*
X316312Y-292569D01*
X316308Y-292514D01*
Y-292467D01*
X316305Y-292427D01*
Y-292394D01*
Y-292369D01*
Y-292350D01*
Y-292347D01*
Y-292263D01*
X316308Y-292183D01*
X316316Y-292110D01*
X316323Y-292041D01*
X316330Y-291979D01*
X316337Y-291921D01*
X316348Y-291866D01*
X316359Y-291819D01*
X316370Y-291779D01*
X316377Y-291742D01*
X316388Y-291710D01*
X316396Y-291684D01*
X316403Y-291666D01*
X316410Y-291652D01*
X316414Y-291644D01*
Y-291641D01*
X316458Y-291553D01*
X316505Y-291477D01*
X316560Y-291411D01*
X316607Y-291357D01*
X316654Y-291317D01*
X316690Y-291287D01*
X316705Y-291277D01*
X316716Y-291269D01*
X316720Y-291262D01*
X316723D01*
X316800Y-291218D01*
X316876Y-291186D01*
X316953Y-291160D01*
X317022Y-291146D01*
X317084Y-291135D01*
X317109Y-291131D01*
X317127D01*
X317145Y-291127D01*
X317171D01*
X317233Y-291131D01*
D02*
G37*
G36*
X319406Y-291102D02*
X319522Y-291120D01*
X319624Y-291142D01*
X319672Y-291157D01*
X319715Y-291171D01*
X319755Y-291186D01*
X319792Y-291200D01*
X319821Y-291211D01*
X319850Y-291222D01*
X319868Y-291233D01*
X319883Y-291240D01*
X319894Y-291244D01*
X319897Y-291248D01*
X319996Y-291309D01*
X320079Y-291382D01*
X320152Y-291455D01*
X320214Y-291528D01*
X320261Y-291593D01*
X320280Y-291622D01*
X320294Y-291648D01*
X320309Y-291666D01*
X320316Y-291681D01*
X320320Y-291692D01*
X320323Y-291695D01*
X320374Y-291808D01*
X320411Y-291925D01*
X320436Y-292041D01*
X320454Y-292147D01*
X320462Y-292194D01*
X320465Y-292241D01*
X320469Y-292278D01*
Y-292314D01*
X320473Y-292339D01*
Y-292361D01*
Y-292376D01*
Y-292379D01*
X320465Y-292511D01*
X320451Y-292638D01*
X320432Y-292751D01*
X320418Y-292805D01*
X320407Y-292853D01*
X320396Y-292896D01*
X320381Y-292936D01*
X320371Y-292973D01*
X320363Y-293002D01*
X320352Y-293024D01*
X320349Y-293042D01*
X320341Y-293053D01*
Y-293057D01*
X320287Y-293166D01*
X320225Y-293264D01*
X320160Y-293348D01*
X320127Y-293380D01*
X320098Y-293413D01*
X320068Y-293442D01*
X320039Y-293468D01*
X320014Y-293490D01*
X319992Y-293504D01*
X319977Y-293519D01*
X319963Y-293530D01*
X319956Y-293533D01*
X319952Y-293537D01*
X319901Y-293566D01*
X319850Y-293592D01*
X319741Y-293632D01*
X319632Y-293661D01*
X319526Y-293679D01*
X319475Y-293686D01*
X319431Y-293694D01*
X319391Y-293697D01*
X319359D01*
X319330Y-293701D01*
X319289D01*
X319217Y-293697D01*
X319147Y-293690D01*
X319082Y-293683D01*
X319020Y-293668D01*
X318962Y-293650D01*
X318907Y-293632D01*
X318856Y-293614D01*
X318809Y-293592D01*
X318769Y-293573D01*
X318729Y-293555D01*
X318700Y-293537D01*
X318671Y-293519D01*
X318653Y-293504D01*
X318634Y-293497D01*
X318627Y-293490D01*
X318623Y-293486D01*
X318572Y-293442D01*
X318529Y-293399D01*
X318489Y-293348D01*
X318449Y-293297D01*
X318383Y-293195D01*
X318332Y-293093D01*
X318310Y-293046D01*
X318292Y-293002D01*
X318278Y-292962D01*
X318267Y-292929D01*
X318256Y-292900D01*
X318249Y-292878D01*
X318245Y-292864D01*
Y-292860D01*
X318580Y-292776D01*
X318594Y-292834D01*
X318612Y-292889D01*
X318631Y-292940D01*
X318649Y-292987D01*
X318671Y-293031D01*
X318692Y-293068D01*
X318718Y-293104D01*
X318740Y-293137D01*
X318758Y-293166D01*
X318780Y-293188D01*
X318798Y-293209D01*
X318813Y-293228D01*
X318827Y-293239D01*
X318838Y-293250D01*
X318842Y-293253D01*
X318845Y-293257D01*
X318882Y-293286D01*
X318922Y-293308D01*
X319002Y-293348D01*
X319078Y-293377D01*
X319155Y-293395D01*
X319220Y-293410D01*
X319246Y-293413D01*
X319271D01*
X319293Y-293417D01*
X319319D01*
X319402Y-293413D01*
X319482Y-293399D01*
X319555Y-293380D01*
X319621Y-293359D01*
X319672Y-293337D01*
X319693Y-293326D01*
X319712Y-293319D01*
X319726Y-293311D01*
X319737Y-293304D01*
X319744Y-293300D01*
X319748D01*
X319817Y-293250D01*
X319876Y-293195D01*
X319927Y-293133D01*
X319967Y-293075D01*
X319999Y-293024D01*
X320021Y-292980D01*
X320028Y-292962D01*
X320036Y-292951D01*
X320039Y-292944D01*
Y-292940D01*
X320068Y-292845D01*
X320090Y-292751D01*
X320109Y-292656D01*
X320119Y-292569D01*
X320123Y-292529D01*
X320127Y-292492D01*
Y-292460D01*
X320130Y-292434D01*
Y-292412D01*
Y-292394D01*
Y-292383D01*
Y-292379D01*
X320127Y-292285D01*
X320119Y-292197D01*
X320105Y-292117D01*
X320090Y-292045D01*
X320079Y-291983D01*
X320072Y-291957D01*
X320065Y-291935D01*
X320061Y-291917D01*
X320058Y-291906D01*
X320054Y-291899D01*
Y-291895D01*
X320018Y-291812D01*
X319977Y-291735D01*
X319934Y-291673D01*
X319886Y-291619D01*
X319846Y-291575D01*
X319814Y-291546D01*
X319788Y-291528D01*
X319784Y-291521D01*
X319781D01*
X319704Y-291473D01*
X319621Y-291437D01*
X319541Y-291411D01*
X319464Y-291397D01*
X319395Y-291386D01*
X319366Y-291382D01*
X319340D01*
X319322Y-291378D01*
X319293D01*
X319202Y-291382D01*
X319118Y-291397D01*
X319049Y-291419D01*
X318987Y-291440D01*
X318940Y-291466D01*
X318904Y-291484D01*
X318882Y-291499D01*
X318875Y-291506D01*
X318816Y-291561D01*
X318762Y-291622D01*
X318718Y-291688D01*
X318682Y-291753D01*
X318653Y-291812D01*
X318642Y-291841D01*
X318634Y-291863D01*
X318627Y-291881D01*
X318620Y-291895D01*
X318616Y-291903D01*
Y-291906D01*
X318288Y-291830D01*
X318310Y-291764D01*
X318332Y-291706D01*
X318361Y-291652D01*
X318387Y-291597D01*
X318416Y-291550D01*
X318449Y-291506D01*
X318478Y-291462D01*
X318507Y-291426D01*
X318536Y-291397D01*
X318562Y-291368D01*
X318587Y-291342D01*
X318605Y-291324D01*
X318623Y-291306D01*
X318638Y-291295D01*
X318645Y-291291D01*
X318649Y-291287D01*
X318700Y-291255D01*
X318751Y-291222D01*
X318802Y-291196D01*
X318856Y-291175D01*
X318966Y-291142D01*
X319064Y-291120D01*
X319111Y-291109D01*
X319151Y-291106D01*
X319191Y-291102D01*
X319224Y-291098D01*
X319249Y-291095D01*
X319286D01*
X319406Y-291102D01*
D02*
G37*
G36*
X322260Y-237194D02*
X322329Y-237201D01*
X322395Y-237216D01*
X322457Y-237234D01*
X322511Y-237260D01*
X322566Y-237281D01*
X322613Y-237311D01*
X322657Y-237336D01*
X322693Y-237361D01*
X322730Y-237390D01*
X322759Y-237412D01*
X322780Y-237434D01*
X322799Y-237456D01*
X322813Y-237471D01*
X322821Y-237478D01*
X322824Y-237482D01*
X322871Y-237547D01*
X322912Y-237624D01*
X322948Y-237704D01*
X322981Y-237787D01*
X323006Y-237875D01*
X323028Y-237962D01*
X323046Y-238053D01*
X323061Y-238137D01*
X323072Y-238221D01*
X323079Y-238297D01*
X323086Y-238366D01*
X323090Y-238424D01*
Y-238475D01*
X323094Y-238512D01*
Y-238526D01*
Y-238537D01*
Y-238541D01*
Y-238544D01*
X323090Y-238661D01*
X323083Y-238770D01*
X323072Y-238872D01*
X323054Y-238967D01*
X323035Y-239050D01*
X323017Y-239127D01*
X322995Y-239196D01*
X322970Y-239258D01*
X322948Y-239309D01*
X322926Y-239356D01*
X322908Y-239392D01*
X322886Y-239425D01*
X322871Y-239451D01*
X322861Y-239465D01*
X322853Y-239476D01*
X322850Y-239480D01*
X322802Y-239531D01*
X322751Y-239575D01*
X322700Y-239611D01*
X322650Y-239644D01*
X322595Y-239673D01*
X322544Y-239695D01*
X322493Y-239713D01*
X322442Y-239727D01*
X322398Y-239738D01*
X322355Y-239749D01*
X322318Y-239757D01*
X322286Y-239760D01*
X322256D01*
X322238Y-239764D01*
X322220D01*
X322136Y-239760D01*
X322060Y-239746D01*
X321991Y-239731D01*
X321929Y-239709D01*
X321881Y-239691D01*
X321845Y-239673D01*
X321831Y-239669D01*
X321820Y-239662D01*
X321816Y-239658D01*
X321812D01*
X321750Y-239615D01*
X321692Y-239564D01*
X321645Y-239513D01*
X321605Y-239462D01*
X321572Y-239414D01*
X321550Y-239378D01*
X321543Y-239363D01*
X321536Y-239352D01*
X321532Y-239349D01*
Y-239345D01*
X321496Y-239269D01*
X321470Y-239189D01*
X321452Y-239116D01*
X321441Y-239047D01*
X321430Y-238988D01*
Y-238967D01*
X321426Y-238945D01*
Y-238927D01*
Y-238916D01*
Y-238908D01*
Y-238905D01*
X321430Y-238839D01*
X321437Y-238777D01*
X321448Y-238716D01*
X321459Y-238661D01*
X321477Y-238610D01*
X321496Y-238559D01*
X321514Y-238515D01*
X321536Y-238475D01*
X321557Y-238439D01*
X321576Y-238406D01*
X321594Y-238381D01*
X321612Y-238355D01*
X321623Y-238337D01*
X321634Y-238326D01*
X321641Y-238319D01*
X321645Y-238315D01*
X321685Y-238275D01*
X321729Y-238239D01*
X321776Y-238210D01*
X321820Y-238184D01*
X321863Y-238159D01*
X321907Y-238140D01*
X321991Y-238115D01*
X322027Y-238104D01*
X322063Y-238097D01*
X322093Y-238093D01*
X322122Y-238089D01*
X322144Y-238086D01*
X322173D01*
X322238Y-238089D01*
X322300Y-238100D01*
X322358Y-238111D01*
X322409Y-238126D01*
X322453Y-238144D01*
X322486Y-238155D01*
X322508Y-238166D01*
X322511Y-238170D01*
X322515D01*
X322573Y-238206D01*
X322624Y-238246D01*
X322671Y-238286D01*
X322708Y-238330D01*
X322741Y-238366D01*
X322766Y-238395D01*
X322780Y-238417D01*
X322784Y-238421D01*
Y-238355D01*
X322780Y-238290D01*
X322777Y-238231D01*
X322770Y-238173D01*
X322766Y-238122D01*
X322759Y-238075D01*
X322751Y-238031D01*
X322741Y-237991D01*
X322733Y-237955D01*
X322726Y-237926D01*
X322719Y-237900D01*
X322715Y-237878D01*
X322708Y-237864D01*
X322704Y-237853D01*
X322700Y-237846D01*
Y-237842D01*
X322664Y-237769D01*
X322628Y-237704D01*
X322588Y-237653D01*
X322551Y-237609D01*
X322518Y-237573D01*
X322493Y-237547D01*
X322475Y-237532D01*
X322467Y-237529D01*
X322424Y-237500D01*
X322380Y-237482D01*
X322336Y-237467D01*
X322293Y-237456D01*
X322260Y-237449D01*
X322231Y-237445D01*
X322205D01*
X322140Y-237452D01*
X322078Y-237467D01*
X322027Y-237489D01*
X321980Y-237511D01*
X321943Y-237536D01*
X321918Y-237558D01*
X321903Y-237573D01*
X321896Y-237580D01*
X321870Y-237613D01*
X321845Y-237653D01*
X321823Y-237696D01*
X321809Y-237740D01*
X321794Y-237780D01*
X321783Y-237813D01*
X321779Y-237835D01*
X321776Y-237838D01*
Y-237842D01*
X321466Y-237816D01*
X321488Y-237715D01*
X321521Y-237624D01*
X321557Y-237543D01*
X321598Y-237478D01*
X321638Y-237427D01*
X321652Y-237405D01*
X321670Y-237387D01*
X321681Y-237376D01*
X321692Y-237365D01*
X321696Y-237361D01*
X321699Y-237358D01*
X321736Y-237329D01*
X321776Y-237303D01*
X321856Y-237260D01*
X321936Y-237230D01*
X322012Y-237212D01*
X322082Y-237198D01*
X322111Y-237194D01*
X322136D01*
X322158Y-237190D01*
X322187D01*
X322260Y-237194D01*
D02*
G37*
G36*
X320393D02*
X320451Y-237201D01*
X320509Y-237212D01*
X320560Y-237227D01*
X320658Y-237267D01*
X320702Y-237285D01*
X320739Y-237307D01*
X320775Y-237332D01*
X320804Y-237351D01*
X320833Y-237372D01*
X320855Y-237390D01*
X320873Y-237405D01*
X320884Y-237416D01*
X320891Y-237423D01*
X320895Y-237427D01*
X320935Y-237471D01*
X320968Y-237522D01*
X321001Y-237569D01*
X321026Y-237620D01*
X321048Y-237674D01*
X321066Y-237725D01*
X321092Y-237820D01*
X321102Y-237867D01*
X321110Y-237907D01*
X321113Y-237948D01*
X321117Y-237980D01*
X321121Y-238006D01*
Y-238024D01*
Y-238038D01*
Y-238042D01*
X321117Y-238111D01*
X321110Y-238173D01*
X321102Y-238235D01*
X321088Y-238293D01*
X321070Y-238344D01*
X321052Y-238395D01*
X321033Y-238439D01*
X321011Y-238479D01*
X320993Y-238515D01*
X320975Y-238548D01*
X320957Y-238574D01*
X320939Y-238599D01*
X320924Y-238617D01*
X320917Y-238628D01*
X320910Y-238635D01*
X320906Y-238639D01*
X320866Y-238679D01*
X320822Y-238712D01*
X320778Y-238745D01*
X320731Y-238770D01*
X320688Y-238792D01*
X320644Y-238810D01*
X320560Y-238836D01*
X320524Y-238846D01*
X320487Y-238854D01*
X320458Y-238858D01*
X320429Y-238861D01*
X320407Y-238865D01*
X320378D01*
X320309Y-238861D01*
X320243Y-238850D01*
X320185Y-238836D01*
X320131Y-238817D01*
X320091Y-238803D01*
X320058Y-238788D01*
X320036Y-238777D01*
X320029Y-238774D01*
X319970Y-238737D01*
X319919Y-238697D01*
X319876Y-238657D01*
X319839Y-238621D01*
X319814Y-238584D01*
X319792Y-238559D01*
X319777Y-238541D01*
X319774Y-238533D01*
Y-238563D01*
Y-238581D01*
Y-238592D01*
Y-238595D01*
X319777Y-238668D01*
X319781Y-238737D01*
X319788Y-238799D01*
X319796Y-238858D01*
X319807Y-238905D01*
X319814Y-238941D01*
X319818Y-238956D01*
Y-238967D01*
X319821Y-238970D01*
Y-238974D01*
X319839Y-239039D01*
X319858Y-239098D01*
X319876Y-239149D01*
X319894Y-239192D01*
X319909Y-239225D01*
X319923Y-239251D01*
X319930Y-239269D01*
X319934Y-239272D01*
X319963Y-239313D01*
X319992Y-239345D01*
X320021Y-239374D01*
X320051Y-239400D01*
X320072Y-239422D01*
X320094Y-239436D01*
X320109Y-239443D01*
X320112Y-239447D01*
X320152Y-239469D01*
X320196Y-239484D01*
X320236Y-239494D01*
X320276Y-239502D01*
X320309Y-239505D01*
X320334Y-239509D01*
X320360D01*
X320418Y-239505D01*
X320473Y-239494D01*
X320520Y-239480D01*
X320560Y-239462D01*
X320589Y-239447D01*
X320615Y-239433D01*
X320629Y-239422D01*
X320633Y-239418D01*
X320669Y-239378D01*
X320698Y-239331D01*
X320724Y-239280D01*
X320742Y-239229D01*
X320757Y-239185D01*
X320768Y-239145D01*
X320771Y-239130D01*
Y-239123D01*
X320775Y-239116D01*
Y-239112D01*
X321073Y-239138D01*
X321052Y-239243D01*
X321022Y-239334D01*
X320986Y-239414D01*
X320950Y-239480D01*
X320913Y-239531D01*
X320895Y-239553D01*
X320880Y-239571D01*
X320869Y-239582D01*
X320859Y-239593D01*
X320855Y-239596D01*
X320851Y-239600D01*
X320815Y-239629D01*
X320775Y-239655D01*
X320695Y-239695D01*
X320615Y-239724D01*
X320538Y-239742D01*
X320469Y-239757D01*
X320440Y-239760D01*
X320414D01*
X320396Y-239764D01*
X320367D01*
X320265Y-239757D01*
X320174Y-239742D01*
X320091Y-239717D01*
X320021Y-239687D01*
X319992Y-239676D01*
X319963Y-239662D01*
X319941Y-239647D01*
X319919Y-239636D01*
X319905Y-239629D01*
X319894Y-239622D01*
X319887Y-239615D01*
X319883D01*
X319810Y-239553D01*
X319745Y-239484D01*
X319694Y-239411D01*
X319650Y-239342D01*
X319614Y-239280D01*
X319599Y-239251D01*
X319588Y-239229D01*
X319581Y-239207D01*
X319574Y-239192D01*
X319570Y-239185D01*
Y-239181D01*
X319552Y-239127D01*
X319534Y-239065D01*
X319508Y-238941D01*
X319490Y-238810D01*
X319479Y-238686D01*
X319472Y-238632D01*
X319468Y-238577D01*
Y-238530D01*
X319464Y-238490D01*
Y-238457D01*
Y-238432D01*
Y-238413D01*
Y-238410D01*
Y-238326D01*
X319468Y-238246D01*
X319475Y-238173D01*
X319483Y-238104D01*
X319490Y-238042D01*
X319497Y-237984D01*
X319508Y-237929D01*
X319519Y-237882D01*
X319530Y-237842D01*
X319537Y-237806D01*
X319548Y-237773D01*
X319555Y-237747D01*
X319563Y-237729D01*
X319570Y-237715D01*
X319574Y-237707D01*
Y-237704D01*
X319617Y-237616D01*
X319665Y-237540D01*
X319719Y-237474D01*
X319767Y-237420D01*
X319814Y-237380D01*
X319850Y-237351D01*
X319865Y-237340D01*
X319876Y-237332D01*
X319879Y-237325D01*
X319883D01*
X319959Y-237281D01*
X320036Y-237249D01*
X320112Y-237223D01*
X320182Y-237209D01*
X320243Y-237198D01*
X320269Y-237194D01*
X320287D01*
X320305Y-237190D01*
X320331D01*
X320393Y-237194D01*
D02*
G37*
G36*
X324524Y-237165D02*
X324641Y-237183D01*
X324743Y-237205D01*
X324790Y-237220D01*
X324833Y-237234D01*
X324873Y-237249D01*
X324910Y-237263D01*
X324939Y-237274D01*
X324968Y-237285D01*
X324986Y-237296D01*
X325001Y-237303D01*
X325012Y-237307D01*
X325015Y-237311D01*
X325114Y-237372D01*
X325198Y-237445D01*
X325270Y-237518D01*
X325332Y-237591D01*
X325379Y-237656D01*
X325398Y-237685D01*
X325412Y-237711D01*
X325427Y-237729D01*
X325434Y-237744D01*
X325438Y-237755D01*
X325441Y-237758D01*
X325492Y-237871D01*
X325529Y-237987D01*
X325554Y-238104D01*
X325572Y-238210D01*
X325580Y-238257D01*
X325583Y-238304D01*
X325587Y-238341D01*
Y-238377D01*
X325591Y-238403D01*
Y-238424D01*
Y-238439D01*
Y-238442D01*
X325583Y-238574D01*
X325569Y-238701D01*
X325551Y-238814D01*
X325536Y-238868D01*
X325525Y-238916D01*
X325514Y-238959D01*
X325500Y-238999D01*
X325489Y-239036D01*
X325481Y-239065D01*
X325470Y-239087D01*
X325467Y-239105D01*
X325460Y-239116D01*
Y-239120D01*
X325405Y-239229D01*
X325343Y-239327D01*
X325278Y-239411D01*
X325245Y-239443D01*
X325216Y-239476D01*
X325187Y-239505D01*
X325157Y-239531D01*
X325132Y-239553D01*
X325110Y-239567D01*
X325096Y-239582D01*
X325081Y-239593D01*
X325074Y-239596D01*
X325070Y-239600D01*
X325019Y-239629D01*
X324968Y-239655D01*
X324859Y-239695D01*
X324750Y-239724D01*
X324644Y-239742D01*
X324593Y-239749D01*
X324550Y-239757D01*
X324510Y-239760D01*
X324477D01*
X324448Y-239764D01*
X324408D01*
X324335Y-239760D01*
X324266Y-239753D01*
X324200Y-239746D01*
X324138Y-239731D01*
X324080Y-239713D01*
X324025Y-239695D01*
X323974Y-239676D01*
X323927Y-239655D01*
X323887Y-239636D01*
X323847Y-239618D01*
X323818Y-239600D01*
X323789Y-239582D01*
X323771Y-239567D01*
X323752Y-239560D01*
X323745Y-239553D01*
X323742Y-239549D01*
X323691Y-239505D01*
X323647Y-239462D01*
X323607Y-239411D01*
X323567Y-239360D01*
X323501Y-239258D01*
X323450Y-239156D01*
X323428Y-239109D01*
X323410Y-239065D01*
X323396Y-239025D01*
X323385Y-238992D01*
X323374Y-238963D01*
X323367Y-238941D01*
X323363Y-238927D01*
Y-238923D01*
X323698Y-238839D01*
X323712Y-238897D01*
X323731Y-238952D01*
X323749Y-239003D01*
X323767Y-239050D01*
X323789Y-239094D01*
X323811Y-239130D01*
X323836Y-239167D01*
X323858Y-239200D01*
X323876Y-239229D01*
X323898Y-239251D01*
X323916Y-239272D01*
X323931Y-239291D01*
X323945Y-239301D01*
X323956Y-239313D01*
X323960Y-239316D01*
X323963Y-239320D01*
X324000Y-239349D01*
X324040Y-239371D01*
X324120Y-239411D01*
X324197Y-239440D01*
X324273Y-239458D01*
X324338Y-239473D01*
X324364Y-239476D01*
X324389D01*
X324411Y-239480D01*
X324437D01*
X324520Y-239476D01*
X324601Y-239462D01*
X324673Y-239443D01*
X324739Y-239422D01*
X324790Y-239400D01*
X324812Y-239389D01*
X324830Y-239382D01*
X324844Y-239374D01*
X324855Y-239367D01*
X324863Y-239363D01*
X324866D01*
X324935Y-239313D01*
X324994Y-239258D01*
X325045Y-239196D01*
X325085Y-239138D01*
X325117Y-239087D01*
X325139Y-239043D01*
X325147Y-239025D01*
X325154Y-239014D01*
X325157Y-239007D01*
Y-239003D01*
X325187Y-238908D01*
X325208Y-238814D01*
X325227Y-238719D01*
X325237Y-238632D01*
X325241Y-238592D01*
X325245Y-238555D01*
Y-238523D01*
X325248Y-238497D01*
Y-238475D01*
Y-238457D01*
Y-238446D01*
Y-238442D01*
X325245Y-238348D01*
X325237Y-238261D01*
X325223Y-238180D01*
X325208Y-238108D01*
X325198Y-238046D01*
X325190Y-238020D01*
X325183Y-237998D01*
X325179Y-237980D01*
X325176Y-237969D01*
X325172Y-237962D01*
Y-237958D01*
X325136Y-237875D01*
X325096Y-237798D01*
X325052Y-237736D01*
X325005Y-237682D01*
X324964Y-237638D01*
X324932Y-237609D01*
X324906Y-237591D01*
X324903Y-237583D01*
X324899D01*
X324823Y-237536D01*
X324739Y-237500D01*
X324659Y-237474D01*
X324582Y-237460D01*
X324513Y-237449D01*
X324484Y-237445D01*
X324459D01*
X324440Y-237441D01*
X324411D01*
X324320Y-237445D01*
X324236Y-237460D01*
X324167Y-237482D01*
X324106Y-237503D01*
X324058Y-237529D01*
X324022Y-237547D01*
X324000Y-237562D01*
X323993Y-237569D01*
X323934Y-237624D01*
X323880Y-237685D01*
X323836Y-237751D01*
X323800Y-237816D01*
X323771Y-237875D01*
X323760Y-237904D01*
X323752Y-237926D01*
X323745Y-237944D01*
X323738Y-237958D01*
X323734Y-237966D01*
Y-237969D01*
X323407Y-237893D01*
X323428Y-237827D01*
X323450Y-237769D01*
X323479Y-237715D01*
X323505Y-237660D01*
X323534Y-237613D01*
X323567Y-237569D01*
X323596Y-237525D01*
X323625Y-237489D01*
X323654Y-237460D01*
X323680Y-237431D01*
X323705Y-237405D01*
X323723Y-237387D01*
X323742Y-237369D01*
X323756Y-237358D01*
X323763Y-237354D01*
X323767Y-237351D01*
X323818Y-237318D01*
X323869Y-237285D01*
X323920Y-237260D01*
X323974Y-237238D01*
X324084Y-237205D01*
X324182Y-237183D01*
X324229Y-237172D01*
X324269Y-237169D01*
X324309Y-237165D01*
X324342Y-237161D01*
X324368Y-237158D01*
X324404D01*
X324524Y-237165D01*
D02*
G37*
G36*
X379208Y-232976D02*
X379278Y-232983D01*
X379343Y-232991D01*
X379405Y-233005D01*
X379463Y-233023D01*
X379518Y-233042D01*
X379569Y-233060D01*
X379616Y-233082D01*
X379656Y-233100D01*
X379696Y-233118D01*
X379725Y-233136D01*
X379754Y-233154D01*
X379773Y-233169D01*
X379791Y-233176D01*
X379798Y-233184D01*
X379802Y-233187D01*
X379853Y-233231D01*
X379896Y-233275D01*
X379937Y-233326D01*
X379977Y-233377D01*
X380042Y-233478D01*
X380093Y-233580D01*
X380115Y-233628D01*
X380133Y-233671D01*
X380148Y-233711D01*
X380158Y-233744D01*
X380169Y-233773D01*
X380177Y-233795D01*
X380180Y-233810D01*
Y-233813D01*
X379845Y-233897D01*
X379831Y-233839D01*
X379813Y-233784D01*
X379795Y-233733D01*
X379776Y-233686D01*
X379754Y-233642D01*
X379733Y-233606D01*
X379707Y-233569D01*
X379685Y-233537D01*
X379667Y-233507D01*
X379645Y-233486D01*
X379627Y-233464D01*
X379612Y-233446D01*
X379598Y-233435D01*
X379587Y-233424D01*
X379583Y-233420D01*
X379580Y-233417D01*
X379543Y-233387D01*
X379503Y-233366D01*
X379423Y-233326D01*
X379347Y-233296D01*
X379270Y-233278D01*
X379205Y-233264D01*
X379179Y-233260D01*
X379154D01*
X379132Y-233256D01*
X379107D01*
X379023Y-233260D01*
X378943Y-233275D01*
X378870Y-233293D01*
X378804Y-233315D01*
X378753Y-233336D01*
X378732Y-233347D01*
X378713Y-233355D01*
X378699Y-233362D01*
X378688Y-233369D01*
X378681Y-233373D01*
X378677D01*
X378608Y-233424D01*
X378550Y-233478D01*
X378499Y-233540D01*
X378459Y-233598D01*
X378426Y-233649D01*
X378404Y-233693D01*
X378397Y-233711D01*
X378390Y-233722D01*
X378386Y-233730D01*
Y-233733D01*
X378357Y-233828D01*
X378335Y-233922D01*
X378317Y-234017D01*
X378306Y-234104D01*
X378302Y-234144D01*
X378298Y-234181D01*
Y-234214D01*
X378295Y-234239D01*
Y-234261D01*
Y-234279D01*
Y-234290D01*
Y-234294D01*
X378298Y-234388D01*
X378306Y-234476D01*
X378320Y-234556D01*
X378335Y-234629D01*
X378346Y-234690D01*
X378353Y-234716D01*
X378360Y-234738D01*
X378364Y-234756D01*
X378368Y-234767D01*
X378371Y-234774D01*
Y-234778D01*
X378408Y-234862D01*
X378448Y-234938D01*
X378491Y-235000D01*
X378539Y-235054D01*
X378579Y-235098D01*
X378611Y-235127D01*
X378637Y-235145D01*
X378641Y-235153D01*
X378644D01*
X378721Y-235200D01*
X378804Y-235237D01*
X378885Y-235262D01*
X378961Y-235277D01*
X379030Y-235287D01*
X379059Y-235291D01*
X379085D01*
X379103Y-235295D01*
X379132D01*
X379223Y-235291D01*
X379307Y-235277D01*
X379376Y-235255D01*
X379438Y-235233D01*
X379485Y-235207D01*
X379521Y-235189D01*
X379543Y-235175D01*
X379551Y-235167D01*
X379609Y-235113D01*
X379663Y-235051D01*
X379707Y-234985D01*
X379744Y-234920D01*
X379773Y-234862D01*
X379784Y-234833D01*
X379791Y-234811D01*
X379798Y-234792D01*
X379805Y-234778D01*
X379809Y-234771D01*
Y-234767D01*
X380137Y-234843D01*
X380115Y-234909D01*
X380093Y-234967D01*
X380064Y-235022D01*
X380038Y-235076D01*
X380009Y-235124D01*
X379977Y-235167D01*
X379947Y-235211D01*
X379918Y-235247D01*
X379889Y-235277D01*
X379864Y-235306D01*
X379838Y-235331D01*
X379820Y-235349D01*
X379802Y-235367D01*
X379787Y-235379D01*
X379780Y-235382D01*
X379776Y-235386D01*
X379725Y-235419D01*
X379674Y-235451D01*
X379623Y-235477D01*
X379569Y-235499D01*
X379460Y-235531D01*
X379361Y-235553D01*
X379314Y-235564D01*
X379274Y-235568D01*
X379234Y-235571D01*
X379201Y-235575D01*
X379176Y-235579D01*
X379139D01*
X379019Y-235571D01*
X378903Y-235553D01*
X378801Y-235531D01*
X378753Y-235517D01*
X378710Y-235502D01*
X378670Y-235488D01*
X378633Y-235473D01*
X378604Y-235462D01*
X378575Y-235451D01*
X378557Y-235440D01*
X378542Y-235433D01*
X378531Y-235429D01*
X378528Y-235426D01*
X378430Y-235364D01*
X378346Y-235291D01*
X378273Y-235218D01*
X378211Y-235145D01*
X378164Y-235080D01*
X378146Y-235051D01*
X378131Y-235025D01*
X378116Y-235007D01*
X378109Y-234993D01*
X378106Y-234982D01*
X378102Y-234978D01*
X378051Y-234865D01*
X378015Y-234749D01*
X377989Y-234632D01*
X377971Y-234527D01*
X377964Y-234479D01*
X377960Y-234432D01*
X377956Y-234396D01*
Y-234359D01*
X377953Y-234334D01*
Y-234312D01*
Y-234297D01*
Y-234294D01*
X377960Y-234163D01*
X377975Y-234035D01*
X377993Y-233922D01*
X378007Y-233868D01*
X378018Y-233821D01*
X378029Y-233777D01*
X378044Y-233737D01*
X378055Y-233700D01*
X378062Y-233671D01*
X378073Y-233649D01*
X378076Y-233631D01*
X378084Y-233620D01*
Y-233617D01*
X378138Y-233507D01*
X378200Y-233409D01*
X378266Y-233326D01*
X378298Y-233293D01*
X378328Y-233260D01*
X378357Y-233231D01*
X378386Y-233205D01*
X378411Y-233184D01*
X378433Y-233169D01*
X378448Y-233154D01*
X378462Y-233143D01*
X378470Y-233140D01*
X378473Y-233136D01*
X378524Y-233107D01*
X378575Y-233082D01*
X378684Y-233042D01*
X378794Y-233012D01*
X378899Y-232994D01*
X378950Y-232987D01*
X378994Y-232980D01*
X379034Y-232976D01*
X379066D01*
X379096Y-232972D01*
X379136D01*
X379208Y-232976D01*
D02*
G37*
G36*
X381167Y-233154D02*
X381185Y-233282D01*
X381203Y-233398D01*
X381214Y-233453D01*
X381225Y-233504D01*
X381232Y-233547D01*
X381243Y-233588D01*
X381251Y-233624D01*
X381258Y-233653D01*
X381265Y-233675D01*
X381269Y-233693D01*
X381272Y-233704D01*
Y-233708D01*
X381327Y-233875D01*
X381385Y-234032D01*
X381414Y-234108D01*
X381443Y-234181D01*
X381476Y-234246D01*
X381505Y-234312D01*
X381531Y-234370D01*
X381556Y-234421D01*
X381578Y-234465D01*
X381596Y-234505D01*
X381614Y-234538D01*
X381625Y-234559D01*
X381633Y-234574D01*
X381636Y-234578D01*
X381680Y-234654D01*
X381724Y-234731D01*
X381767Y-234800D01*
X381811Y-234865D01*
X381851Y-234924D01*
X381891Y-234982D01*
X381931Y-235033D01*
X381964Y-235076D01*
X381997Y-235120D01*
X382026Y-235156D01*
X382055Y-235186D01*
X382077Y-235211D01*
X382091Y-235233D01*
X382106Y-235247D01*
X382113Y-235255D01*
X382117Y-235258D01*
Y-235502D01*
X380486D01*
Y-235204D01*
X381720D01*
X381633Y-235098D01*
X381549Y-234985D01*
X381476Y-234876D01*
X381407Y-234771D01*
X381378Y-234723D01*
X381352Y-234680D01*
X381327Y-234640D01*
X381309Y-234607D01*
X381294Y-234578D01*
X381283Y-234559D01*
X381276Y-234545D01*
X381272Y-234541D01*
X381200Y-234396D01*
X381134Y-234250D01*
X381079Y-234112D01*
X381058Y-234050D01*
X381036Y-233988D01*
X381014Y-233933D01*
X380999Y-233882D01*
X380985Y-233839D01*
X380974Y-233802D01*
X380963Y-233770D01*
X380956Y-233748D01*
X380952Y-233733D01*
Y-233730D01*
X380916Y-233580D01*
X380901Y-233507D01*
X380890Y-233442D01*
X380879Y-233380D01*
X380868Y-233318D01*
X380861Y-233267D01*
X380854Y-233216D01*
X380850Y-233173D01*
X380847Y-233133D01*
X380843Y-233096D01*
Y-233067D01*
X380839Y-233045D01*
Y-233031D01*
Y-233020D01*
Y-233016D01*
X381156D01*
X381167Y-233154D01*
D02*
G37*
G36*
X383344Y-232980D02*
X383435Y-232994D01*
X383511Y-233020D01*
X383576Y-233045D01*
X383631Y-233071D01*
X383649Y-233085D01*
X383667Y-233096D01*
X383682Y-233103D01*
X383693Y-233111D01*
X383697Y-233118D01*
X383700D01*
X383766Y-233180D01*
X383820Y-233245D01*
X383868Y-233318D01*
X383904Y-233384D01*
X383933Y-233446D01*
X383948Y-233471D01*
X383955Y-233497D01*
X383962Y-233515D01*
X383970Y-233529D01*
X383973Y-233537D01*
Y-233540D01*
X383991Y-233595D01*
X384006Y-233649D01*
X384028Y-233766D01*
X384046Y-233886D01*
X384057Y-234002D01*
X384061Y-234053D01*
X384064Y-234101D01*
Y-234144D01*
X384068Y-234185D01*
Y-234214D01*
Y-234239D01*
Y-234254D01*
Y-234257D01*
Y-234327D01*
X384064Y-234392D01*
Y-234450D01*
X384061Y-234508D01*
X384053Y-234559D01*
X384050Y-234610D01*
X384046Y-234654D01*
X384039Y-234694D01*
X384035Y-234731D01*
X384028Y-234763D01*
X384024Y-234789D01*
X384021Y-234811D01*
X384017Y-234829D01*
X384013Y-234840D01*
X384010Y-234847D01*
Y-234851D01*
X383988Y-234931D01*
X383962Y-235003D01*
X383933Y-235065D01*
X383911Y-235120D01*
X383886Y-235167D01*
X383871Y-235200D01*
X383857Y-235218D01*
X383853Y-235226D01*
X383813Y-235280D01*
X383773Y-235328D01*
X383729Y-235367D01*
X383689Y-235404D01*
X383653Y-235429D01*
X383624Y-235448D01*
X383606Y-235458D01*
X383602Y-235462D01*
X383598D01*
X383540Y-235491D01*
X383478Y-235509D01*
X383420Y-235524D01*
X383365Y-235535D01*
X383318Y-235542D01*
X383278Y-235546D01*
X383245D01*
X383147Y-235539D01*
X383056Y-235524D01*
X382979Y-235499D01*
X382914Y-235473D01*
X382859Y-235444D01*
X382838Y-235433D01*
X382819Y-235419D01*
X382805Y-235411D01*
X382794Y-235404D01*
X382790Y-235397D01*
X382787D01*
X382721Y-235338D01*
X382666Y-235269D01*
X382619Y-235200D01*
X382583Y-235135D01*
X382554Y-235073D01*
X382539Y-235047D01*
X382532Y-235022D01*
X382524Y-235003D01*
X382517Y-234989D01*
X382514Y-234982D01*
Y-234978D01*
X382499Y-234924D01*
X382485Y-234869D01*
X382463Y-234749D01*
X382444Y-234629D01*
X382434Y-234516D01*
X382430Y-234461D01*
X382426Y-234414D01*
Y-234370D01*
X382423Y-234330D01*
Y-234301D01*
Y-234276D01*
Y-234261D01*
Y-234257D01*
X382426Y-234130D01*
X382434Y-234010D01*
X382444Y-233901D01*
X382463Y-233799D01*
X382481Y-233704D01*
X382503Y-233620D01*
X382524Y-233544D01*
X382546Y-233478D01*
X382568Y-233420D01*
X382594Y-233369D01*
X382612Y-233326D01*
X382630Y-233293D01*
X382648Y-233264D01*
X382659Y-233245D01*
X382666Y-233235D01*
X382670Y-233231D01*
X382710Y-233187D01*
X382754Y-233147D01*
X382801Y-233111D01*
X382849Y-233082D01*
X382896Y-233056D01*
X382943Y-233034D01*
X382990Y-233020D01*
X383034Y-233005D01*
X383078Y-232994D01*
X383118Y-232987D01*
X383154Y-232980D01*
X383183Y-232976D01*
X383209Y-232972D01*
X383245D01*
X383344Y-232980D01*
D02*
G37*
G36*
X554521Y-329081D02*
X554229Y-329121D01*
X554204Y-329081D01*
X554171Y-329048D01*
X554142Y-329015D01*
X554113Y-328990D01*
X554084Y-328972D01*
X554062Y-328954D01*
X554047Y-328946D01*
X554044Y-328943D01*
X553996Y-328921D01*
X553949Y-328903D01*
X553905Y-328892D01*
X553862Y-328881D01*
X553825Y-328877D01*
X553796Y-328874D01*
X553727D01*
X553683Y-328881D01*
X553607Y-328899D01*
X553541Y-328924D01*
X553483Y-328950D01*
X553439Y-328979D01*
X553407Y-329005D01*
X553388Y-329023D01*
X553381Y-329027D01*
Y-329030D01*
X553330Y-329092D01*
X553294Y-329157D01*
X553268Y-329227D01*
X553250Y-329296D01*
X553239Y-329354D01*
X553235Y-329380D01*
Y-329401D01*
X553232Y-329420D01*
Y-329434D01*
Y-329441D01*
Y-329445D01*
Y-329496D01*
X553239Y-329543D01*
X553257Y-329634D01*
X553283Y-329711D01*
X553308Y-329773D01*
X553337Y-329824D01*
X553363Y-329864D01*
X553374Y-329875D01*
X553381Y-329886D01*
X553385Y-329889D01*
X553388Y-329893D01*
X553417Y-329922D01*
X553447Y-329947D01*
X553512Y-329991D01*
X553574Y-330020D01*
X553636Y-330038D01*
X553687Y-330053D01*
X553731Y-330057D01*
X553745Y-330060D01*
X553767D01*
X553836Y-330057D01*
X553898Y-330042D01*
X553953Y-330024D01*
X553996Y-330002D01*
X554036Y-329980D01*
X554066Y-329962D01*
X554080Y-329947D01*
X554087Y-329944D01*
X554131Y-329893D01*
X554167Y-329838D01*
X554197Y-329776D01*
X554218Y-329722D01*
X554233Y-329667D01*
X554244Y-329627D01*
X554248Y-329609D01*
X554251Y-329598D01*
Y-329591D01*
Y-329587D01*
X554575Y-329612D01*
X554568Y-329671D01*
X554557Y-329725D01*
X554524Y-329827D01*
X554484Y-329915D01*
X554462Y-329955D01*
X554440Y-329987D01*
X554422Y-330020D01*
X554400Y-330049D01*
X554382Y-330071D01*
X554364Y-330089D01*
X554349Y-330104D01*
X554342Y-330118D01*
X554335Y-330122D01*
X554331Y-330126D01*
X554287Y-330158D01*
X554244Y-330188D01*
X554197Y-330213D01*
X554149Y-330235D01*
X554058Y-330268D01*
X553967Y-330290D01*
X553927Y-330300D01*
X553887Y-330304D01*
X553854Y-330308D01*
X553825Y-330311D01*
X553800Y-330315D01*
X553767D01*
X553690Y-330311D01*
X553618Y-330300D01*
X553549Y-330286D01*
X553487Y-330268D01*
X553429Y-330242D01*
X553374Y-330217D01*
X553323Y-330191D01*
X553279Y-330162D01*
X553239Y-330133D01*
X553203Y-330107D01*
X553174Y-330078D01*
X553148Y-330057D01*
X553130Y-330038D01*
X553115Y-330024D01*
X553108Y-330013D01*
X553104Y-330009D01*
X553068Y-329962D01*
X553039Y-329911D01*
X553010Y-329864D01*
X552988Y-329813D01*
X552952Y-329714D01*
X552930Y-329620D01*
X552922Y-329580D01*
X552915Y-329540D01*
X552912Y-329507D01*
X552908Y-329478D01*
X552904Y-329452D01*
Y-329434D01*
Y-329423D01*
Y-329420D01*
X552908Y-329354D01*
X552915Y-329292D01*
X552926Y-329230D01*
X552941Y-329176D01*
X552959Y-329125D01*
X552977Y-329074D01*
X552999Y-329030D01*
X553017Y-328990D01*
X553039Y-328954D01*
X553061Y-328921D01*
X553079Y-328895D01*
X553097Y-328870D01*
X553112Y-328852D01*
X553123Y-328841D01*
X553130Y-328834D01*
X553134Y-328830D01*
X553177Y-328790D01*
X553221Y-328753D01*
X553268Y-328724D01*
X553316Y-328699D01*
X553363Y-328673D01*
X553410Y-328655D01*
X553498Y-328630D01*
X553538Y-328619D01*
X553574Y-328611D01*
X553607Y-328608D01*
X553636Y-328604D01*
X553658Y-328601D01*
X553738D01*
X553782Y-328608D01*
X553869Y-328626D01*
X553949Y-328651D01*
X554022Y-328681D01*
X554080Y-328710D01*
X554106Y-328724D01*
X554127Y-328735D01*
X554145Y-328746D01*
X554156Y-328753D01*
X554164Y-328757D01*
X554167Y-328761D01*
X554033Y-328080D01*
X553024D01*
Y-327785D01*
X554277D01*
X554521Y-329081D01*
D02*
G37*
G36*
X551798Y-327745D02*
X551867Y-327752D01*
X551932Y-327767D01*
X551994Y-327785D01*
X552049Y-327811D01*
X552104Y-327833D01*
X552151Y-327862D01*
X552194Y-327887D01*
X552231Y-327913D01*
X552267Y-327942D01*
X552296Y-327964D01*
X552318Y-327985D01*
X552337Y-328007D01*
X552351Y-328022D01*
X552358Y-328029D01*
X552362Y-328033D01*
X552409Y-328098D01*
X552449Y-328175D01*
X552486Y-328255D01*
X552519Y-328339D01*
X552544Y-328426D01*
X552566Y-328513D01*
X552584Y-328604D01*
X552598Y-328688D01*
X552609Y-328772D01*
X552617Y-328848D01*
X552624Y-328917D01*
X552628Y-328976D01*
Y-329027D01*
X552631Y-329063D01*
Y-329077D01*
Y-329088D01*
Y-329092D01*
Y-329096D01*
X552628Y-329212D01*
X552620Y-329321D01*
X552609Y-329423D01*
X552591Y-329518D01*
X552573Y-329602D01*
X552555Y-329678D01*
X552533Y-329747D01*
X552507Y-329809D01*
X552486Y-329860D01*
X552464Y-329907D01*
X552446Y-329944D01*
X552424Y-329977D01*
X552409Y-330002D01*
X552398Y-330016D01*
X552391Y-330027D01*
X552387Y-330031D01*
X552340Y-330082D01*
X552289Y-330126D01*
X552238Y-330162D01*
X552187Y-330195D01*
X552133Y-330224D01*
X552082Y-330246D01*
X552031Y-330264D01*
X551980Y-330279D01*
X551936Y-330290D01*
X551892Y-330300D01*
X551856Y-330308D01*
X551823Y-330311D01*
X551794D01*
X551776Y-330315D01*
X551758D01*
X551674Y-330311D01*
X551597Y-330297D01*
X551528Y-330282D01*
X551467Y-330260D01*
X551419Y-330242D01*
X551383Y-330224D01*
X551368Y-330220D01*
X551357Y-330213D01*
X551354Y-330209D01*
X551350D01*
X551288Y-330166D01*
X551230Y-330115D01*
X551183Y-330064D01*
X551143Y-330013D01*
X551110Y-329966D01*
X551088Y-329929D01*
X551081Y-329915D01*
X551073Y-329904D01*
X551070Y-329900D01*
Y-329896D01*
X551033Y-329820D01*
X551008Y-329740D01*
X550990Y-329667D01*
X550979Y-329598D01*
X550968Y-329540D01*
Y-329518D01*
X550964Y-329496D01*
Y-329478D01*
Y-329467D01*
Y-329460D01*
Y-329456D01*
X550968Y-329391D01*
X550975Y-329329D01*
X550986Y-329267D01*
X550997Y-329212D01*
X551015Y-329161D01*
X551033Y-329110D01*
X551052Y-329066D01*
X551073Y-329027D01*
X551095Y-328990D01*
X551113Y-328957D01*
X551132Y-328932D01*
X551150Y-328906D01*
X551161Y-328888D01*
X551172Y-328877D01*
X551179Y-328870D01*
X551183Y-328866D01*
X551223Y-328826D01*
X551266Y-328790D01*
X551314Y-328761D01*
X551357Y-328735D01*
X551401Y-328710D01*
X551445Y-328692D01*
X551528Y-328666D01*
X551565Y-328655D01*
X551601Y-328648D01*
X551630Y-328644D01*
X551659Y-328641D01*
X551681Y-328637D01*
X551710D01*
X551776Y-328641D01*
X551838Y-328651D01*
X551896Y-328662D01*
X551947Y-328677D01*
X551991Y-328695D01*
X552023Y-328706D01*
X552045Y-328717D01*
X552049Y-328721D01*
X552052D01*
X552111Y-328757D01*
X552162Y-328797D01*
X552209Y-328837D01*
X552246Y-328881D01*
X552278Y-328917D01*
X552304Y-328946D01*
X552318Y-328968D01*
X552322Y-328972D01*
Y-328906D01*
X552318Y-328841D01*
X552315Y-328783D01*
X552307Y-328724D01*
X552304Y-328673D01*
X552296Y-328626D01*
X552289Y-328582D01*
X552278Y-328542D01*
X552271Y-328506D01*
X552264Y-328477D01*
X552256Y-328451D01*
X552253Y-328430D01*
X552246Y-328415D01*
X552242Y-328404D01*
X552238Y-328397D01*
Y-328393D01*
X552202Y-328320D01*
X552165Y-328255D01*
X552125Y-328204D01*
X552089Y-328160D01*
X552056Y-328124D01*
X552031Y-328098D01*
X552012Y-328084D01*
X552005Y-328080D01*
X551962Y-328051D01*
X551918Y-328033D01*
X551874Y-328018D01*
X551830Y-328007D01*
X551798Y-328000D01*
X551769Y-327996D01*
X551743D01*
X551678Y-328004D01*
X551616Y-328018D01*
X551565Y-328040D01*
X551517Y-328062D01*
X551481Y-328087D01*
X551456Y-328109D01*
X551441Y-328124D01*
X551434Y-328131D01*
X551408Y-328164D01*
X551383Y-328204D01*
X551361Y-328247D01*
X551346Y-328291D01*
X551332Y-328331D01*
X551321Y-328364D01*
X551317Y-328386D01*
X551314Y-328389D01*
Y-328393D01*
X551004Y-328368D01*
X551026Y-328266D01*
X551059Y-328175D01*
X551095Y-328095D01*
X551135Y-328029D01*
X551175Y-327978D01*
X551190Y-327956D01*
X551208Y-327938D01*
X551219Y-327927D01*
X551230Y-327916D01*
X551233Y-327913D01*
X551237Y-327909D01*
X551274Y-327880D01*
X551314Y-327854D01*
X551394Y-327811D01*
X551474Y-327782D01*
X551550Y-327763D01*
X551619Y-327749D01*
X551649Y-327745D01*
X551674D01*
X551696Y-327742D01*
X551725D01*
X551798Y-327745D01*
D02*
G37*
G36*
X556020Y-327716D02*
X556137Y-327734D01*
X556239Y-327756D01*
X556286Y-327771D01*
X556329Y-327785D01*
X556370Y-327800D01*
X556406Y-327814D01*
X556435Y-327825D01*
X556464Y-327836D01*
X556482Y-327847D01*
X556497Y-327854D01*
X556508Y-327858D01*
X556511Y-327862D01*
X556610Y-327923D01*
X556694Y-327996D01*
X556766Y-328069D01*
X556828Y-328142D01*
X556876Y-328207D01*
X556894Y-328237D01*
X556908Y-328262D01*
X556923Y-328280D01*
X556930Y-328295D01*
X556934Y-328306D01*
X556937Y-328309D01*
X556988Y-328422D01*
X557025Y-328539D01*
X557050Y-328655D01*
X557068Y-328761D01*
X557076Y-328808D01*
X557079Y-328855D01*
X557083Y-328892D01*
Y-328928D01*
X557087Y-328954D01*
Y-328976D01*
Y-328990D01*
Y-328994D01*
X557079Y-329125D01*
X557065Y-329252D01*
X557047Y-329365D01*
X557032Y-329420D01*
X557021Y-329467D01*
X557010Y-329511D01*
X556996Y-329551D01*
X556985Y-329587D01*
X556978Y-329616D01*
X556966Y-329638D01*
X556963Y-329656D01*
X556956Y-329667D01*
Y-329671D01*
X556901Y-329780D01*
X556839Y-329878D01*
X556774Y-329962D01*
X556741Y-329995D01*
X556712Y-330027D01*
X556683Y-330057D01*
X556653Y-330082D01*
X556628Y-330104D01*
X556606Y-330118D01*
X556592Y-330133D01*
X556577Y-330144D01*
X556570Y-330148D01*
X556566Y-330151D01*
X556515Y-330180D01*
X556464Y-330206D01*
X556355Y-330246D01*
X556246Y-330275D01*
X556140Y-330293D01*
X556089Y-330300D01*
X556046Y-330308D01*
X556006Y-330311D01*
X555973D01*
X555944Y-330315D01*
X555904D01*
X555831Y-330311D01*
X555762Y-330304D01*
X555696Y-330297D01*
X555634Y-330282D01*
X555576Y-330264D01*
X555521Y-330246D01*
X555471Y-330228D01*
X555423Y-330206D01*
X555383Y-330188D01*
X555343Y-330169D01*
X555314Y-330151D01*
X555285Y-330133D01*
X555267Y-330118D01*
X555248Y-330111D01*
X555241Y-330104D01*
X555237Y-330100D01*
X555187Y-330057D01*
X555143Y-330013D01*
X555103Y-329962D01*
X555063Y-329911D01*
X554997Y-329809D01*
X554946Y-329707D01*
X554924Y-329660D01*
X554906Y-329616D01*
X554892Y-329576D01*
X554881Y-329543D01*
X554870Y-329514D01*
X554863Y-329492D01*
X554859Y-329478D01*
Y-329474D01*
X555194Y-329391D01*
X555208Y-329449D01*
X555227Y-329503D01*
X555245Y-329554D01*
X555263Y-329602D01*
X555285Y-329645D01*
X555307Y-329682D01*
X555332Y-329718D01*
X555354Y-329751D01*
X555372Y-329780D01*
X555394Y-329802D01*
X555412Y-329824D01*
X555427Y-329842D01*
X555441Y-329853D01*
X555452Y-329864D01*
X555456Y-329867D01*
X555460Y-329871D01*
X555496Y-329900D01*
X555536Y-329922D01*
X555616Y-329962D01*
X555692Y-329991D01*
X555769Y-330009D01*
X555834Y-330024D01*
X555860Y-330027D01*
X555886D01*
X555907Y-330031D01*
X555933D01*
X556016Y-330027D01*
X556097Y-330013D01*
X556169Y-329995D01*
X556235Y-329973D01*
X556286Y-329951D01*
X556308Y-329940D01*
X556326Y-329933D01*
X556341Y-329925D01*
X556351Y-329918D01*
X556359Y-329915D01*
X556362D01*
X556431Y-329864D01*
X556490Y-329809D01*
X556541Y-329747D01*
X556581Y-329689D01*
X556613Y-329638D01*
X556635Y-329594D01*
X556643Y-329576D01*
X556650Y-329565D01*
X556653Y-329558D01*
Y-329554D01*
X556683Y-329460D01*
X556705Y-329365D01*
X556723Y-329270D01*
X556734Y-329183D01*
X556737Y-329143D01*
X556741Y-329106D01*
Y-329074D01*
X556744Y-329048D01*
Y-329027D01*
Y-329008D01*
Y-328997D01*
Y-328994D01*
X556741Y-328899D01*
X556734Y-328812D01*
X556719Y-328732D01*
X556705Y-328659D01*
X556694Y-328597D01*
X556686Y-328572D01*
X556679Y-328550D01*
X556675Y-328531D01*
X556672Y-328520D01*
X556668Y-328513D01*
Y-328510D01*
X556632Y-328426D01*
X556592Y-328349D01*
X556548Y-328288D01*
X556501Y-328233D01*
X556461Y-328189D01*
X556428Y-328160D01*
X556402Y-328142D01*
X556399Y-328135D01*
X556395D01*
X556319Y-328087D01*
X556235Y-328051D01*
X556155Y-328026D01*
X556078Y-328011D01*
X556009Y-328000D01*
X555980Y-327996D01*
X555955D01*
X555936Y-327993D01*
X555907D01*
X555816Y-327996D01*
X555733Y-328011D01*
X555663Y-328033D01*
X555602Y-328055D01*
X555554Y-328080D01*
X555518Y-328098D01*
X555496Y-328113D01*
X555489Y-328120D01*
X555431Y-328175D01*
X555376Y-328237D01*
X555332Y-328302D01*
X555296Y-328368D01*
X555267Y-328426D01*
X555256Y-328455D01*
X555248Y-328477D01*
X555241Y-328495D01*
X555234Y-328510D01*
X555230Y-328517D01*
Y-328520D01*
X554903Y-328444D01*
X554924Y-328379D01*
X554946Y-328320D01*
X554976Y-328266D01*
X555001Y-328211D01*
X555030Y-328164D01*
X555063Y-328120D01*
X555092Y-328076D01*
X555121Y-328040D01*
X555150Y-328011D01*
X555176Y-327982D01*
X555201Y-327956D01*
X555219Y-327938D01*
X555237Y-327920D01*
X555252Y-327909D01*
X555259Y-327905D01*
X555263Y-327902D01*
X555314Y-327869D01*
X555365Y-327836D01*
X555416Y-327811D01*
X555471Y-327789D01*
X555580Y-327756D01*
X555678Y-327734D01*
X555725Y-327723D01*
X555765Y-327720D01*
X555805Y-327716D01*
X555838Y-327712D01*
X555864Y-327709D01*
X555900D01*
X556020Y-327716D01*
D02*
G37*
G36*
X534475Y-328841D02*
X534544Y-328848D01*
X534609Y-328855D01*
X534671Y-328870D01*
X534729Y-328888D01*
X534784Y-328906D01*
X534835Y-328925D01*
X534882Y-328946D01*
X534922Y-328965D01*
X534962Y-328983D01*
X534992Y-329001D01*
X535021Y-329019D01*
X535039Y-329034D01*
X535057Y-329041D01*
X535064Y-329048D01*
X535068Y-329052D01*
X535119Y-329096D01*
X535163Y-329139D01*
X535203Y-329190D01*
X535243Y-329241D01*
X535308Y-329343D01*
X535359Y-329445D01*
X535381Y-329492D01*
X535399Y-329536D01*
X535414Y-329576D01*
X535425Y-329609D01*
X535436Y-329638D01*
X535443Y-329660D01*
X535447Y-329674D01*
Y-329678D01*
X535112Y-329762D01*
X535097Y-329704D01*
X535079Y-329649D01*
X535061Y-329598D01*
X535042Y-329551D01*
X535021Y-329507D01*
X534999Y-329471D01*
X534973Y-329434D01*
X534951Y-329401D01*
X534933Y-329372D01*
X534911Y-329350D01*
X534893Y-329329D01*
X534879Y-329310D01*
X534864Y-329299D01*
X534853Y-329289D01*
X534850Y-329285D01*
X534846Y-329281D01*
X534809Y-329252D01*
X534769Y-329230D01*
X534689Y-329190D01*
X534613Y-329161D01*
X534537Y-329143D01*
X534471Y-329129D01*
X534445Y-329125D01*
X534420D01*
X534398Y-329121D01*
X534373D01*
X534289Y-329125D01*
X534209Y-329139D01*
X534136Y-329158D01*
X534071Y-329179D01*
X534020Y-329201D01*
X533998Y-329212D01*
X533980Y-329220D01*
X533965Y-329227D01*
X533954Y-329234D01*
X533947Y-329238D01*
X533943D01*
X533874Y-329289D01*
X533816Y-329343D01*
X533765Y-329405D01*
X533725Y-329463D01*
X533692Y-329514D01*
X533670Y-329558D01*
X533663Y-329576D01*
X533656Y-329587D01*
X533652Y-329594D01*
Y-329598D01*
X533623Y-329693D01*
X533601Y-329787D01*
X533583Y-329882D01*
X533572Y-329969D01*
X533568Y-330009D01*
X533565Y-330046D01*
Y-330079D01*
X533561Y-330104D01*
Y-330126D01*
Y-330144D01*
Y-330155D01*
Y-330159D01*
X533565Y-330253D01*
X533572Y-330341D01*
X533587Y-330421D01*
X533601Y-330493D01*
X533612Y-330555D01*
X533619Y-330581D01*
X533627Y-330603D01*
X533630Y-330621D01*
X533634Y-330632D01*
X533637Y-330639D01*
Y-330643D01*
X533674Y-330726D01*
X533714Y-330803D01*
X533758Y-330865D01*
X533805Y-330919D01*
X533845Y-330963D01*
X533878Y-330992D01*
X533903Y-331010D01*
X533907Y-331018D01*
X533911D01*
X533987Y-331065D01*
X534071Y-331101D01*
X534151Y-331127D01*
X534227Y-331141D01*
X534296Y-331152D01*
X534325Y-331156D01*
X534351D01*
X534369Y-331160D01*
X534398D01*
X534489Y-331156D01*
X534573Y-331141D01*
X534642Y-331119D01*
X534704Y-331098D01*
X534751Y-331072D01*
X534788Y-331054D01*
X534809Y-331039D01*
X534817Y-331032D01*
X534875Y-330978D01*
X534930Y-330916D01*
X534973Y-330850D01*
X535010Y-330785D01*
X535039Y-330726D01*
X535050Y-330697D01*
X535057Y-330676D01*
X535064Y-330657D01*
X535072Y-330643D01*
X535075Y-330635D01*
Y-330632D01*
X535403Y-330708D01*
X535381Y-330774D01*
X535359Y-330832D01*
X535330Y-330887D01*
X535305Y-330941D01*
X535276Y-330989D01*
X535243Y-331032D01*
X535214Y-331076D01*
X535184Y-331112D01*
X535155Y-331141D01*
X535130Y-331171D01*
X535104Y-331196D01*
X535086Y-331214D01*
X535068Y-331232D01*
X535053Y-331243D01*
X535046Y-331247D01*
X535042Y-331251D01*
X534992Y-331283D01*
X534941Y-331316D01*
X534890Y-331342D01*
X534835Y-331363D01*
X534726Y-331396D01*
X534627Y-331418D01*
X534580Y-331429D01*
X534540Y-331433D01*
X534500Y-331436D01*
X534467Y-331440D01*
X534442Y-331444D01*
X534406D01*
X534285Y-331436D01*
X534169Y-331418D01*
X534067Y-331396D01*
X534020Y-331382D01*
X533976Y-331367D01*
X533936Y-331352D01*
X533899Y-331338D01*
X533870Y-331327D01*
X533841Y-331316D01*
X533823Y-331305D01*
X533809Y-331298D01*
X533798Y-331294D01*
X533794Y-331291D01*
X533696Y-331229D01*
X533612Y-331156D01*
X533539Y-331083D01*
X533477Y-331010D01*
X533430Y-330945D01*
X533412Y-330916D01*
X533397Y-330890D01*
X533383Y-330872D01*
X533375Y-330857D01*
X533372Y-330847D01*
X533368Y-330843D01*
X533317Y-330730D01*
X533281Y-330614D01*
X533255Y-330497D01*
X533237Y-330392D01*
X533230Y-330344D01*
X533226Y-330297D01*
X533222Y-330260D01*
Y-330224D01*
X533219Y-330199D01*
Y-330177D01*
Y-330162D01*
Y-330159D01*
X533226Y-330028D01*
X533241Y-329900D01*
X533259Y-329787D01*
X533273Y-329733D01*
X533284Y-329685D01*
X533295Y-329642D01*
X533310Y-329602D01*
X533321Y-329565D01*
X533328Y-329536D01*
X533339Y-329514D01*
X533343Y-329496D01*
X533350Y-329485D01*
Y-329482D01*
X533404Y-329372D01*
X533466Y-329274D01*
X533532Y-329190D01*
X533565Y-329158D01*
X533594Y-329125D01*
X533623Y-329096D01*
X533652Y-329070D01*
X533677Y-329048D01*
X533699Y-329034D01*
X533714Y-329019D01*
X533728Y-329008D01*
X533736Y-329005D01*
X533739Y-329001D01*
X533790Y-328972D01*
X533841Y-328946D01*
X533951Y-328906D01*
X534060Y-328877D01*
X534165Y-328859D01*
X534216Y-328852D01*
X534260Y-328844D01*
X534300Y-328841D01*
X534333D01*
X534362Y-328837D01*
X534402D01*
X534475Y-328841D01*
D02*
G37*
G36*
X536600D02*
X536662Y-328848D01*
X536724Y-328859D01*
X536782Y-328874D01*
X536837Y-328892D01*
X536884Y-328910D01*
X536932Y-328932D01*
X536972Y-328954D01*
X537012Y-328972D01*
X537044Y-328994D01*
X537074Y-329012D01*
X537095Y-329030D01*
X537114Y-329045D01*
X537128Y-329056D01*
X537136Y-329063D01*
X537139Y-329067D01*
X537183Y-329110D01*
X537219Y-329158D01*
X537252Y-329205D01*
X537281Y-329252D01*
X537303Y-329296D01*
X537325Y-329343D01*
X537354Y-329431D01*
X537361Y-329471D01*
X537368Y-329507D01*
X537376Y-329540D01*
X537379Y-329569D01*
X537383Y-329591D01*
Y-329609D01*
Y-329620D01*
Y-329624D01*
X537379Y-329711D01*
X537365Y-329791D01*
X537343Y-329860D01*
X537321Y-329918D01*
X537299Y-329966D01*
X537278Y-330002D01*
X537263Y-330024D01*
X537259Y-330031D01*
X537208Y-330086D01*
X537154Y-330133D01*
X537095Y-330170D01*
X537037Y-330199D01*
X536986Y-330220D01*
X536946Y-330235D01*
X536932Y-330239D01*
X536921Y-330242D01*
X536913Y-330246D01*
X536910D01*
X536972Y-330279D01*
X537023Y-330311D01*
X537066Y-330348D01*
X537103Y-330381D01*
X537132Y-330410D01*
X537154Y-330435D01*
X537165Y-330450D01*
X537168Y-330457D01*
X537197Y-330508D01*
X537219Y-330559D01*
X537237Y-330610D01*
X537248Y-330657D01*
X537256Y-330697D01*
X537259Y-330726D01*
Y-330748D01*
Y-330755D01*
X537256Y-330817D01*
X537245Y-330879D01*
X537230Y-330934D01*
X537212Y-330981D01*
X537194Y-331021D01*
X537179Y-331054D01*
X537168Y-331072D01*
X537165Y-331080D01*
X537128Y-331134D01*
X537084Y-331181D01*
X537041Y-331222D01*
X536997Y-331258D01*
X536961Y-331283D01*
X536928Y-331305D01*
X536906Y-331316D01*
X536903Y-331320D01*
X536899D01*
X536833Y-331349D01*
X536768Y-331371D01*
X536702Y-331389D01*
X536644Y-331400D01*
X536597Y-331407D01*
X536557Y-331411D01*
X536466D01*
X536415Y-331403D01*
X536316Y-331385D01*
X536233Y-331356D01*
X536160Y-331327D01*
X536127Y-331309D01*
X536102Y-331294D01*
X536076Y-331280D01*
X536058Y-331265D01*
X536044Y-331254D01*
X536033Y-331247D01*
X536025Y-331243D01*
X536022Y-331240D01*
X535953Y-331171D01*
X535898Y-331094D01*
X535854Y-331014D01*
X535818Y-330934D01*
X535796Y-330865D01*
X535785Y-330836D01*
X535778Y-330810D01*
X535774Y-330788D01*
X535771Y-330774D01*
X535767Y-330763D01*
Y-330759D01*
X536076Y-330705D01*
X536091Y-330785D01*
X536113Y-330854D01*
X536138Y-330912D01*
X536164Y-330959D01*
X536189Y-330996D01*
X536211Y-331021D01*
X536226Y-331039D01*
X536229Y-331043D01*
X536276Y-331080D01*
X536327Y-331109D01*
X536375Y-331127D01*
X536422Y-331141D01*
X536466Y-331149D01*
X536498Y-331156D01*
X536528D01*
X536593Y-331152D01*
X536651Y-331138D01*
X536702Y-331119D01*
X536746Y-331101D01*
X536779Y-331080D01*
X536804Y-331061D01*
X536823Y-331047D01*
X536826Y-331043D01*
X536866Y-330999D01*
X536895Y-330952D01*
X536913Y-330905D01*
X536928Y-330861D01*
X536935Y-330821D01*
X536943Y-330792D01*
Y-330770D01*
Y-330766D01*
Y-330763D01*
Y-330723D01*
X536935Y-330686D01*
X536917Y-330625D01*
X536892Y-330570D01*
X536863Y-330523D01*
X536833Y-330490D01*
X536808Y-330464D01*
X536790Y-330450D01*
X536786Y-330446D01*
X536782D01*
X536721Y-330413D01*
X536662Y-330388D01*
X536600Y-330370D01*
X536546Y-330359D01*
X536498Y-330351D01*
X536458Y-330344D01*
X536411D01*
X536397Y-330348D01*
X536378D01*
X536342Y-330075D01*
X536389Y-330086D01*
X536433Y-330093D01*
X536469Y-330100D01*
X536502Y-330104D01*
X536528Y-330108D01*
X536560D01*
X536637Y-330100D01*
X536706Y-330086D01*
X536768Y-330064D01*
X536819Y-330038D01*
X536859Y-330013D01*
X536888Y-329991D01*
X536906Y-329977D01*
X536913Y-329969D01*
X536961Y-329915D01*
X536997Y-329856D01*
X537023Y-329798D01*
X537037Y-329740D01*
X537048Y-329693D01*
X537052Y-329653D01*
X537055Y-329638D01*
Y-329627D01*
Y-329620D01*
Y-329616D01*
X537048Y-329536D01*
X537030Y-329463D01*
X537008Y-329401D01*
X536979Y-329347D01*
X536950Y-329303D01*
X536928Y-329270D01*
X536910Y-329249D01*
X536903Y-329241D01*
X536844Y-329190D01*
X536782Y-329154D01*
X536721Y-329129D01*
X536662Y-329110D01*
X536611Y-329099D01*
X536571Y-329096D01*
X536557Y-329092D01*
X536535D01*
X536469Y-329096D01*
X536408Y-329110D01*
X536353Y-329129D01*
X536309Y-329150D01*
X536273Y-329169D01*
X536244Y-329187D01*
X536229Y-329201D01*
X536222Y-329205D01*
X536178Y-329256D01*
X536142Y-329314D01*
X536109Y-329376D01*
X536084Y-329441D01*
X536065Y-329496D01*
X536058Y-329522D01*
X536054Y-329543D01*
X536051Y-329562D01*
X536047Y-329576D01*
X536044Y-329583D01*
Y-329587D01*
X535734Y-329547D01*
X535741Y-329489D01*
X535752Y-329434D01*
X535785Y-329332D01*
X535825Y-329245D01*
X535847Y-329208D01*
X535869Y-329172D01*
X535891Y-329139D01*
X535912Y-329114D01*
X535931Y-329088D01*
X535949Y-329070D01*
X535960Y-329056D01*
X535971Y-329045D01*
X535978Y-329037D01*
X535982Y-329034D01*
X536025Y-329001D01*
X536069Y-328968D01*
X536113Y-328943D01*
X536160Y-328921D01*
X536251Y-328885D01*
X536338Y-328863D01*
X536378Y-328855D01*
X536415Y-328848D01*
X536447Y-328844D01*
X536477Y-328841D01*
X536498Y-328837D01*
X536531D01*
X536600Y-328841D01*
D02*
G37*
G36*
X538573D02*
X538646Y-328852D01*
X538715Y-328866D01*
X538777Y-328885D01*
X538835Y-328910D01*
X538890Y-328936D01*
X538941Y-328961D01*
X538985Y-328990D01*
X539025Y-329019D01*
X539061Y-329045D01*
X539090Y-329074D01*
X539116Y-329096D01*
X539134Y-329114D01*
X539148Y-329129D01*
X539156Y-329139D01*
X539159Y-329143D01*
X539196Y-329190D01*
X539225Y-329241D01*
X539254Y-329289D01*
X539276Y-329340D01*
X539312Y-329438D01*
X539334Y-329533D01*
X539341Y-329573D01*
X539349Y-329613D01*
X539352Y-329645D01*
X539356Y-329674D01*
X539360Y-329700D01*
Y-329718D01*
Y-329729D01*
Y-329733D01*
X539356Y-329798D01*
X539349Y-329860D01*
X539338Y-329922D01*
X539323Y-329977D01*
X539305Y-330028D01*
X539287Y-330079D01*
X539265Y-330122D01*
X539247Y-330162D01*
X539225Y-330199D01*
X539203Y-330231D01*
X539185Y-330257D01*
X539167Y-330282D01*
X539152Y-330300D01*
X539141Y-330311D01*
X539134Y-330319D01*
X539130Y-330322D01*
X539086Y-330362D01*
X539043Y-330399D01*
X538996Y-330428D01*
X538948Y-330453D01*
X538901Y-330479D01*
X538854Y-330497D01*
X538766Y-330523D01*
X538726Y-330534D01*
X538690Y-330541D01*
X538657Y-330544D01*
X538628Y-330548D01*
X538606Y-330552D01*
X538526D01*
X538482Y-330544D01*
X538395Y-330526D01*
X538315Y-330501D01*
X538242Y-330472D01*
X538184Y-330443D01*
X538158Y-330428D01*
X538136Y-330417D01*
X538118Y-330406D01*
X538107Y-330399D01*
X538100Y-330395D01*
X538097Y-330392D01*
X538231Y-331072D01*
X539239D01*
Y-331367D01*
X537987D01*
X537743Y-330071D01*
X538035Y-330031D01*
X538060Y-330071D01*
X538093Y-330104D01*
X538122Y-330137D01*
X538151Y-330162D01*
X538180Y-330180D01*
X538202Y-330199D01*
X538217Y-330206D01*
X538220Y-330209D01*
X538268Y-330231D01*
X538315Y-330250D01*
X538358Y-330260D01*
X538402Y-330271D01*
X538439Y-330275D01*
X538468Y-330279D01*
X538537D01*
X538581Y-330271D01*
X538657Y-330253D01*
X538723Y-330228D01*
X538781Y-330202D01*
X538824Y-330173D01*
X538857Y-330148D01*
X538875Y-330129D01*
X538883Y-330126D01*
Y-330122D01*
X538934Y-330060D01*
X538970Y-329995D01*
X538996Y-329926D01*
X539014Y-329856D01*
X539025Y-329798D01*
X539028Y-329773D01*
Y-329751D01*
X539032Y-329733D01*
Y-329718D01*
Y-329711D01*
Y-329707D01*
Y-329656D01*
X539025Y-329609D01*
X539007Y-329518D01*
X538981Y-329441D01*
X538955Y-329380D01*
X538926Y-329329D01*
X538901Y-329289D01*
X538890Y-329278D01*
X538883Y-329267D01*
X538879Y-329263D01*
X538875Y-329259D01*
X538846Y-329230D01*
X538817Y-329205D01*
X538752Y-329161D01*
X538690Y-329132D01*
X538628Y-329114D01*
X538577Y-329099D01*
X538533Y-329096D01*
X538519Y-329092D01*
X538497D01*
X538428Y-329096D01*
X538366Y-329110D01*
X538311Y-329129D01*
X538268Y-329150D01*
X538228Y-329172D01*
X538198Y-329190D01*
X538184Y-329205D01*
X538176Y-329208D01*
X538133Y-329259D01*
X538097Y-329314D01*
X538067Y-329376D01*
X538046Y-329431D01*
X538031Y-329485D01*
X538020Y-329525D01*
X538016Y-329543D01*
X538013Y-329554D01*
Y-329562D01*
Y-329565D01*
X537689Y-329540D01*
X537696Y-329482D01*
X537707Y-329427D01*
X537740Y-329325D01*
X537780Y-329238D01*
X537802Y-329198D01*
X537823Y-329165D01*
X537842Y-329132D01*
X537863Y-329103D01*
X537882Y-329081D01*
X537900Y-329063D01*
X537915Y-329048D01*
X537922Y-329034D01*
X537929Y-329030D01*
X537933Y-329027D01*
X537976Y-328994D01*
X538020Y-328965D01*
X538067Y-328939D01*
X538115Y-328917D01*
X538206Y-328885D01*
X538297Y-328863D01*
X538337Y-328852D01*
X538377Y-328848D01*
X538410Y-328844D01*
X538439Y-328841D01*
X538464Y-328837D01*
X538497D01*
X538573Y-328841D01*
D02*
G37*
G36*
X567397Y-309846D02*
X567467Y-309853D01*
X567532Y-309861D01*
X567594Y-309875D01*
X567652Y-309893D01*
X567707Y-309912D01*
X567758Y-309930D01*
X567805Y-309952D01*
X567845Y-309970D01*
X567885Y-309988D01*
X567914Y-310006D01*
X567943Y-310024D01*
X567962Y-310039D01*
X567980Y-310046D01*
X567987Y-310054D01*
X567991Y-310057D01*
X568042Y-310101D01*
X568085Y-310145D01*
X568125Y-310196D01*
X568165Y-310246D01*
X568231Y-310349D01*
X568282Y-310450D01*
X568304Y-310498D01*
X568322Y-310541D01*
X568337Y-310581D01*
X568348Y-310614D01*
X568358Y-310643D01*
X568366Y-310665D01*
X568369Y-310680D01*
Y-310683D01*
X568035Y-310767D01*
X568020Y-310709D01*
X568002Y-310654D01*
X567983Y-310603D01*
X567965Y-310556D01*
X567943Y-310512D01*
X567922Y-310476D01*
X567896Y-310439D01*
X567874Y-310407D01*
X567856Y-310378D01*
X567834Y-310356D01*
X567816Y-310334D01*
X567802Y-310316D01*
X567787Y-310305D01*
X567776Y-310294D01*
X567772Y-310290D01*
X567769Y-310287D01*
X567732Y-310258D01*
X567692Y-310236D01*
X567612Y-310196D01*
X567536Y-310166D01*
X567459Y-310148D01*
X567394Y-310134D01*
X567368Y-310130D01*
X567343D01*
X567321Y-310126D01*
X567296D01*
X567212Y-310130D01*
X567132Y-310145D01*
X567059Y-310163D01*
X566993Y-310185D01*
X566943Y-310207D01*
X566921Y-310217D01*
X566902Y-310225D01*
X566888Y-310232D01*
X566877Y-310239D01*
X566870Y-310243D01*
X566866D01*
X566797Y-310294D01*
X566739Y-310349D01*
X566688Y-310410D01*
X566648Y-310469D01*
X566615Y-310520D01*
X566593Y-310563D01*
X566586Y-310581D01*
X566578Y-310592D01*
X566575Y-310600D01*
Y-310603D01*
X566546Y-310698D01*
X566524Y-310792D01*
X566506Y-310887D01*
X566495Y-310975D01*
X566491Y-311015D01*
X566488Y-311051D01*
Y-311084D01*
X566484Y-311109D01*
Y-311131D01*
Y-311149D01*
Y-311160D01*
Y-311164D01*
X566488Y-311258D01*
X566495Y-311346D01*
X566509Y-311426D01*
X566524Y-311499D01*
X566535Y-311561D01*
X566542Y-311586D01*
X566549Y-311608D01*
X566553Y-311626D01*
X566557Y-311637D01*
X566560Y-311644D01*
Y-311648D01*
X566597Y-311732D01*
X566637Y-311808D01*
X566680Y-311870D01*
X566728Y-311925D01*
X566768Y-311968D01*
X566800Y-311997D01*
X566826Y-312016D01*
X566830Y-312023D01*
X566833D01*
X566910Y-312070D01*
X566993Y-312107D01*
X567073Y-312132D01*
X567150Y-312147D01*
X567219Y-312158D01*
X567248Y-312161D01*
X567274D01*
X567292Y-312165D01*
X567321D01*
X567412Y-312161D01*
X567496Y-312147D01*
X567565Y-312125D01*
X567627Y-312103D01*
X567674Y-312077D01*
X567710Y-312059D01*
X567732Y-312045D01*
X567740Y-312037D01*
X567798Y-311983D01*
X567852Y-311921D01*
X567896Y-311855D01*
X567933Y-311790D01*
X567962Y-311732D01*
X567973Y-311702D01*
X567980Y-311681D01*
X567987Y-311663D01*
X567994Y-311648D01*
X567998Y-311641D01*
Y-311637D01*
X568326Y-311714D01*
X568304Y-311779D01*
X568282Y-311837D01*
X568253Y-311892D01*
X568227Y-311946D01*
X568198Y-311994D01*
X568165Y-312037D01*
X568136Y-312081D01*
X568107Y-312118D01*
X568078Y-312147D01*
X568053Y-312176D01*
X568027Y-312201D01*
X568009Y-312219D01*
X567991Y-312238D01*
X567976Y-312248D01*
X567969Y-312252D01*
X567965Y-312256D01*
X567914Y-312289D01*
X567863Y-312321D01*
X567812Y-312347D01*
X567758Y-312369D01*
X567649Y-312401D01*
X567550Y-312423D01*
X567503Y-312434D01*
X567463Y-312438D01*
X567423Y-312441D01*
X567390Y-312445D01*
X567365Y-312449D01*
X567328D01*
X567208Y-312441D01*
X567092Y-312423D01*
X566990Y-312401D01*
X566943Y-312387D01*
X566899Y-312372D01*
X566859Y-312358D01*
X566822Y-312343D01*
X566793Y-312332D01*
X566764Y-312321D01*
X566746Y-312310D01*
X566731Y-312303D01*
X566720Y-312299D01*
X566717Y-312296D01*
X566618Y-312234D01*
X566535Y-312161D01*
X566462Y-312088D01*
X566400Y-312016D01*
X566353Y-311950D01*
X566335Y-311921D01*
X566320Y-311895D01*
X566305Y-311877D01*
X566298Y-311863D01*
X566294Y-311852D01*
X566291Y-311848D01*
X566240Y-311735D01*
X566203Y-311619D01*
X566178Y-311502D01*
X566160Y-311397D01*
X566153Y-311349D01*
X566149Y-311302D01*
X566145Y-311266D01*
Y-311229D01*
X566142Y-311204D01*
Y-311182D01*
Y-311168D01*
Y-311164D01*
X566149Y-311033D01*
X566163Y-310905D01*
X566182Y-310792D01*
X566196Y-310738D01*
X566207Y-310691D01*
X566218Y-310647D01*
X566233Y-310607D01*
X566244Y-310571D01*
X566251Y-310541D01*
X566262Y-310520D01*
X566265Y-310501D01*
X566273Y-310490D01*
Y-310487D01*
X566327Y-310378D01*
X566389Y-310279D01*
X566455Y-310196D01*
X566488Y-310163D01*
X566517Y-310130D01*
X566546Y-310101D01*
X566575Y-310075D01*
X566600Y-310054D01*
X566622Y-310039D01*
X566637Y-310024D01*
X566651Y-310014D01*
X566658Y-310010D01*
X566662Y-310006D01*
X566713Y-309977D01*
X566764Y-309952D01*
X566873Y-309912D01*
X566983Y-309882D01*
X567088Y-309864D01*
X567139Y-309857D01*
X567183Y-309850D01*
X567223Y-309846D01*
X567255D01*
X567285Y-309842D01*
X567325D01*
X567397Y-309846D01*
D02*
G37*
G36*
X571496D02*
X571569Y-309857D01*
X571638Y-309872D01*
X571700Y-309890D01*
X571758Y-309915D01*
X571813Y-309941D01*
X571864Y-309966D01*
X571907Y-309995D01*
X571947Y-310024D01*
X571984Y-310050D01*
X572013Y-310079D01*
X572039Y-310101D01*
X572057Y-310119D01*
X572071Y-310134D01*
X572079Y-310145D01*
X572082Y-310148D01*
X572119Y-310196D01*
X572148Y-310246D01*
X572177Y-310294D01*
X572199Y-310345D01*
X572235Y-310443D01*
X572257Y-310538D01*
X572264Y-310578D01*
X572271Y-310618D01*
X572275Y-310651D01*
X572279Y-310680D01*
X572282Y-310705D01*
Y-310723D01*
Y-310734D01*
Y-310738D01*
X572279Y-310804D01*
X572271Y-310865D01*
X572261Y-310927D01*
X572246Y-310982D01*
X572228Y-311033D01*
X572210Y-311084D01*
X572188Y-311127D01*
X572169Y-311168D01*
X572148Y-311204D01*
X572126Y-311237D01*
X572108Y-311262D01*
X572089Y-311288D01*
X572075Y-311306D01*
X572064Y-311317D01*
X572057Y-311324D01*
X572053Y-311328D01*
X572009Y-311368D01*
X571966Y-311404D01*
X571918Y-311433D01*
X571871Y-311459D01*
X571824Y-311484D01*
X571776Y-311502D01*
X571689Y-311528D01*
X571649Y-311539D01*
X571613Y-311546D01*
X571580Y-311550D01*
X571551Y-311553D01*
X571529Y-311557D01*
X571449D01*
X571405Y-311550D01*
X571318Y-311531D01*
X571238Y-311506D01*
X571165Y-311477D01*
X571107Y-311448D01*
X571081Y-311433D01*
X571059Y-311422D01*
X571041Y-311411D01*
X571030Y-311404D01*
X571023Y-311400D01*
X571019Y-311397D01*
X571154Y-312077D01*
X572162D01*
Y-312372D01*
X570910D01*
X570666Y-311076D01*
X570957Y-311036D01*
X570983Y-311076D01*
X571016Y-311109D01*
X571045Y-311142D01*
X571074Y-311168D01*
X571103Y-311186D01*
X571125Y-311204D01*
X571139Y-311211D01*
X571143Y-311215D01*
X571190Y-311237D01*
X571238Y-311255D01*
X571281Y-311266D01*
X571325Y-311277D01*
X571361Y-311280D01*
X571390Y-311284D01*
X571460D01*
X571503Y-311277D01*
X571580Y-311258D01*
X571645Y-311233D01*
X571704Y-311208D01*
X571747Y-311178D01*
X571780Y-311153D01*
X571798Y-311135D01*
X571805Y-311131D01*
Y-311127D01*
X571856Y-311066D01*
X571893Y-311000D01*
X571918Y-310931D01*
X571937Y-310862D01*
X571947Y-310804D01*
X571951Y-310778D01*
Y-310756D01*
X571955Y-310738D01*
Y-310723D01*
Y-310716D01*
Y-310712D01*
Y-310662D01*
X571947Y-310614D01*
X571929Y-310523D01*
X571904Y-310447D01*
X571878Y-310385D01*
X571849Y-310334D01*
X571824Y-310294D01*
X571813Y-310283D01*
X571805Y-310272D01*
X571802Y-310268D01*
X571798Y-310265D01*
X571769Y-310236D01*
X571740Y-310210D01*
X571674Y-310166D01*
X571613Y-310137D01*
X571551Y-310119D01*
X571500Y-310105D01*
X571456Y-310101D01*
X571442Y-310097D01*
X571420D01*
X571350Y-310101D01*
X571289Y-310116D01*
X571234Y-310134D01*
X571190Y-310156D01*
X571150Y-310177D01*
X571121Y-310196D01*
X571107Y-310210D01*
X571099Y-310214D01*
X571056Y-310265D01*
X571019Y-310319D01*
X570990Y-310381D01*
X570968Y-310436D01*
X570954Y-310490D01*
X570943Y-310530D01*
X570939Y-310549D01*
X570935Y-310560D01*
Y-310567D01*
Y-310571D01*
X570612Y-310545D01*
X570619Y-310487D01*
X570630Y-310432D01*
X570662Y-310330D01*
X570703Y-310243D01*
X570724Y-310203D01*
X570746Y-310170D01*
X570764Y-310137D01*
X570786Y-310108D01*
X570805Y-310086D01*
X570823Y-310068D01*
X570837Y-310054D01*
X570845Y-310039D01*
X570852Y-310035D01*
X570856Y-310032D01*
X570899Y-309999D01*
X570943Y-309970D01*
X570990Y-309944D01*
X571037Y-309923D01*
X571129Y-309890D01*
X571219Y-309868D01*
X571259Y-309857D01*
X571300Y-309853D01*
X571332Y-309850D01*
X571361Y-309846D01*
X571387Y-309842D01*
X571420D01*
X571496Y-309846D01*
D02*
G37*
G36*
X569538D02*
X569611Y-309857D01*
X569680Y-309872D01*
X569742Y-309890D01*
X569800Y-309915D01*
X569854Y-309941D01*
X569905Y-309966D01*
X569949Y-309995D01*
X569989Y-310024D01*
X570025Y-310050D01*
X570055Y-310079D01*
X570080Y-310101D01*
X570098Y-310119D01*
X570113Y-310134D01*
X570120Y-310145D01*
X570124Y-310148D01*
X570160Y-310196D01*
X570189Y-310246D01*
X570219Y-310294D01*
X570240Y-310345D01*
X570277Y-310443D01*
X570298Y-310538D01*
X570306Y-310578D01*
X570313Y-310618D01*
X570317Y-310651D01*
X570320Y-310680D01*
X570324Y-310705D01*
Y-310723D01*
Y-310734D01*
Y-310738D01*
X570320Y-310804D01*
X570313Y-310865D01*
X570302Y-310927D01*
X570288Y-310982D01*
X570269Y-311033D01*
X570251Y-311084D01*
X570229Y-311127D01*
X570211Y-311168D01*
X570189Y-311204D01*
X570167Y-311237D01*
X570149Y-311262D01*
X570131Y-311288D01*
X570117Y-311306D01*
X570106Y-311317D01*
X570098Y-311324D01*
X570095Y-311328D01*
X570051Y-311368D01*
X570007Y-311404D01*
X569960Y-311433D01*
X569913Y-311459D01*
X569865Y-311484D01*
X569818Y-311502D01*
X569731Y-311528D01*
X569691Y-311539D01*
X569654Y-311546D01*
X569622Y-311550D01*
X569592Y-311553D01*
X569570Y-311557D01*
X569490D01*
X569447Y-311550D01*
X569359Y-311531D01*
X569279Y-311506D01*
X569206Y-311477D01*
X569148Y-311448D01*
X569123Y-311433D01*
X569101Y-311422D01*
X569083Y-311411D01*
X569072Y-311404D01*
X569065Y-311400D01*
X569061Y-311397D01*
X569196Y-312077D01*
X570204D01*
Y-312372D01*
X568952D01*
X568708Y-311076D01*
X568999Y-311036D01*
X569025Y-311076D01*
X569057Y-311109D01*
X569086Y-311142D01*
X569115Y-311168D01*
X569145Y-311186D01*
X569167Y-311204D01*
X569181Y-311211D01*
X569185Y-311215D01*
X569232Y-311237D01*
X569279Y-311255D01*
X569323Y-311266D01*
X569367Y-311277D01*
X569403Y-311280D01*
X569432Y-311284D01*
X569501D01*
X569545Y-311277D01*
X569622Y-311258D01*
X569687Y-311233D01*
X569745Y-311208D01*
X569789Y-311178D01*
X569822Y-311153D01*
X569840Y-311135D01*
X569847Y-311131D01*
Y-311127D01*
X569898Y-311066D01*
X569935Y-311000D01*
X569960Y-310931D01*
X569978Y-310862D01*
X569989Y-310804D01*
X569993Y-310778D01*
Y-310756D01*
X569996Y-310738D01*
Y-310723D01*
Y-310716D01*
Y-310712D01*
Y-310662D01*
X569989Y-310614D01*
X569971Y-310523D01*
X569945Y-310447D01*
X569920Y-310385D01*
X569891Y-310334D01*
X569865Y-310294D01*
X569854Y-310283D01*
X569847Y-310272D01*
X569843Y-310268D01*
X569840Y-310265D01*
X569811Y-310236D01*
X569782Y-310210D01*
X569716Y-310166D01*
X569654Y-310137D01*
X569592Y-310119D01*
X569541Y-310105D01*
X569498Y-310101D01*
X569483Y-310097D01*
X569461D01*
X569392Y-310101D01*
X569330Y-310116D01*
X569276Y-310134D01*
X569232Y-310156D01*
X569192Y-310177D01*
X569163Y-310196D01*
X569148Y-310210D01*
X569141Y-310214D01*
X569097Y-310265D01*
X569061Y-310319D01*
X569032Y-310381D01*
X569010Y-310436D01*
X568995Y-310490D01*
X568985Y-310530D01*
X568981Y-310549D01*
X568977Y-310560D01*
Y-310567D01*
Y-310571D01*
X568653Y-310545D01*
X568660Y-310487D01*
X568672Y-310432D01*
X568704Y-310330D01*
X568744Y-310243D01*
X568766Y-310203D01*
X568788Y-310170D01*
X568806Y-310137D01*
X568828Y-310108D01*
X568846Y-310086D01*
X568864Y-310068D01*
X568879Y-310054D01*
X568886Y-310039D01*
X568893Y-310035D01*
X568897Y-310032D01*
X568941Y-309999D01*
X568985Y-309970D01*
X569032Y-309944D01*
X569079Y-309923D01*
X569170Y-309890D01*
X569261Y-309868D01*
X569301Y-309857D01*
X569341Y-309853D01*
X569374Y-309850D01*
X569403Y-309846D01*
X569429Y-309842D01*
X569461D01*
X569538Y-309846D01*
D02*
G37*
G36*
X534475Y-312276D02*
X534544Y-312283D01*
X534609Y-312291D01*
X534671Y-312305D01*
X534729Y-312323D01*
X534784Y-312342D01*
X534835Y-312360D01*
X534882Y-312382D01*
X534922Y-312400D01*
X534962Y-312418D01*
X534992Y-312436D01*
X535021Y-312454D01*
X535039Y-312469D01*
X535057Y-312476D01*
X535064Y-312484D01*
X535068Y-312487D01*
X535119Y-312531D01*
X535163Y-312575D01*
X535203Y-312626D01*
X535243Y-312677D01*
X535308Y-312778D01*
X535359Y-312880D01*
X535381Y-312928D01*
X535399Y-312971D01*
X535414Y-313011D01*
X535425Y-313044D01*
X535436Y-313073D01*
X535443Y-313095D01*
X535447Y-313110D01*
Y-313113D01*
X535112Y-313197D01*
X535097Y-313139D01*
X535079Y-313084D01*
X535061Y-313033D01*
X535042Y-312986D01*
X535021Y-312942D01*
X534999Y-312906D01*
X534973Y-312869D01*
X534951Y-312837D01*
X534933Y-312807D01*
X534911Y-312786D01*
X534893Y-312764D01*
X534879Y-312746D01*
X534864Y-312735D01*
X534853Y-312724D01*
X534850Y-312720D01*
X534846Y-312717D01*
X534809Y-312687D01*
X534769Y-312666D01*
X534689Y-312626D01*
X534613Y-312596D01*
X534537Y-312578D01*
X534471Y-312564D01*
X534445Y-312560D01*
X534420D01*
X534398Y-312556D01*
X534373D01*
X534289Y-312560D01*
X534209Y-312575D01*
X534136Y-312593D01*
X534071Y-312615D01*
X534020Y-312636D01*
X533998Y-312647D01*
X533980Y-312655D01*
X533965Y-312662D01*
X533954Y-312669D01*
X533947Y-312673D01*
X533943D01*
X533874Y-312724D01*
X533816Y-312778D01*
X533765Y-312840D01*
X533725Y-312898D01*
X533692Y-312949D01*
X533670Y-312993D01*
X533663Y-313011D01*
X533656Y-313022D01*
X533652Y-313030D01*
Y-313033D01*
X533623Y-313128D01*
X533601Y-313222D01*
X533583Y-313317D01*
X533572Y-313404D01*
X533568Y-313444D01*
X533565Y-313481D01*
Y-313514D01*
X533561Y-313539D01*
Y-313561D01*
Y-313579D01*
Y-313590D01*
Y-313594D01*
X533565Y-313688D01*
X533572Y-313776D01*
X533587Y-313856D01*
X533601Y-313929D01*
X533612Y-313990D01*
X533619Y-314016D01*
X533627Y-314038D01*
X533630Y-314056D01*
X533634Y-314067D01*
X533637Y-314074D01*
Y-314078D01*
X533674Y-314162D01*
X533714Y-314238D01*
X533758Y-314300D01*
X533805Y-314354D01*
X533845Y-314398D01*
X533878Y-314427D01*
X533903Y-314445D01*
X533907Y-314453D01*
X533911D01*
X533987Y-314500D01*
X534071Y-314536D01*
X534151Y-314562D01*
X534227Y-314577D01*
X534296Y-314587D01*
X534325Y-314591D01*
X534351D01*
X534369Y-314595D01*
X534398D01*
X534489Y-314591D01*
X534573Y-314577D01*
X534642Y-314555D01*
X534704Y-314533D01*
X534751Y-314507D01*
X534788Y-314489D01*
X534809Y-314475D01*
X534817Y-314467D01*
X534875Y-314413D01*
X534930Y-314351D01*
X534973Y-314285D01*
X535010Y-314220D01*
X535039Y-314162D01*
X535050Y-314132D01*
X535057Y-314111D01*
X535064Y-314092D01*
X535072Y-314078D01*
X535075Y-314071D01*
Y-314067D01*
X535403Y-314143D01*
X535381Y-314209D01*
X535359Y-314267D01*
X535330Y-314322D01*
X535305Y-314376D01*
X535276Y-314424D01*
X535243Y-314467D01*
X535214Y-314511D01*
X535184Y-314547D01*
X535155Y-314577D01*
X535130Y-314606D01*
X535104Y-314631D01*
X535086Y-314649D01*
X535068Y-314668D01*
X535053Y-314679D01*
X535046Y-314682D01*
X535042Y-314686D01*
X534992Y-314719D01*
X534941Y-314751D01*
X534890Y-314777D01*
X534835Y-314799D01*
X534726Y-314831D01*
X534627Y-314853D01*
X534580Y-314864D01*
X534540Y-314868D01*
X534500Y-314871D01*
X534467Y-314875D01*
X534442Y-314879D01*
X534406D01*
X534285Y-314871D01*
X534169Y-314853D01*
X534067Y-314831D01*
X534020Y-314817D01*
X533976Y-314802D01*
X533936Y-314788D01*
X533899Y-314773D01*
X533870Y-314762D01*
X533841Y-314751D01*
X533823Y-314740D01*
X533809Y-314733D01*
X533798Y-314729D01*
X533794Y-314726D01*
X533696Y-314664D01*
X533612Y-314591D01*
X533539Y-314518D01*
X533477Y-314445D01*
X533430Y-314380D01*
X533412Y-314351D01*
X533397Y-314325D01*
X533383Y-314307D01*
X533375Y-314293D01*
X533372Y-314282D01*
X533368Y-314278D01*
X533317Y-314165D01*
X533281Y-314049D01*
X533255Y-313932D01*
X533237Y-313827D01*
X533230Y-313779D01*
X533226Y-313732D01*
X533222Y-313696D01*
Y-313659D01*
X533219Y-313634D01*
Y-313612D01*
Y-313597D01*
Y-313594D01*
X533226Y-313463D01*
X533241Y-313335D01*
X533259Y-313222D01*
X533273Y-313168D01*
X533284Y-313121D01*
X533295Y-313077D01*
X533310Y-313037D01*
X533321Y-313000D01*
X533328Y-312971D01*
X533339Y-312949D01*
X533343Y-312931D01*
X533350Y-312920D01*
Y-312917D01*
X533404Y-312807D01*
X533466Y-312709D01*
X533532Y-312626D01*
X533565Y-312593D01*
X533594Y-312560D01*
X533623Y-312531D01*
X533652Y-312505D01*
X533677Y-312484D01*
X533699Y-312469D01*
X533714Y-312454D01*
X533728Y-312443D01*
X533736Y-312440D01*
X533739Y-312436D01*
X533790Y-312407D01*
X533841Y-312382D01*
X533951Y-312342D01*
X534060Y-312312D01*
X534165Y-312294D01*
X534216Y-312287D01*
X534260Y-312280D01*
X534300Y-312276D01*
X534333D01*
X534362Y-312272D01*
X534402D01*
X534475Y-312276D01*
D02*
G37*
G36*
X536600D02*
X536662Y-312283D01*
X536724Y-312294D01*
X536782Y-312309D01*
X536837Y-312327D01*
X536884Y-312345D01*
X536932Y-312367D01*
X536972Y-312389D01*
X537012Y-312407D01*
X537044Y-312429D01*
X537074Y-312447D01*
X537095Y-312465D01*
X537114Y-312480D01*
X537128Y-312491D01*
X537136Y-312498D01*
X537139Y-312502D01*
X537183Y-312545D01*
X537219Y-312593D01*
X537252Y-312640D01*
X537281Y-312687D01*
X537303Y-312731D01*
X537325Y-312778D01*
X537354Y-312866D01*
X537361Y-312906D01*
X537368Y-312942D01*
X537376Y-312975D01*
X537379Y-313004D01*
X537383Y-313026D01*
Y-313044D01*
Y-313055D01*
Y-313059D01*
X537379Y-313146D01*
X537365Y-313226D01*
X537343Y-313295D01*
X537321Y-313353D01*
X537299Y-313401D01*
X537278Y-313437D01*
X537263Y-313459D01*
X537259Y-313466D01*
X537208Y-313521D01*
X537154Y-313568D01*
X537095Y-313605D01*
X537037Y-313634D01*
X536986Y-313656D01*
X536946Y-313670D01*
X536932Y-313674D01*
X536921Y-313677D01*
X536913Y-313681D01*
X536910D01*
X536972Y-313714D01*
X537023Y-313747D01*
X537066Y-313783D01*
X537103Y-313816D01*
X537132Y-313845D01*
X537154Y-313870D01*
X537165Y-313885D01*
X537168Y-313892D01*
X537197Y-313943D01*
X537219Y-313994D01*
X537237Y-314045D01*
X537248Y-314092D01*
X537256Y-314132D01*
X537259Y-314162D01*
Y-314183D01*
Y-314191D01*
X537256Y-314253D01*
X537245Y-314314D01*
X537230Y-314369D01*
X537212Y-314416D01*
X537194Y-314456D01*
X537179Y-314489D01*
X537168Y-314507D01*
X537165Y-314515D01*
X537128Y-314569D01*
X537084Y-314617D01*
X537041Y-314657D01*
X536997Y-314693D01*
X536961Y-314719D01*
X536928Y-314740D01*
X536906Y-314751D01*
X536903Y-314755D01*
X536899D01*
X536833Y-314784D01*
X536768Y-314806D01*
X536702Y-314824D01*
X536644Y-314835D01*
X536597Y-314842D01*
X536557Y-314846D01*
X536466D01*
X536415Y-314839D01*
X536316Y-314820D01*
X536233Y-314791D01*
X536160Y-314762D01*
X536127Y-314744D01*
X536102Y-314729D01*
X536076Y-314715D01*
X536058Y-314700D01*
X536044Y-314689D01*
X536033Y-314682D01*
X536025Y-314679D01*
X536022Y-314675D01*
X535953Y-314606D01*
X535898Y-314529D01*
X535854Y-314449D01*
X535818Y-314369D01*
X535796Y-314300D01*
X535785Y-314271D01*
X535778Y-314245D01*
X535774Y-314224D01*
X535771Y-314209D01*
X535767Y-314198D01*
Y-314194D01*
X536076Y-314140D01*
X536091Y-314220D01*
X536113Y-314289D01*
X536138Y-314347D01*
X536164Y-314394D01*
X536189Y-314431D01*
X536211Y-314456D01*
X536226Y-314475D01*
X536229Y-314478D01*
X536276Y-314515D01*
X536327Y-314544D01*
X536375Y-314562D01*
X536422Y-314577D01*
X536466Y-314584D01*
X536498Y-314591D01*
X536528D01*
X536593Y-314587D01*
X536651Y-314573D01*
X536702Y-314555D01*
X536746Y-314536D01*
X536779Y-314515D01*
X536804Y-314496D01*
X536823Y-314482D01*
X536826Y-314478D01*
X536866Y-314435D01*
X536895Y-314387D01*
X536913Y-314340D01*
X536928Y-314296D01*
X536935Y-314256D01*
X536943Y-314227D01*
Y-314205D01*
Y-314202D01*
Y-314198D01*
Y-314158D01*
X536935Y-314122D01*
X536917Y-314060D01*
X536892Y-314005D01*
X536863Y-313958D01*
X536833Y-313925D01*
X536808Y-313899D01*
X536790Y-313885D01*
X536786Y-313881D01*
X536782D01*
X536721Y-313848D01*
X536662Y-313823D01*
X536600Y-313805D01*
X536546Y-313794D01*
X536498Y-313787D01*
X536458Y-313779D01*
X536411D01*
X536397Y-313783D01*
X536378D01*
X536342Y-313510D01*
X536389Y-313521D01*
X536433Y-313528D01*
X536469Y-313535D01*
X536502Y-313539D01*
X536528Y-313543D01*
X536560D01*
X536637Y-313535D01*
X536706Y-313521D01*
X536768Y-313499D01*
X536819Y-313474D01*
X536859Y-313448D01*
X536888Y-313426D01*
X536906Y-313412D01*
X536913Y-313404D01*
X536961Y-313350D01*
X536997Y-313292D01*
X537023Y-313233D01*
X537037Y-313175D01*
X537048Y-313128D01*
X537052Y-313088D01*
X537055Y-313073D01*
Y-313062D01*
Y-313055D01*
Y-313051D01*
X537048Y-312971D01*
X537030Y-312898D01*
X537008Y-312837D01*
X536979Y-312782D01*
X536950Y-312738D01*
X536928Y-312706D01*
X536910Y-312684D01*
X536903Y-312677D01*
X536844Y-312626D01*
X536782Y-312589D01*
X536721Y-312564D01*
X536662Y-312545D01*
X536611Y-312534D01*
X536571Y-312531D01*
X536557Y-312527D01*
X536535D01*
X536469Y-312531D01*
X536408Y-312545D01*
X536353Y-312564D01*
X536309Y-312585D01*
X536273Y-312604D01*
X536244Y-312622D01*
X536229Y-312636D01*
X536222Y-312640D01*
X536178Y-312691D01*
X536142Y-312749D01*
X536109Y-312811D01*
X536084Y-312877D01*
X536065Y-312931D01*
X536058Y-312957D01*
X536054Y-312979D01*
X536051Y-312997D01*
X536047Y-313011D01*
X536044Y-313019D01*
Y-313022D01*
X535734Y-312982D01*
X535741Y-312924D01*
X535752Y-312869D01*
X535785Y-312768D01*
X535825Y-312680D01*
X535847Y-312644D01*
X535869Y-312607D01*
X535891Y-312575D01*
X535912Y-312549D01*
X535931Y-312524D01*
X535949Y-312505D01*
X535960Y-312491D01*
X535971Y-312480D01*
X535978Y-312473D01*
X535982Y-312469D01*
X536025Y-312436D01*
X536069Y-312403D01*
X536113Y-312378D01*
X536160Y-312356D01*
X536251Y-312320D01*
X536338Y-312298D01*
X536378Y-312291D01*
X536415Y-312283D01*
X536447Y-312280D01*
X536477Y-312276D01*
X536498Y-312272D01*
X536531D01*
X536600Y-312276D01*
D02*
G37*
G36*
X538988Y-312920D02*
X539330D01*
Y-313204D01*
X538988D01*
Y-314835D01*
X538737D01*
X537583Y-313204D01*
Y-312920D01*
X538679D01*
Y-312316D01*
X538988D01*
Y-312920D01*
D02*
G37*
G36*
X118717Y-33651D02*
X118786Y-33658D01*
X118851Y-33672D01*
X118913Y-33691D01*
X118968Y-33716D01*
X119022Y-33738D01*
X119070Y-33767D01*
X119113Y-33793D01*
X119150Y-33818D01*
X119186Y-33847D01*
X119215Y-33869D01*
X119237Y-33891D01*
X119255Y-33913D01*
X119270Y-33927D01*
X119277Y-33935D01*
X119281Y-33938D01*
X119328Y-34004D01*
X119368Y-34080D01*
X119405Y-34160D01*
X119437Y-34244D01*
X119463Y-34331D01*
X119485Y-34419D01*
X119503Y-34510D01*
X119518Y-34593D01*
X119528Y-34677D01*
X119536Y-34754D01*
X119543Y-34823D01*
X119547Y-34881D01*
Y-34932D01*
X119550Y-34968D01*
Y-34983D01*
Y-34994D01*
Y-34997D01*
Y-35001D01*
X119547Y-35118D01*
X119539Y-35227D01*
X119528Y-35329D01*
X119510Y-35423D01*
X119492Y-35507D01*
X119474Y-35583D01*
X119452Y-35653D01*
X119427Y-35715D01*
X119405Y-35765D01*
X119383Y-35813D01*
X119365Y-35849D01*
X119343Y-35882D01*
X119328Y-35908D01*
X119317Y-35922D01*
X119310Y-35933D01*
X119306Y-35937D01*
X119259Y-35987D01*
X119208Y-36031D01*
X119157Y-36068D01*
X119106Y-36100D01*
X119052Y-36130D01*
X119001Y-36151D01*
X118950Y-36169D01*
X118899Y-36184D01*
X118855Y-36195D01*
X118811Y-36206D01*
X118775Y-36213D01*
X118742Y-36217D01*
X118713D01*
X118695Y-36220D01*
X118677D01*
X118593Y-36217D01*
X118517Y-36202D01*
X118447Y-36188D01*
X118385Y-36166D01*
X118338Y-36148D01*
X118302Y-36130D01*
X118287Y-36126D01*
X118276Y-36119D01*
X118273Y-36115D01*
X118269D01*
X118207Y-36071D01*
X118149Y-36020D01*
X118102Y-35969D01*
X118061Y-35918D01*
X118029Y-35871D01*
X118007Y-35835D01*
X118000Y-35820D01*
X117992Y-35809D01*
X117989Y-35805D01*
Y-35802D01*
X117952Y-35726D01*
X117927Y-35645D01*
X117909Y-35573D01*
X117898Y-35503D01*
X117887Y-35445D01*
Y-35423D01*
X117883Y-35401D01*
Y-35383D01*
Y-35372D01*
Y-35365D01*
Y-35361D01*
X117887Y-35296D01*
X117894Y-35234D01*
X117905Y-35172D01*
X117916Y-35118D01*
X117934Y-35067D01*
X117952Y-35016D01*
X117971Y-34972D01*
X117992Y-34932D01*
X118014Y-34896D01*
X118032Y-34863D01*
X118051Y-34837D01*
X118069Y-34812D01*
X118080Y-34794D01*
X118091Y-34783D01*
X118098Y-34775D01*
X118102Y-34772D01*
X118142Y-34732D01*
X118185Y-34695D01*
X118233Y-34666D01*
X118276Y-34641D01*
X118320Y-34615D01*
X118364Y-34597D01*
X118447Y-34572D01*
X118484Y-34561D01*
X118520Y-34553D01*
X118549Y-34550D01*
X118578Y-34546D01*
X118600Y-34543D01*
X118629D01*
X118695Y-34546D01*
X118757Y-34557D01*
X118815Y-34568D01*
X118866Y-34582D01*
X118910Y-34601D01*
X118942Y-34612D01*
X118964Y-34623D01*
X118968Y-34626D01*
X118972D01*
X119030Y-34663D01*
X119081Y-34703D01*
X119128Y-34743D01*
X119164Y-34786D01*
X119197Y-34823D01*
X119223Y-34852D01*
X119237Y-34874D01*
X119241Y-34877D01*
Y-34812D01*
X119237Y-34746D01*
X119234Y-34688D01*
X119226Y-34630D01*
X119223Y-34579D01*
X119215Y-34532D01*
X119208Y-34488D01*
X119197Y-34448D01*
X119190Y-34411D01*
X119183Y-34382D01*
X119175Y-34357D01*
X119172Y-34335D01*
X119164Y-34320D01*
X119161Y-34310D01*
X119157Y-34302D01*
Y-34299D01*
X119121Y-34226D01*
X119084Y-34160D01*
X119044Y-34109D01*
X119008Y-34066D01*
X118975Y-34029D01*
X118950Y-34004D01*
X118931Y-33989D01*
X118924Y-33986D01*
X118880Y-33956D01*
X118837Y-33938D01*
X118793Y-33924D01*
X118749Y-33913D01*
X118717Y-33906D01*
X118688Y-33902D01*
X118662D01*
X118597Y-33909D01*
X118535Y-33924D01*
X118484Y-33946D01*
X118436Y-33967D01*
X118400Y-33993D01*
X118375Y-34015D01*
X118360Y-34029D01*
X118353Y-34036D01*
X118327Y-34069D01*
X118302Y-34109D01*
X118280Y-34153D01*
X118265Y-34197D01*
X118251Y-34237D01*
X118240Y-34269D01*
X118236Y-34291D01*
X118233Y-34295D01*
Y-34299D01*
X117923Y-34273D01*
X117945Y-34171D01*
X117978Y-34080D01*
X118014Y-34000D01*
X118054Y-33935D01*
X118094Y-33884D01*
X118109Y-33862D01*
X118127Y-33844D01*
X118138Y-33833D01*
X118149Y-33822D01*
X118152Y-33818D01*
X118156Y-33814D01*
X118193Y-33785D01*
X118233Y-33760D01*
X118313Y-33716D01*
X118393Y-33687D01*
X118469Y-33669D01*
X118538Y-33654D01*
X118567Y-33651D01*
X118593D01*
X118615Y-33647D01*
X118644D01*
X118717Y-33651D01*
D02*
G37*
G36*
X120981Y-33622D02*
X121097Y-33640D01*
X121199Y-33662D01*
X121247Y-33676D01*
X121290Y-33691D01*
X121330Y-33705D01*
X121367Y-33720D01*
X121396Y-33731D01*
X121425Y-33742D01*
X121443Y-33753D01*
X121458Y-33760D01*
X121468Y-33764D01*
X121472Y-33767D01*
X121570Y-33829D01*
X121654Y-33902D01*
X121727Y-33975D01*
X121789Y-34047D01*
X121836Y-34113D01*
X121854Y-34142D01*
X121869Y-34168D01*
X121883Y-34186D01*
X121891Y-34200D01*
X121894Y-34211D01*
X121898Y-34215D01*
X121949Y-34328D01*
X121985Y-34444D01*
X122011Y-34561D01*
X122029Y-34666D01*
X122036Y-34714D01*
X122040Y-34761D01*
X122044Y-34797D01*
Y-34834D01*
X122047Y-34859D01*
Y-34881D01*
Y-34896D01*
Y-34899D01*
X122040Y-35030D01*
X122025Y-35158D01*
X122007Y-35271D01*
X121993Y-35325D01*
X121982Y-35372D01*
X121971Y-35416D01*
X121956Y-35456D01*
X121945Y-35493D01*
X121938Y-35522D01*
X121927Y-35544D01*
X121923Y-35562D01*
X121916Y-35573D01*
Y-35576D01*
X121862Y-35685D01*
X121800Y-35784D01*
X121734Y-35867D01*
X121702Y-35900D01*
X121672Y-35933D01*
X121643Y-35962D01*
X121614Y-35987D01*
X121589Y-36009D01*
X121567Y-36024D01*
X121552Y-36039D01*
X121538Y-36049D01*
X121530Y-36053D01*
X121527Y-36057D01*
X121476Y-36086D01*
X121425Y-36111D01*
X121316Y-36151D01*
X121206Y-36180D01*
X121101Y-36199D01*
X121050Y-36206D01*
X121006Y-36213D01*
X120966Y-36217D01*
X120933D01*
X120904Y-36220D01*
X120864D01*
X120791Y-36217D01*
X120722Y-36210D01*
X120657Y-36202D01*
X120595Y-36188D01*
X120537Y-36169D01*
X120482Y-36151D01*
X120431Y-36133D01*
X120384Y-36111D01*
X120344Y-36093D01*
X120304Y-36075D01*
X120275Y-36057D01*
X120246Y-36039D01*
X120227Y-36024D01*
X120209Y-36017D01*
X120202Y-36009D01*
X120198Y-36006D01*
X120147Y-35962D01*
X120104Y-35918D01*
X120063Y-35867D01*
X120023Y-35816D01*
X119958Y-35715D01*
X119907Y-35613D01*
X119885Y-35565D01*
X119867Y-35522D01*
X119852Y-35482D01*
X119841Y-35449D01*
X119831Y-35420D01*
X119823Y-35398D01*
X119820Y-35383D01*
Y-35380D01*
X120155Y-35296D01*
X120169Y-35354D01*
X120187Y-35409D01*
X120205Y-35460D01*
X120224Y-35507D01*
X120246Y-35551D01*
X120267Y-35587D01*
X120293Y-35624D01*
X120315Y-35656D01*
X120333Y-35685D01*
X120355Y-35707D01*
X120373Y-35729D01*
X120387Y-35747D01*
X120402Y-35758D01*
X120413Y-35769D01*
X120417Y-35773D01*
X120420Y-35776D01*
X120457Y-35805D01*
X120497Y-35827D01*
X120577Y-35867D01*
X120653Y-35897D01*
X120730Y-35915D01*
X120795Y-35929D01*
X120821Y-35933D01*
X120846D01*
X120868Y-35937D01*
X120893D01*
X120977Y-35933D01*
X121057Y-35918D01*
X121130Y-35900D01*
X121195Y-35878D01*
X121247Y-35857D01*
X121268Y-35846D01*
X121286Y-35838D01*
X121301Y-35831D01*
X121312Y-35824D01*
X121319Y-35820D01*
X121323D01*
X121392Y-35769D01*
X121450Y-35715D01*
X121501Y-35653D01*
X121541Y-35594D01*
X121574Y-35544D01*
X121596Y-35500D01*
X121603Y-35482D01*
X121610Y-35471D01*
X121614Y-35463D01*
Y-35460D01*
X121643Y-35365D01*
X121665Y-35271D01*
X121683Y-35176D01*
X121694Y-35089D01*
X121698Y-35048D01*
X121702Y-35012D01*
Y-34979D01*
X121705Y-34954D01*
Y-34932D01*
Y-34914D01*
Y-34903D01*
Y-34899D01*
X121702Y-34805D01*
X121694Y-34717D01*
X121680Y-34637D01*
X121665Y-34564D01*
X121654Y-34502D01*
X121647Y-34477D01*
X121640Y-34455D01*
X121636Y-34437D01*
X121632Y-34426D01*
X121629Y-34419D01*
Y-34415D01*
X121592Y-34331D01*
X121552Y-34255D01*
X121509Y-34193D01*
X121461Y-34138D01*
X121421Y-34095D01*
X121388Y-34066D01*
X121363Y-34047D01*
X121359Y-34040D01*
X121356D01*
X121279Y-33993D01*
X121195Y-33956D01*
X121115Y-33931D01*
X121039Y-33916D01*
X120970Y-33906D01*
X120941Y-33902D01*
X120915D01*
X120897Y-33898D01*
X120868D01*
X120777Y-33902D01*
X120693Y-33916D01*
X120624Y-33938D01*
X120562Y-33960D01*
X120515Y-33986D01*
X120478Y-34004D01*
X120457Y-34018D01*
X120449Y-34026D01*
X120391Y-34080D01*
X120336Y-34142D01*
X120293Y-34208D01*
X120256Y-34273D01*
X120227Y-34331D01*
X120216Y-34361D01*
X120209Y-34382D01*
X120202Y-34400D01*
X120194Y-34415D01*
X120191Y-34422D01*
Y-34426D01*
X119863Y-34350D01*
X119885Y-34284D01*
X119907Y-34226D01*
X119936Y-34171D01*
X119962Y-34117D01*
X119991Y-34069D01*
X120023Y-34026D01*
X120053Y-33982D01*
X120082Y-33946D01*
X120111Y-33916D01*
X120136Y-33887D01*
X120162Y-33862D01*
X120180Y-33844D01*
X120198Y-33825D01*
X120213Y-33814D01*
X120220Y-33811D01*
X120224Y-33807D01*
X120275Y-33774D01*
X120326Y-33742D01*
X120377Y-33716D01*
X120431Y-33694D01*
X120540Y-33662D01*
X120639Y-33640D01*
X120686Y-33629D01*
X120726Y-33625D01*
X120766Y-33622D01*
X120799Y-33618D01*
X120824Y-33614D01*
X120861D01*
X120981Y-33622D01*
D02*
G37*
G36*
X116853Y-33654D02*
X116944Y-33669D01*
X117020Y-33694D01*
X117086Y-33720D01*
X117141Y-33749D01*
X117162Y-33760D01*
X117181Y-33774D01*
X117195Y-33782D01*
X117206Y-33789D01*
X117210Y-33796D01*
X117213D01*
X117279Y-33854D01*
X117333Y-33924D01*
X117381Y-33993D01*
X117417Y-34058D01*
X117446Y-34120D01*
X117461Y-34146D01*
X117468Y-34171D01*
X117475Y-34189D01*
X117483Y-34204D01*
X117486Y-34211D01*
Y-34215D01*
X117501Y-34269D01*
X117516Y-34324D01*
X117537Y-34444D01*
X117555Y-34564D01*
X117566Y-34677D01*
X117570Y-34732D01*
X117574Y-34779D01*
Y-34823D01*
X117577Y-34863D01*
Y-34892D01*
Y-34917D01*
Y-34932D01*
Y-34936D01*
X117574Y-35063D01*
X117566Y-35183D01*
X117555Y-35292D01*
X117537Y-35394D01*
X117519Y-35489D01*
X117497Y-35573D01*
X117475Y-35649D01*
X117454Y-35715D01*
X117432Y-35773D01*
X117406Y-35824D01*
X117388Y-35867D01*
X117370Y-35900D01*
X117352Y-35929D01*
X117341Y-35947D01*
X117333Y-35958D01*
X117330Y-35962D01*
X117290Y-36006D01*
X117246Y-36046D01*
X117199Y-36082D01*
X117151Y-36111D01*
X117104Y-36137D01*
X117057Y-36159D01*
X117009Y-36173D01*
X116966Y-36188D01*
X116922Y-36199D01*
X116882Y-36206D01*
X116846Y-36213D01*
X116817Y-36217D01*
X116791Y-36220D01*
X116755D01*
X116656Y-36213D01*
X116565Y-36199D01*
X116489Y-36173D01*
X116423Y-36148D01*
X116369Y-36122D01*
X116351Y-36108D01*
X116332Y-36097D01*
X116318Y-36090D01*
X116307Y-36082D01*
X116303Y-36075D01*
X116300D01*
X116234Y-36013D01*
X116180Y-35947D01*
X116132Y-35875D01*
X116096Y-35809D01*
X116067Y-35747D01*
X116052Y-35722D01*
X116045Y-35696D01*
X116038Y-35678D01*
X116030Y-35664D01*
X116027Y-35656D01*
Y-35653D01*
X116008Y-35598D01*
X115994Y-35544D01*
X115972Y-35427D01*
X115954Y-35307D01*
X115943Y-35190D01*
X115939Y-35139D01*
X115936Y-35092D01*
Y-35048D01*
X115932Y-35008D01*
Y-34979D01*
Y-34954D01*
Y-34939D01*
Y-34936D01*
Y-34866D01*
X115936Y-34801D01*
Y-34743D01*
X115939Y-34684D01*
X115947Y-34633D01*
X115950Y-34582D01*
X115954Y-34539D01*
X115961Y-34499D01*
X115965Y-34462D01*
X115972Y-34430D01*
X115976Y-34404D01*
X115979Y-34382D01*
X115983Y-34364D01*
X115987Y-34353D01*
X115990Y-34346D01*
Y-34342D01*
X116012Y-34262D01*
X116038Y-34189D01*
X116067Y-34128D01*
X116089Y-34073D01*
X116114Y-34026D01*
X116129Y-33993D01*
X116143Y-33975D01*
X116147Y-33967D01*
X116187Y-33913D01*
X116227Y-33865D01*
X116271Y-33825D01*
X116311Y-33789D01*
X116347Y-33764D01*
X116376Y-33745D01*
X116394Y-33734D01*
X116398Y-33731D01*
X116402D01*
X116460Y-33702D01*
X116522Y-33683D01*
X116580Y-33669D01*
X116635Y-33658D01*
X116682Y-33651D01*
X116722Y-33647D01*
X116755D01*
X116853Y-33654D01*
D02*
G37*
G36*
X126659Y-74578D02*
X126728Y-74585D01*
X126794Y-74593D01*
X126856Y-74607D01*
X126914Y-74625D01*
X126969Y-74644D01*
X127020Y-74662D01*
X127067Y-74684D01*
X127107Y-74702D01*
X127147Y-74720D01*
X127176Y-74738D01*
X127205Y-74756D01*
X127224Y-74771D01*
X127242Y-74778D01*
X127249Y-74786D01*
X127253Y-74789D01*
X127304Y-74833D01*
X127347Y-74877D01*
X127387Y-74928D01*
X127427Y-74979D01*
X127493Y-75080D01*
X127544Y-75182D01*
X127566Y-75230D01*
X127584Y-75273D01*
X127598Y-75313D01*
X127609Y-75346D01*
X127620Y-75375D01*
X127628Y-75397D01*
X127631Y-75412D01*
Y-75415D01*
X127296Y-75499D01*
X127282Y-75441D01*
X127264Y-75386D01*
X127245Y-75335D01*
X127227Y-75288D01*
X127205Y-75244D01*
X127183Y-75208D01*
X127158Y-75171D01*
X127136Y-75139D01*
X127118Y-75109D01*
X127096Y-75088D01*
X127078Y-75066D01*
X127063Y-75048D01*
X127049Y-75037D01*
X127038Y-75026D01*
X127034Y-75022D01*
X127031Y-75019D01*
X126994Y-74989D01*
X126954Y-74968D01*
X126874Y-74928D01*
X126798Y-74898D01*
X126721Y-74880D01*
X126656Y-74866D01*
X126630Y-74862D01*
X126605D01*
X126583Y-74858D01*
X126557D01*
X126474Y-74862D01*
X126394Y-74877D01*
X126321Y-74895D01*
X126255Y-74917D01*
X126204Y-74938D01*
X126182Y-74949D01*
X126164Y-74957D01*
X126150Y-74964D01*
X126139Y-74971D01*
X126131Y-74975D01*
X126128D01*
X126059Y-75026D01*
X126000Y-75080D01*
X125950Y-75142D01*
X125909Y-75200D01*
X125877Y-75252D01*
X125855Y-75295D01*
X125848Y-75313D01*
X125840Y-75324D01*
X125837Y-75332D01*
Y-75335D01*
X125807Y-75430D01*
X125786Y-75524D01*
X125768Y-75619D01*
X125757Y-75706D01*
X125753Y-75747D01*
X125749Y-75783D01*
Y-75816D01*
X125746Y-75841D01*
Y-75863D01*
Y-75881D01*
Y-75892D01*
Y-75896D01*
X125749Y-75990D01*
X125757Y-76078D01*
X125771Y-76158D01*
X125786Y-76231D01*
X125797Y-76293D01*
X125804Y-76318D01*
X125811Y-76340D01*
X125815Y-76358D01*
X125819Y-76369D01*
X125822Y-76376D01*
Y-76380D01*
X125858Y-76464D01*
X125899Y-76540D01*
X125942Y-76602D01*
X125990Y-76657D01*
X126030Y-76700D01*
X126062Y-76729D01*
X126088Y-76748D01*
X126092Y-76755D01*
X126095D01*
X126172Y-76802D01*
X126255Y-76838D01*
X126335Y-76864D01*
X126412Y-76879D01*
X126481Y-76889D01*
X126510Y-76893D01*
X126535D01*
X126554Y-76897D01*
X126583D01*
X126674Y-76893D01*
X126758Y-76879D01*
X126827Y-76857D01*
X126889Y-76835D01*
X126936Y-76809D01*
X126972Y-76791D01*
X126994Y-76777D01*
X127002Y-76769D01*
X127060Y-76715D01*
X127114Y-76653D01*
X127158Y-76587D01*
X127194Y-76522D01*
X127224Y-76464D01*
X127234Y-76434D01*
X127242Y-76413D01*
X127249Y-76394D01*
X127256Y-76380D01*
X127260Y-76373D01*
Y-76369D01*
X127587Y-76445D01*
X127566Y-76511D01*
X127544Y-76569D01*
X127515Y-76624D01*
X127489Y-76678D01*
X127460Y-76726D01*
X127427Y-76769D01*
X127398Y-76813D01*
X127369Y-76850D01*
X127340Y-76879D01*
X127314Y-76908D01*
X127289Y-76933D01*
X127271Y-76951D01*
X127253Y-76970D01*
X127238Y-76981D01*
X127231Y-76984D01*
X127227Y-76988D01*
X127176Y-77021D01*
X127125Y-77053D01*
X127074Y-77079D01*
X127020Y-77101D01*
X126910Y-77133D01*
X126812Y-77155D01*
X126765Y-77166D01*
X126725Y-77170D01*
X126685Y-77173D01*
X126652Y-77177D01*
X126627Y-77181D01*
X126590D01*
X126470Y-77173D01*
X126354Y-77155D01*
X126252Y-77133D01*
X126204Y-77119D01*
X126161Y-77104D01*
X126121Y-77090D01*
X126084Y-77075D01*
X126055Y-77064D01*
X126026Y-77053D01*
X126008Y-77042D01*
X125993Y-77035D01*
X125982Y-77031D01*
X125979Y-77028D01*
X125880Y-76966D01*
X125797Y-76893D01*
X125724Y-76820D01*
X125662Y-76748D01*
X125615Y-76682D01*
X125596Y-76653D01*
X125582Y-76627D01*
X125567Y-76609D01*
X125560Y-76595D01*
X125556Y-76584D01*
X125553Y-76580D01*
X125502Y-76467D01*
X125465Y-76351D01*
X125440Y-76234D01*
X125422Y-76129D01*
X125414Y-76081D01*
X125411Y-76034D01*
X125407Y-75998D01*
Y-75961D01*
X125403Y-75936D01*
Y-75914D01*
Y-75899D01*
Y-75896D01*
X125411Y-75765D01*
X125425Y-75637D01*
X125444Y-75524D01*
X125458Y-75470D01*
X125469Y-75423D01*
X125480Y-75379D01*
X125495Y-75339D01*
X125505Y-75302D01*
X125513Y-75273D01*
X125524Y-75252D01*
X125527Y-75233D01*
X125534Y-75222D01*
Y-75219D01*
X125589Y-75109D01*
X125651Y-75011D01*
X125717Y-74928D01*
X125749Y-74895D01*
X125778Y-74862D01*
X125807Y-74833D01*
X125837Y-74807D01*
X125862Y-74786D01*
X125884Y-74771D01*
X125899Y-74756D01*
X125913Y-74746D01*
X125920Y-74742D01*
X125924Y-74738D01*
X125975Y-74709D01*
X126026Y-74684D01*
X126135Y-74644D01*
X126244Y-74615D01*
X126350Y-74596D01*
X126401Y-74589D01*
X126445Y-74582D01*
X126485Y-74578D01*
X126517D01*
X126547Y-74575D01*
X126586D01*
X126659Y-74578D01*
D02*
G37*
G36*
X131500Y-74917D02*
X130259D01*
X130303Y-74979D01*
X130325Y-75004D01*
X130343Y-75029D01*
X130361Y-75051D01*
X130376Y-75066D01*
X130387Y-75077D01*
X130390Y-75080D01*
X130409Y-75099D01*
X130430Y-75117D01*
X130481Y-75164D01*
X130540Y-75219D01*
X130601Y-75273D01*
X130660Y-75321D01*
X130685Y-75343D01*
X130707Y-75364D01*
X130725Y-75379D01*
X130740Y-75390D01*
X130747Y-75397D01*
X130751Y-75401D01*
X130809Y-75452D01*
X130867Y-75499D01*
X130918Y-75546D01*
X130965Y-75586D01*
X131009Y-75626D01*
X131045Y-75663D01*
X131082Y-75696D01*
X131111Y-75725D01*
X131140Y-75754D01*
X131162Y-75776D01*
X131180Y-75794D01*
X131198Y-75812D01*
X131217Y-75834D01*
X131224Y-75841D01*
X131275Y-75903D01*
X131318Y-75958D01*
X131355Y-76012D01*
X131384Y-76056D01*
X131406Y-76096D01*
X131420Y-76125D01*
X131428Y-76143D01*
X131431Y-76151D01*
X131453Y-76205D01*
X131468Y-76260D01*
X131482Y-76311D01*
X131490Y-76354D01*
X131493Y-76394D01*
X131497Y-76424D01*
Y-76442D01*
Y-76449D01*
X131493Y-76504D01*
X131486Y-76555D01*
X131479Y-76606D01*
X131464Y-76649D01*
X131428Y-76737D01*
X131391Y-76806D01*
X131369Y-76838D01*
X131351Y-76864D01*
X131333Y-76889D01*
X131315Y-76908D01*
X131300Y-76922D01*
X131293Y-76937D01*
X131286Y-76940D01*
X131282Y-76944D01*
X131242Y-76981D01*
X131198Y-77013D01*
X131151Y-77039D01*
X131104Y-77061D01*
X131009Y-77097D01*
X130914Y-77122D01*
X130874Y-77130D01*
X130834Y-77137D01*
X130798Y-77141D01*
X130769Y-77144D01*
X130743Y-77148D01*
X130707D01*
X130641Y-77144D01*
X130580Y-77141D01*
X130521Y-77130D01*
X130467Y-77119D01*
X130416Y-77104D01*
X130368Y-77090D01*
X130325Y-77071D01*
X130285Y-77053D01*
X130248Y-77035D01*
X130219Y-77017D01*
X130194Y-77002D01*
X130172Y-76988D01*
X130154Y-76977D01*
X130143Y-76966D01*
X130136Y-76962D01*
X130132Y-76959D01*
X130096Y-76922D01*
X130063Y-76882D01*
X130030Y-76838D01*
X130005Y-76795D01*
X129961Y-76708D01*
X129932Y-76620D01*
X129921Y-76580D01*
X129910Y-76540D01*
X129903Y-76507D01*
X129895Y-76478D01*
X129892Y-76453D01*
Y-76434D01*
X129888Y-76424D01*
Y-76420D01*
X130205Y-76387D01*
X130212Y-76471D01*
X130227Y-76544D01*
X130248Y-76609D01*
X130274Y-76660D01*
X130296Y-76704D01*
X130317Y-76733D01*
X130332Y-76751D01*
X130339Y-76758D01*
X130394Y-76802D01*
X130452Y-76835D01*
X130514Y-76860D01*
X130569Y-76875D01*
X130620Y-76886D01*
X130663Y-76889D01*
X130678Y-76893D01*
X130700D01*
X130776Y-76889D01*
X130845Y-76875D01*
X130903Y-76853D01*
X130955Y-76831D01*
X130995Y-76806D01*
X131020Y-76788D01*
X131038Y-76773D01*
X131045Y-76766D01*
X131089Y-76715D01*
X131122Y-76664D01*
X131147Y-76613D01*
X131162Y-76562D01*
X131173Y-76522D01*
X131176Y-76486D01*
X131180Y-76464D01*
Y-76460D01*
Y-76456D01*
X131173Y-76391D01*
X131158Y-76322D01*
X131133Y-76260D01*
X131107Y-76201D01*
X131078Y-76154D01*
X131053Y-76114D01*
X131045Y-76100D01*
X131038Y-76089D01*
X131031Y-76085D01*
Y-76081D01*
X131002Y-76041D01*
X130965Y-76001D01*
X130925Y-75958D01*
X130882Y-75914D01*
X130791Y-75827D01*
X130700Y-75739D01*
X130652Y-75699D01*
X130612Y-75663D01*
X130572Y-75630D01*
X130540Y-75601D01*
X130514Y-75579D01*
X130492Y-75561D01*
X130478Y-75550D01*
X130474Y-75546D01*
X130383Y-75470D01*
X130299Y-75397D01*
X130230Y-75332D01*
X130175Y-75277D01*
X130128Y-75230D01*
X130096Y-75197D01*
X130077Y-75175D01*
X130070Y-75171D01*
Y-75168D01*
X130019Y-75106D01*
X129979Y-75048D01*
X129943Y-74989D01*
X129913Y-74938D01*
X129892Y-74895D01*
X129877Y-74862D01*
X129870Y-74840D01*
X129866Y-74836D01*
Y-74833D01*
X129852Y-74793D01*
X129844Y-74756D01*
X129837Y-74720D01*
X129833Y-74687D01*
X129830Y-74658D01*
Y-74636D01*
Y-74622D01*
Y-74618D01*
X131500D01*
Y-74917D01*
D02*
G37*
G36*
X129215Y-75222D02*
X129557D01*
Y-75506D01*
X129215D01*
Y-77137D01*
X128963D01*
X127810Y-75506D01*
Y-75222D01*
X128905D01*
Y-74618D01*
X129215D01*
Y-75222D01*
D02*
G37*
G36*
X145467Y-69839D02*
X145175Y-69879D01*
X145150Y-69839D01*
X145117Y-69806D01*
X145088Y-69773D01*
X145059Y-69748D01*
X145030Y-69729D01*
X145008Y-69711D01*
X144993Y-69704D01*
X144990Y-69700D01*
X144942Y-69678D01*
X144895Y-69660D01*
X144852Y-69649D01*
X144808Y-69638D01*
X144771Y-69635D01*
X144742Y-69631D01*
X144673D01*
X144629Y-69638D01*
X144553Y-69656D01*
X144488Y-69682D01*
X144429Y-69708D01*
X144386Y-69737D01*
X144353Y-69762D01*
X144335Y-69780D01*
X144327Y-69784D01*
Y-69788D01*
X144276Y-69849D01*
X144240Y-69915D01*
X144214Y-69984D01*
X144196Y-70053D01*
X144185Y-70112D01*
X144182Y-70137D01*
Y-70159D01*
X144178Y-70177D01*
Y-70192D01*
Y-70199D01*
Y-70202D01*
Y-70253D01*
X144185Y-70301D01*
X144203Y-70392D01*
X144229Y-70468D01*
X144255Y-70530D01*
X144284Y-70581D01*
X144309Y-70621D01*
X144320Y-70632D01*
X144327Y-70643D01*
X144331Y-70647D01*
X144335Y-70650D01*
X144364Y-70679D01*
X144393Y-70705D01*
X144458Y-70749D01*
X144520Y-70778D01*
X144582Y-70796D01*
X144633Y-70810D01*
X144677Y-70814D01*
X144691Y-70818D01*
X144713D01*
X144782Y-70814D01*
X144844Y-70799D01*
X144899Y-70781D01*
X144942Y-70759D01*
X144983Y-70738D01*
X145012Y-70719D01*
X145026Y-70705D01*
X145034Y-70701D01*
X145077Y-70650D01*
X145114Y-70596D01*
X145143Y-70534D01*
X145165Y-70479D01*
X145179Y-70425D01*
X145190Y-70385D01*
X145194Y-70366D01*
X145197Y-70355D01*
Y-70348D01*
Y-70345D01*
X145521Y-70370D01*
X145514Y-70428D01*
X145503Y-70483D01*
X145470Y-70585D01*
X145430Y-70672D01*
X145408Y-70712D01*
X145387Y-70745D01*
X145368Y-70778D01*
X145346Y-70807D01*
X145328Y-70829D01*
X145310Y-70847D01*
X145296Y-70861D01*
X145288Y-70876D01*
X145281Y-70880D01*
X145277Y-70883D01*
X145234Y-70916D01*
X145190Y-70945D01*
X145143Y-70971D01*
X145095Y-70992D01*
X145004Y-71025D01*
X144913Y-71047D01*
X144873Y-71058D01*
X144833Y-71062D01*
X144800Y-71065D01*
X144771Y-71069D01*
X144746Y-71073D01*
X144713D01*
X144637Y-71069D01*
X144564Y-71058D01*
X144495Y-71043D01*
X144433Y-71025D01*
X144375Y-71000D01*
X144320Y-70974D01*
X144269Y-70949D01*
X144225Y-70920D01*
X144185Y-70890D01*
X144149Y-70865D01*
X144120Y-70836D01*
X144094Y-70814D01*
X144076Y-70796D01*
X144062Y-70781D01*
X144054Y-70770D01*
X144051Y-70767D01*
X144014Y-70719D01*
X143985Y-70668D01*
X143956Y-70621D01*
X143934Y-70570D01*
X143898Y-70472D01*
X143876Y-70377D01*
X143869Y-70337D01*
X143861Y-70297D01*
X143858Y-70264D01*
X143854Y-70235D01*
X143851Y-70210D01*
Y-70192D01*
Y-70181D01*
Y-70177D01*
X143854Y-70112D01*
X143861Y-70050D01*
X143872Y-69988D01*
X143887Y-69933D01*
X143905Y-69882D01*
X143923Y-69831D01*
X143945Y-69788D01*
X143963Y-69748D01*
X143985Y-69711D01*
X144007Y-69678D01*
X144025Y-69653D01*
X144043Y-69627D01*
X144058Y-69609D01*
X144069Y-69598D01*
X144076Y-69591D01*
X144080Y-69587D01*
X144123Y-69547D01*
X144167Y-69511D01*
X144214Y-69482D01*
X144262Y-69456D01*
X144309Y-69431D01*
X144356Y-69413D01*
X144444Y-69387D01*
X144484Y-69376D01*
X144520Y-69369D01*
X144553Y-69365D01*
X144582Y-69362D01*
X144604Y-69358D01*
X144684D01*
X144728Y-69365D01*
X144815Y-69384D01*
X144895Y-69409D01*
X144968Y-69438D01*
X145026Y-69467D01*
X145052Y-69482D01*
X145073Y-69493D01*
X145092Y-69504D01*
X145103Y-69511D01*
X145110Y-69515D01*
X145114Y-69518D01*
X144979Y-68837D01*
X143971D01*
Y-68543D01*
X145223D01*
X145467Y-69839D01*
D02*
G37*
G36*
X146966Y-68474D02*
X147083Y-68492D01*
X147185Y-68514D01*
X147232Y-68528D01*
X147276Y-68543D01*
X147316Y-68557D01*
X147352Y-68572D01*
X147381Y-68583D01*
X147410Y-68594D01*
X147429Y-68605D01*
X147443Y-68612D01*
X147454Y-68616D01*
X147458Y-68619D01*
X147556Y-68681D01*
X147640Y-68754D01*
X147713Y-68827D01*
X147774Y-68899D01*
X147822Y-68965D01*
X147840Y-68994D01*
X147854Y-69020D01*
X147869Y-69038D01*
X147876Y-69052D01*
X147880Y-69063D01*
X147884Y-69067D01*
X147934Y-69180D01*
X147971Y-69296D01*
X147996Y-69413D01*
X148015Y-69518D01*
X148022Y-69565D01*
X148026Y-69613D01*
X148029Y-69649D01*
Y-69686D01*
X148033Y-69711D01*
Y-69733D01*
Y-69748D01*
Y-69751D01*
X148026Y-69882D01*
X148011Y-70010D01*
X147993Y-70122D01*
X147978Y-70177D01*
X147967Y-70224D01*
X147956Y-70268D01*
X147942Y-70308D01*
X147931Y-70345D01*
X147924Y-70374D01*
X147913Y-70395D01*
X147909Y-70414D01*
X147902Y-70425D01*
Y-70428D01*
X147847Y-70537D01*
X147785Y-70636D01*
X147720Y-70719D01*
X147687Y-70752D01*
X147658Y-70785D01*
X147629Y-70814D01*
X147600Y-70840D01*
X147574Y-70861D01*
X147552Y-70876D01*
X147538Y-70890D01*
X147523Y-70901D01*
X147516Y-70905D01*
X147512Y-70909D01*
X147461Y-70938D01*
X147410Y-70963D01*
X147301Y-71003D01*
X147192Y-71032D01*
X147086Y-71051D01*
X147036Y-71058D01*
X146992Y-71065D01*
X146952Y-71069D01*
X146919D01*
X146890Y-71073D01*
X146850D01*
X146777Y-71069D01*
X146708Y-71062D01*
X146642Y-71054D01*
X146581Y-71040D01*
X146522Y-71021D01*
X146468Y-71003D01*
X146417Y-70985D01*
X146369Y-70963D01*
X146329Y-70945D01*
X146289Y-70927D01*
X146260Y-70909D01*
X146231Y-70890D01*
X146213Y-70876D01*
X146195Y-70869D01*
X146187Y-70861D01*
X146184Y-70858D01*
X146133Y-70814D01*
X146089Y-70770D01*
X146049Y-70719D01*
X146009Y-70668D01*
X145943Y-70566D01*
X145893Y-70465D01*
X145871Y-70417D01*
X145852Y-70374D01*
X145838Y-70334D01*
X145827Y-70301D01*
X145816Y-70272D01*
X145809Y-70250D01*
X145805Y-70235D01*
Y-70232D01*
X146140Y-70148D01*
X146155Y-70206D01*
X146173Y-70261D01*
X146191Y-70312D01*
X146209Y-70359D01*
X146231Y-70403D01*
X146253Y-70439D01*
X146278Y-70476D01*
X146300Y-70508D01*
X146318Y-70537D01*
X146340Y-70559D01*
X146358Y-70581D01*
X146373Y-70599D01*
X146388Y-70610D01*
X146398Y-70621D01*
X146402Y-70625D01*
X146406Y-70628D01*
X146442Y-70657D01*
X146482Y-70679D01*
X146562Y-70719D01*
X146639Y-70749D01*
X146715Y-70767D01*
X146781Y-70781D01*
X146806Y-70785D01*
X146832D01*
X146853Y-70789D01*
X146879D01*
X146963Y-70785D01*
X147043Y-70770D01*
X147116Y-70752D01*
X147181Y-70730D01*
X147232Y-70709D01*
X147254Y-70698D01*
X147272Y-70690D01*
X147287Y-70683D01*
X147298Y-70676D01*
X147305Y-70672D01*
X147309D01*
X147378Y-70621D01*
X147436Y-70566D01*
X147487Y-70505D01*
X147527Y-70446D01*
X147560Y-70395D01*
X147582Y-70352D01*
X147589Y-70334D01*
X147596Y-70323D01*
X147600Y-70315D01*
Y-70312D01*
X147629Y-70217D01*
X147651Y-70122D01*
X147669Y-70028D01*
X147680Y-69940D01*
X147683Y-69900D01*
X147687Y-69864D01*
Y-69831D01*
X147691Y-69806D01*
Y-69784D01*
Y-69766D01*
Y-69755D01*
Y-69751D01*
X147687Y-69656D01*
X147680Y-69569D01*
X147665Y-69489D01*
X147651Y-69416D01*
X147640Y-69354D01*
X147632Y-69329D01*
X147625Y-69307D01*
X147622Y-69289D01*
X147618Y-69278D01*
X147614Y-69271D01*
Y-69267D01*
X147578Y-69183D01*
X147538Y-69107D01*
X147494Y-69045D01*
X147447Y-68990D01*
X147407Y-68947D01*
X147374Y-68918D01*
X147348Y-68899D01*
X147345Y-68892D01*
X147341D01*
X147265Y-68845D01*
X147181Y-68808D01*
X147101Y-68783D01*
X147025Y-68768D01*
X146955Y-68757D01*
X146926Y-68754D01*
X146901D01*
X146883Y-68750D01*
X146853D01*
X146763Y-68754D01*
X146679Y-68768D01*
X146610Y-68790D01*
X146548Y-68812D01*
X146500Y-68837D01*
X146464Y-68856D01*
X146442Y-68870D01*
X146435Y-68878D01*
X146377Y-68932D01*
X146322Y-68994D01*
X146278Y-69060D01*
X146242Y-69125D01*
X146213Y-69183D01*
X146202Y-69212D01*
X146195Y-69234D01*
X146187Y-69253D01*
X146180Y-69267D01*
X146176Y-69274D01*
Y-69278D01*
X145849Y-69201D01*
X145871Y-69136D01*
X145893Y-69078D01*
X145922Y-69023D01*
X145947Y-68969D01*
X145976Y-68921D01*
X146009Y-68878D01*
X146038Y-68834D01*
X146067Y-68797D01*
X146096Y-68768D01*
X146122Y-68739D01*
X146147Y-68714D01*
X146166Y-68696D01*
X146184Y-68677D01*
X146198Y-68666D01*
X146205Y-68663D01*
X146209Y-68659D01*
X146260Y-68626D01*
X146311Y-68594D01*
X146362Y-68568D01*
X146417Y-68546D01*
X146526Y-68514D01*
X146624Y-68492D01*
X146671Y-68481D01*
X146712Y-68477D01*
X146751Y-68474D01*
X146784Y-68470D01*
X146810Y-68466D01*
X146846D01*
X146966Y-68474D01*
D02*
G37*
G36*
X142802Y-68503D02*
X142860Y-68506D01*
X142962Y-68528D01*
X143010Y-68543D01*
X143053Y-68557D01*
X143093Y-68575D01*
X143130Y-68594D01*
X143159Y-68612D01*
X143188Y-68630D01*
X143213Y-68645D01*
X143232Y-68659D01*
X143246Y-68670D01*
X143257Y-68681D01*
X143264Y-68685D01*
X143268Y-68688D01*
X143301Y-68725D01*
X143334Y-68761D01*
X143359Y-68801D01*
X143381Y-68841D01*
X143417Y-68918D01*
X143439Y-68990D01*
X143454Y-69052D01*
X143457Y-69081D01*
X143461Y-69103D01*
X143465Y-69125D01*
Y-69140D01*
Y-69147D01*
Y-69151D01*
X143461Y-69216D01*
X143450Y-69278D01*
X143436Y-69333D01*
X143417Y-69380D01*
X143403Y-69416D01*
X143388Y-69445D01*
X143377Y-69460D01*
X143374Y-69467D01*
X143334Y-69511D01*
X143290Y-69551D01*
X143243Y-69587D01*
X143195Y-69617D01*
X143152Y-69638D01*
X143119Y-69653D01*
X143104Y-69660D01*
X143093Y-69664D01*
X143090Y-69667D01*
X143086D01*
X143170Y-69693D01*
X143239Y-69726D01*
X143301Y-69766D01*
X143352Y-69802D01*
X143392Y-69839D01*
X143421Y-69868D01*
X143436Y-69886D01*
X143443Y-69889D01*
Y-69893D01*
X143483Y-69959D01*
X143516Y-70028D01*
X143537Y-70093D01*
X143552Y-70159D01*
X143559Y-70217D01*
X143563Y-70243D01*
Y-70264D01*
X143567Y-70279D01*
Y-70293D01*
Y-70301D01*
Y-70304D01*
X143563Y-70363D01*
X143556Y-70421D01*
X143545Y-70476D01*
X143530Y-70530D01*
X143494Y-70621D01*
X143475Y-70665D01*
X143454Y-70701D01*
X143432Y-70738D01*
X143414Y-70767D01*
X143392Y-70792D01*
X143377Y-70814D01*
X143363Y-70832D01*
X143352Y-70843D01*
X143344Y-70850D01*
X143341Y-70854D01*
X143297Y-70894D01*
X143250Y-70927D01*
X143199Y-70956D01*
X143148Y-70982D01*
X143101Y-71000D01*
X143050Y-71018D01*
X142951Y-71043D01*
X142908Y-71054D01*
X142868Y-71062D01*
X142831Y-71065D01*
X142798Y-71069D01*
X142773Y-71073D01*
X142737D01*
X142667Y-71069D01*
X142606Y-71062D01*
X142544Y-71051D01*
X142485Y-71040D01*
X142435Y-71021D01*
X142384Y-71003D01*
X142336Y-70985D01*
X142296Y-70963D01*
X142260Y-70941D01*
X142227Y-70923D01*
X142201Y-70905D01*
X142176Y-70887D01*
X142158Y-70876D01*
X142147Y-70865D01*
X142140Y-70858D01*
X142136Y-70854D01*
X142096Y-70810D01*
X142060Y-70767D01*
X142031Y-70723D01*
X142005Y-70676D01*
X141980Y-70632D01*
X141961Y-70585D01*
X141936Y-70501D01*
X141925Y-70461D01*
X141918Y-70425D01*
X141914Y-70392D01*
X141910Y-70366D01*
X141907Y-70345D01*
Y-70326D01*
Y-70315D01*
Y-70312D01*
X141910Y-70228D01*
X141925Y-70152D01*
X141947Y-70082D01*
X141969Y-70024D01*
X141990Y-69977D01*
X142012Y-69940D01*
X142027Y-69919D01*
X142031Y-69915D01*
Y-69911D01*
X142081Y-69853D01*
X142136Y-69802D01*
X142194Y-69762D01*
X142249Y-69726D01*
X142300Y-69700D01*
X142343Y-69682D01*
X142358Y-69675D01*
X142369Y-69671D01*
X142376Y-69667D01*
X142380D01*
X142314Y-69638D01*
X142260Y-69606D01*
X142212Y-69573D01*
X142172Y-69540D01*
X142143Y-69511D01*
X142122Y-69489D01*
X142107Y-69475D01*
X142103Y-69467D01*
X142070Y-69416D01*
X142049Y-69365D01*
X142031Y-69314D01*
X142020Y-69263D01*
X142012Y-69223D01*
X142009Y-69191D01*
Y-69169D01*
Y-69165D01*
Y-69161D01*
X142012Y-69111D01*
X142016Y-69063D01*
X142041Y-68972D01*
X142074Y-68892D01*
X142111Y-68823D01*
X142147Y-68768D01*
X142165Y-68747D01*
X142180Y-68725D01*
X142194Y-68710D01*
X142205Y-68699D01*
X142209Y-68696D01*
X142212Y-68692D01*
X142253Y-68659D01*
X142293Y-68626D01*
X142336Y-68601D01*
X142380Y-68579D01*
X142467Y-68546D01*
X142555Y-68524D01*
X142591Y-68514D01*
X142627Y-68510D01*
X142660Y-68506D01*
X142689Y-68503D01*
X142711Y-68499D01*
X142744D01*
X142802Y-68503D01*
D02*
G37*
G36*
X147442Y-45725D02*
X147569Y-45740D01*
X147682Y-45758D01*
X147737Y-45773D01*
X147784Y-45784D01*
X147828Y-45794D01*
X147868Y-45809D01*
X147904Y-45820D01*
X147933Y-45827D01*
X147955Y-45838D01*
X147973Y-45842D01*
X147984Y-45849D01*
X147988D01*
X148097Y-45904D01*
X148195Y-45966D01*
X148279Y-46031D01*
X148312Y-46064D01*
X148345Y-46093D01*
X148374Y-46122D01*
X148399Y-46151D01*
X148421Y-46177D01*
X148435Y-46199D01*
X148450Y-46213D01*
X148461Y-46228D01*
X148465Y-46235D01*
X148468Y-46239D01*
X148497Y-46290D01*
X148523Y-46341D01*
X148563Y-46450D01*
X148592Y-46559D01*
X148610Y-46665D01*
X148617Y-46715D01*
X148625Y-46759D01*
X148628Y-46799D01*
Y-46832D01*
X148632Y-46861D01*
Y-46901D01*
X148628Y-46974D01*
X148621Y-47043D01*
X148614Y-47109D01*
X148599Y-47170D01*
X148581Y-47229D01*
X148563Y-47283D01*
X148545Y-47334D01*
X148523Y-47381D01*
X148505Y-47422D01*
X148486Y-47462D01*
X148468Y-47491D01*
X148450Y-47520D01*
X148435Y-47538D01*
X148428Y-47556D01*
X148421Y-47563D01*
X148417Y-47567D01*
X148374Y-47618D01*
X148330Y-47662D01*
X148279Y-47702D01*
X148228Y-47742D01*
X148126Y-47807D01*
X148024Y-47858D01*
X147977Y-47880D01*
X147933Y-47898D01*
X147893Y-47913D01*
X147860Y-47924D01*
X147831Y-47935D01*
X147810Y-47942D01*
X147795Y-47946D01*
X147791D01*
X147707Y-47611D01*
X147766Y-47596D01*
X147820Y-47578D01*
X147871Y-47560D01*
X147919Y-47542D01*
X147962Y-47520D01*
X147999Y-47498D01*
X148035Y-47473D01*
X148068Y-47451D01*
X148097Y-47433D01*
X148119Y-47411D01*
X148141Y-47392D01*
X148159Y-47378D01*
X148170Y-47363D01*
X148181Y-47352D01*
X148184Y-47349D01*
X148188Y-47345D01*
X148217Y-47309D01*
X148239Y-47269D01*
X148279Y-47189D01*
X148308Y-47112D01*
X148326Y-47036D01*
X148341Y-46970D01*
X148345Y-46945D01*
Y-46919D01*
X148348Y-46897D01*
Y-46872D01*
X148345Y-46788D01*
X148330Y-46708D01*
X148312Y-46635D01*
X148290Y-46570D01*
X148268Y-46519D01*
X148257Y-46497D01*
X148250Y-46479D01*
X148243Y-46464D01*
X148235Y-46453D01*
X148232Y-46446D01*
Y-46442D01*
X148181Y-46373D01*
X148126Y-46315D01*
X148064Y-46264D01*
X148006Y-46224D01*
X147955Y-46191D01*
X147911Y-46169D01*
X147893Y-46162D01*
X147882Y-46155D01*
X147875Y-46151D01*
X147871D01*
X147777Y-46122D01*
X147682Y-46100D01*
X147587Y-46082D01*
X147500Y-46071D01*
X147460Y-46068D01*
X147424Y-46064D01*
X147391D01*
X147365Y-46060D01*
X147344D01*
X147325D01*
X147314D01*
X147311D01*
X147216Y-46064D01*
X147129Y-46071D01*
X147049Y-46086D01*
X146976Y-46100D01*
X146914Y-46111D01*
X146888Y-46119D01*
X146867Y-46126D01*
X146848Y-46129D01*
X146838Y-46133D01*
X146830Y-46137D01*
X146827D01*
X146743Y-46173D01*
X146667Y-46213D01*
X146605Y-46257D01*
X146550Y-46304D01*
X146506Y-46344D01*
X146477Y-46377D01*
X146459Y-46402D01*
X146452Y-46406D01*
Y-46410D01*
X146404Y-46486D01*
X146368Y-46570D01*
X146343Y-46650D01*
X146328Y-46726D01*
X146317Y-46795D01*
X146313Y-46825D01*
Y-46850D01*
X146310Y-46868D01*
Y-46897D01*
X146313Y-46988D01*
X146328Y-47072D01*
X146350Y-47141D01*
X146372Y-47203D01*
X146397Y-47251D01*
X146415Y-47287D01*
X146430Y-47309D01*
X146437Y-47316D01*
X146492Y-47374D01*
X146554Y-47429D01*
X146619Y-47473D01*
X146685Y-47509D01*
X146743Y-47538D01*
X146772Y-47549D01*
X146794Y-47556D01*
X146812Y-47563D01*
X146827Y-47571D01*
X146834Y-47574D01*
X146838D01*
X146761Y-47902D01*
X146696Y-47880D01*
X146637Y-47858D01*
X146583Y-47829D01*
X146528Y-47804D01*
X146481Y-47775D01*
X146437Y-47742D01*
X146394Y-47713D01*
X146357Y-47684D01*
X146328Y-47655D01*
X146299Y-47629D01*
X146273Y-47604D01*
X146255Y-47585D01*
X146237Y-47567D01*
X146226Y-47553D01*
X146222Y-47545D01*
X146219Y-47542D01*
X146186Y-47491D01*
X146153Y-47440D01*
X146128Y-47389D01*
X146106Y-47334D01*
X146073Y-47225D01*
X146051Y-47127D01*
X146040Y-47079D01*
X146037Y-47039D01*
X146033Y-46999D01*
X146029Y-46967D01*
X146026Y-46941D01*
Y-46905D01*
X146033Y-46785D01*
X146051Y-46668D01*
X146073Y-46566D01*
X146088Y-46519D01*
X146102Y-46475D01*
X146117Y-46435D01*
X146131Y-46399D01*
X146142Y-46370D01*
X146153Y-46341D01*
X146164Y-46322D01*
X146171Y-46308D01*
X146175Y-46297D01*
X146179Y-46293D01*
X146241Y-46195D01*
X146313Y-46111D01*
X146386Y-46038D01*
X146459Y-45976D01*
X146525Y-45929D01*
X146554Y-45911D01*
X146579Y-45896D01*
X146597Y-45882D01*
X146612Y-45875D01*
X146623Y-45871D01*
X146626Y-45867D01*
X146739Y-45816D01*
X146856Y-45780D01*
X146972Y-45755D01*
X147078Y-45736D01*
X147125Y-45729D01*
X147172Y-45725D01*
X147209Y-45722D01*
X147245D01*
X147271Y-45718D01*
X147293D01*
X147307D01*
X147311D01*
X147442Y-45725D01*
D02*
G37*
G36*
X147984Y-49220D02*
X148588D01*
Y-49529D01*
X147984D01*
Y-49871D01*
X147700D01*
Y-49529D01*
X146070D01*
Y-49278D01*
X147700Y-48124D01*
X147984D01*
Y-49220D01*
D02*
G37*
G36*
X146969Y-50479D02*
X146943Y-50534D01*
X146918Y-50588D01*
X146892Y-50639D01*
X146870Y-50683D01*
X146852Y-50719D01*
X146838Y-50741D01*
X146834Y-50745D01*
Y-50749D01*
X146794Y-50814D01*
X146754Y-50872D01*
X146718Y-50923D01*
X146685Y-50963D01*
X146659Y-51000D01*
X146637Y-51022D01*
X146623Y-51040D01*
X146619Y-51043D01*
X148588D01*
Y-51353D01*
X146059D01*
Y-51153D01*
X146121Y-51116D01*
X146179Y-51076D01*
X146237Y-51029D01*
X146288Y-50985D01*
X146332Y-50941D01*
X146368Y-50909D01*
X146379Y-50894D01*
X146390Y-50883D01*
X146394Y-50880D01*
X146397Y-50876D01*
X146459Y-50800D01*
X146517Y-50723D01*
X146568Y-50650D01*
X146608Y-50577D01*
X146645Y-50516D01*
X146659Y-50490D01*
X146670Y-50468D01*
X146681Y-50450D01*
X146685Y-50436D01*
X146692Y-50428D01*
Y-50425D01*
X146991D01*
X146969Y-50479D01*
D02*
G37*
G36*
X614248Y-238586D02*
X614317Y-238594D01*
X614383Y-238601D01*
X614444Y-238615D01*
X614503Y-238634D01*
X614557Y-238652D01*
X614608Y-238670D01*
X614655Y-238692D01*
X614696Y-238710D01*
X614736Y-238728D01*
X614765Y-238747D01*
X614794Y-238765D01*
X614812Y-238779D01*
X614830Y-238787D01*
X614838Y-238794D01*
X614841Y-238797D01*
X614892Y-238841D01*
X614936Y-238885D01*
X614976Y-238936D01*
X615016Y-238987D01*
X615081Y-239089D01*
X615132Y-239191D01*
X615154Y-239238D01*
X615172Y-239282D01*
X615187Y-239322D01*
X615198Y-239354D01*
X615209Y-239383D01*
X615216Y-239405D01*
X615220Y-239420D01*
Y-239423D01*
X614885Y-239507D01*
X614870Y-239449D01*
X614852Y-239394D01*
X614834Y-239343D01*
X614816Y-239296D01*
X614794Y-239252D01*
X614772Y-239216D01*
X614747Y-239180D01*
X614725Y-239147D01*
X614707Y-239118D01*
X614685Y-239096D01*
X614667Y-239074D01*
X614652Y-239056D01*
X614637Y-239045D01*
X614626Y-239034D01*
X614623Y-239030D01*
X614619Y-239027D01*
X614583Y-238998D01*
X614543Y-238976D01*
X614463Y-238936D01*
X614386Y-238907D01*
X614310Y-238888D01*
X614244Y-238874D01*
X614219Y-238870D01*
X614193D01*
X614171Y-238867D01*
X614146D01*
X614062Y-238870D01*
X613982Y-238885D01*
X613909Y-238903D01*
X613844Y-238925D01*
X613793Y-238947D01*
X613771Y-238958D01*
X613753Y-238965D01*
X613738Y-238972D01*
X613727Y-238979D01*
X613720Y-238983D01*
X613716D01*
X613647Y-239034D01*
X613589Y-239089D01*
X613538Y-239151D01*
X613498Y-239209D01*
X613465Y-239260D01*
X613443Y-239303D01*
X613436Y-239322D01*
X613429Y-239333D01*
X613425Y-239340D01*
Y-239343D01*
X613396Y-239438D01*
X613374Y-239533D01*
X613356Y-239627D01*
X613345Y-239715D01*
X613342Y-239755D01*
X613338Y-239791D01*
Y-239824D01*
X613334Y-239849D01*
Y-239871D01*
Y-239889D01*
Y-239900D01*
Y-239904D01*
X613338Y-239999D01*
X613345Y-240086D01*
X613360Y-240166D01*
X613374Y-240239D01*
X613385Y-240301D01*
X613392Y-240326D01*
X613400Y-240348D01*
X613403Y-240366D01*
X613407Y-240377D01*
X613411Y-240385D01*
Y-240388D01*
X613447Y-240472D01*
X613487Y-240548D01*
X613531Y-240610D01*
X613578Y-240665D01*
X613618Y-240708D01*
X613651Y-240738D01*
X613676Y-240756D01*
X613680Y-240763D01*
X613684D01*
X613760Y-240810D01*
X613844Y-240847D01*
X613924Y-240872D01*
X614000Y-240887D01*
X614070Y-240898D01*
X614099Y-240901D01*
X614124D01*
X614142Y-240905D01*
X614171D01*
X614262Y-240901D01*
X614346Y-240887D01*
X614415Y-240865D01*
X614477Y-240843D01*
X614525Y-240818D01*
X614561Y-240799D01*
X614583Y-240785D01*
X614590Y-240778D01*
X614648Y-240723D01*
X614703Y-240661D01*
X614747Y-240596D01*
X614783Y-240530D01*
X614812Y-240472D01*
X614823Y-240443D01*
X614830Y-240421D01*
X614838Y-240403D01*
X614845Y-240388D01*
X614849Y-240381D01*
Y-240377D01*
X615176Y-240454D01*
X615154Y-240519D01*
X615132Y-240577D01*
X615103Y-240632D01*
X615078Y-240687D01*
X615049Y-240734D01*
X615016Y-240778D01*
X614987Y-240821D01*
X614958Y-240858D01*
X614928Y-240887D01*
X614903Y-240916D01*
X614878Y-240941D01*
X614859Y-240960D01*
X614841Y-240978D01*
X614827Y-240989D01*
X614819Y-240992D01*
X614816Y-240996D01*
X614765Y-241029D01*
X614714Y-241061D01*
X614663Y-241087D01*
X614608Y-241109D01*
X614499Y-241142D01*
X614401Y-241163D01*
X614353Y-241174D01*
X614313Y-241178D01*
X614273Y-241182D01*
X614241Y-241185D01*
X614215Y-241189D01*
X614179D01*
X614059Y-241182D01*
X613942Y-241163D01*
X613840Y-241142D01*
X613793Y-241127D01*
X613749Y-241112D01*
X613709Y-241098D01*
X613673Y-241083D01*
X613644Y-241072D01*
X613615Y-241061D01*
X613596Y-241051D01*
X613582Y-241043D01*
X613571Y-241040D01*
X613567Y-241036D01*
X613469Y-240974D01*
X613385Y-240901D01*
X613312Y-240828D01*
X613250Y-240756D01*
X613203Y-240690D01*
X613185Y-240661D01*
X613170Y-240636D01*
X613156Y-240617D01*
X613149Y-240603D01*
X613145Y-240592D01*
X613141Y-240588D01*
X613090Y-240476D01*
X613054Y-240359D01*
X613028Y-240243D01*
X613010Y-240137D01*
X613003Y-240090D01*
X612999Y-240042D01*
X612996Y-240006D01*
Y-239969D01*
X612992Y-239944D01*
Y-239922D01*
Y-239908D01*
Y-239904D01*
X612999Y-239773D01*
X613014Y-239646D01*
X613032Y-239533D01*
X613047Y-239478D01*
X613058Y-239431D01*
X613068Y-239387D01*
X613083Y-239347D01*
X613094Y-239311D01*
X613101Y-239282D01*
X613112Y-239260D01*
X613116Y-239242D01*
X613123Y-239231D01*
Y-239227D01*
X613178Y-239118D01*
X613240Y-239019D01*
X613305Y-238936D01*
X613338Y-238903D01*
X613367Y-238870D01*
X613396Y-238841D01*
X613425Y-238816D01*
X613451Y-238794D01*
X613473Y-238779D01*
X613487Y-238765D01*
X613502Y-238754D01*
X613509Y-238750D01*
X613513Y-238747D01*
X613563Y-238717D01*
X613615Y-238692D01*
X613724Y-238652D01*
X613833Y-238623D01*
X613939Y-238604D01*
X613989Y-238597D01*
X614033Y-238590D01*
X614073Y-238586D01*
X614106D01*
X614135Y-238583D01*
X614175D01*
X614248Y-238586D01*
D02*
G37*
G36*
X616359Y-238590D02*
X616450Y-238604D01*
X616534Y-238630D01*
X616603Y-238659D01*
X616632Y-238670D01*
X616661Y-238685D01*
X616683Y-238699D01*
X616705Y-238710D01*
X616719Y-238717D01*
X616730Y-238725D01*
X616738Y-238732D01*
X616741D01*
X616814Y-238794D01*
X616880Y-238863D01*
X616930Y-238936D01*
X616974Y-239005D01*
X617011Y-239067D01*
X617025Y-239096D01*
X617036Y-239118D01*
X617043Y-239140D01*
X617051Y-239154D01*
X617054Y-239161D01*
Y-239165D01*
X617072Y-239220D01*
X617091Y-239282D01*
X617116Y-239405D01*
X617134Y-239536D01*
X617145Y-239660D01*
X617153Y-239715D01*
X617156Y-239769D01*
Y-239817D01*
X617160Y-239857D01*
Y-239889D01*
Y-239915D01*
Y-239933D01*
Y-239937D01*
Y-240020D01*
X617156Y-240101D01*
X617149Y-240173D01*
X617142Y-240243D01*
X617134Y-240304D01*
X617127Y-240363D01*
X617116Y-240417D01*
X617105Y-240464D01*
X617094Y-240505D01*
X617087Y-240541D01*
X617076Y-240574D01*
X617069Y-240599D01*
X617062Y-240617D01*
X617054Y-240632D01*
X617051Y-240639D01*
Y-240643D01*
X617007Y-240730D01*
X616960Y-240807D01*
X616905Y-240872D01*
X616858Y-240927D01*
X616810Y-240967D01*
X616774Y-240996D01*
X616759Y-241007D01*
X616749Y-241014D01*
X616745Y-241021D01*
X616741D01*
X616665Y-241065D01*
X616588Y-241098D01*
X616512Y-241123D01*
X616443Y-241138D01*
X616381Y-241149D01*
X616355Y-241153D01*
X616337D01*
X616319Y-241156D01*
X616293D01*
X616232Y-241153D01*
X616173Y-241145D01*
X616115Y-241134D01*
X616064Y-241120D01*
X615966Y-241080D01*
X615922Y-241061D01*
X615886Y-241040D01*
X615849Y-241014D01*
X615820Y-240996D01*
X615791Y-240974D01*
X615769Y-240956D01*
X615751Y-240941D01*
X615740Y-240931D01*
X615733Y-240923D01*
X615729Y-240919D01*
X615689Y-240876D01*
X615657Y-240825D01*
X615624Y-240778D01*
X615598Y-240727D01*
X615577Y-240672D01*
X615558Y-240621D01*
X615533Y-240526D01*
X615522Y-240479D01*
X615515Y-240439D01*
X615511Y-240399D01*
X615507Y-240366D01*
X615504Y-240341D01*
Y-240323D01*
Y-240308D01*
Y-240304D01*
X615507Y-240235D01*
X615515Y-240173D01*
X615522Y-240111D01*
X615536Y-240053D01*
X615555Y-240002D01*
X615573Y-239951D01*
X615591Y-239908D01*
X615613Y-239868D01*
X615631Y-239831D01*
X615649Y-239798D01*
X615667Y-239773D01*
X615686Y-239747D01*
X615700Y-239729D01*
X615707Y-239718D01*
X615715Y-239711D01*
X615718Y-239707D01*
X615759Y-239667D01*
X615802Y-239635D01*
X615846Y-239602D01*
X615893Y-239576D01*
X615937Y-239555D01*
X615980Y-239536D01*
X616064Y-239511D01*
X616101Y-239500D01*
X616137Y-239493D01*
X616166Y-239489D01*
X616195Y-239485D01*
X616217Y-239482D01*
X616246D01*
X616315Y-239485D01*
X616381Y-239496D01*
X616439Y-239511D01*
X616494Y-239529D01*
X616534Y-239544D01*
X616567Y-239558D01*
X616588Y-239569D01*
X616596Y-239573D01*
X616654Y-239609D01*
X616705Y-239649D01*
X616749Y-239689D01*
X616785Y-239726D01*
X616810Y-239762D01*
X616832Y-239788D01*
X616847Y-239806D01*
X616851Y-239813D01*
Y-239784D01*
Y-239766D01*
Y-239755D01*
Y-239751D01*
X616847Y-239678D01*
X616843Y-239609D01*
X616836Y-239547D01*
X616829Y-239489D01*
X616818Y-239442D01*
X616810Y-239405D01*
X616807Y-239391D01*
Y-239380D01*
X616803Y-239376D01*
Y-239372D01*
X616785Y-239307D01*
X616767Y-239249D01*
X616749Y-239198D01*
X616730Y-239154D01*
X616716Y-239121D01*
X616701Y-239096D01*
X616694Y-239078D01*
X616690Y-239074D01*
X616661Y-239034D01*
X616632Y-239001D01*
X616603Y-238972D01*
X616574Y-238947D01*
X616552Y-238925D01*
X616530Y-238910D01*
X616516Y-238903D01*
X616512Y-238899D01*
X616472Y-238878D01*
X616428Y-238863D01*
X616388Y-238852D01*
X616348Y-238845D01*
X616315Y-238841D01*
X616290Y-238837D01*
X616264D01*
X616206Y-238841D01*
X616152Y-238852D01*
X616104Y-238867D01*
X616064Y-238885D01*
X616035Y-238899D01*
X616010Y-238914D01*
X615995Y-238925D01*
X615991Y-238929D01*
X615955Y-238968D01*
X615926Y-239016D01*
X615900Y-239067D01*
X615882Y-239118D01*
X615868Y-239161D01*
X615857Y-239201D01*
X615853Y-239216D01*
Y-239223D01*
X615849Y-239231D01*
Y-239234D01*
X615551Y-239209D01*
X615573Y-239103D01*
X615602Y-239012D01*
X615638Y-238932D01*
X615675Y-238867D01*
X615711Y-238816D01*
X615729Y-238794D01*
X615744Y-238776D01*
X615755Y-238765D01*
X615766Y-238754D01*
X615769Y-238750D01*
X615773Y-238747D01*
X615809Y-238717D01*
X615849Y-238692D01*
X615930Y-238652D01*
X616010Y-238623D01*
X616086Y-238604D01*
X616155Y-238590D01*
X616184Y-238586D01*
X616210D01*
X616228Y-238583D01*
X616257D01*
X616359Y-238590D01*
D02*
G37*
G36*
X618332Y-238586D02*
X618394Y-238594D01*
X618456Y-238604D01*
X618514Y-238619D01*
X618569Y-238637D01*
X618616Y-238655D01*
X618663Y-238677D01*
X618703Y-238699D01*
X618743Y-238717D01*
X618776Y-238739D01*
X618805Y-238757D01*
X618827Y-238776D01*
X618845Y-238790D01*
X618860Y-238801D01*
X618867Y-238808D01*
X618871Y-238812D01*
X618914Y-238856D01*
X618951Y-238903D01*
X618984Y-238950D01*
X619013Y-238998D01*
X619034Y-239041D01*
X619056Y-239089D01*
X619085Y-239176D01*
X619093Y-239216D01*
X619100Y-239252D01*
X619107Y-239285D01*
X619111Y-239314D01*
X619114Y-239336D01*
Y-239354D01*
Y-239365D01*
Y-239369D01*
X619111Y-239456D01*
X619096Y-239536D01*
X619074Y-239605D01*
X619053Y-239664D01*
X619031Y-239711D01*
X619009Y-239747D01*
X618994Y-239769D01*
X618991Y-239777D01*
X618940Y-239831D01*
X618885Y-239879D01*
X618827Y-239915D01*
X618769Y-239944D01*
X618718Y-239966D01*
X618678Y-239980D01*
X618663Y-239984D01*
X618652Y-239988D01*
X618645Y-239991D01*
X618641D01*
X618703Y-240024D01*
X618754Y-240057D01*
X618798Y-240093D01*
X618834Y-240126D01*
X618863Y-240155D01*
X618885Y-240181D01*
X618896Y-240195D01*
X618900Y-240202D01*
X618929Y-240253D01*
X618951Y-240304D01*
X618969Y-240355D01*
X618980Y-240403D01*
X618987Y-240443D01*
X618991Y-240472D01*
Y-240494D01*
Y-240501D01*
X618987Y-240563D01*
X618976Y-240625D01*
X618962Y-240679D01*
X618944Y-240727D01*
X618925Y-240767D01*
X618911Y-240799D01*
X618900Y-240818D01*
X618896Y-240825D01*
X618860Y-240880D01*
X618816Y-240927D01*
X618772Y-240967D01*
X618729Y-241003D01*
X618692Y-241029D01*
X618659Y-241051D01*
X618638Y-241061D01*
X618634Y-241065D01*
X618630D01*
X618565Y-241094D01*
X618499Y-241116D01*
X618434Y-241134D01*
X618376Y-241145D01*
X618328Y-241153D01*
X618288Y-241156D01*
X618197D01*
X618146Y-241149D01*
X618048Y-241131D01*
X617964Y-241102D01*
X617892Y-241072D01*
X617859Y-241054D01*
X617833Y-241040D01*
X617808Y-241025D01*
X617790Y-241010D01*
X617775Y-241000D01*
X617764Y-240992D01*
X617757Y-240989D01*
X617753Y-240985D01*
X617684Y-240916D01*
X617629Y-240839D01*
X617586Y-240759D01*
X617549Y-240679D01*
X617527Y-240610D01*
X617517Y-240581D01*
X617509Y-240556D01*
X617506Y-240534D01*
X617502Y-240519D01*
X617498Y-240508D01*
Y-240505D01*
X617808Y-240450D01*
X617822Y-240530D01*
X617844Y-240599D01*
X617870Y-240657D01*
X617895Y-240705D01*
X617921Y-240741D01*
X617942Y-240767D01*
X617957Y-240785D01*
X617961Y-240789D01*
X618008Y-240825D01*
X618059Y-240854D01*
X618106Y-240872D01*
X618154Y-240887D01*
X618197Y-240894D01*
X618230Y-240901D01*
X618259D01*
X618325Y-240898D01*
X618383Y-240883D01*
X618434Y-240865D01*
X618477Y-240847D01*
X618510Y-240825D01*
X618536Y-240807D01*
X618554Y-240792D01*
X618558Y-240789D01*
X618598Y-240745D01*
X618627Y-240698D01*
X618645Y-240650D01*
X618659Y-240606D01*
X618667Y-240566D01*
X618674Y-240537D01*
Y-240515D01*
Y-240512D01*
Y-240508D01*
Y-240468D01*
X618667Y-240432D01*
X618649Y-240370D01*
X618623Y-240315D01*
X618594Y-240268D01*
X618565Y-240235D01*
X618539Y-240210D01*
X618521Y-240195D01*
X618518Y-240192D01*
X618514D01*
X618452Y-240159D01*
X618394Y-240133D01*
X618332Y-240115D01*
X618277Y-240104D01*
X618230Y-240097D01*
X618190Y-240090D01*
X618143D01*
X618128Y-240093D01*
X618110D01*
X618074Y-239820D01*
X618121Y-239831D01*
X618164Y-239839D01*
X618201Y-239846D01*
X618234Y-239849D01*
X618259Y-239853D01*
X618292D01*
X618368Y-239846D01*
X618437Y-239831D01*
X618499Y-239809D01*
X618550Y-239784D01*
X618590Y-239758D01*
X618619Y-239737D01*
X618638Y-239722D01*
X618645Y-239715D01*
X618692Y-239660D01*
X618729Y-239602D01*
X618754Y-239544D01*
X618769Y-239485D01*
X618780Y-239438D01*
X618783Y-239398D01*
X618787Y-239383D01*
Y-239372D01*
Y-239365D01*
Y-239362D01*
X618780Y-239282D01*
X618761Y-239209D01*
X618740Y-239147D01*
X618711Y-239092D01*
X618681Y-239049D01*
X618659Y-239016D01*
X618641Y-238994D01*
X618634Y-238987D01*
X618576Y-238936D01*
X618514Y-238899D01*
X618452Y-238874D01*
X618394Y-238856D01*
X618343Y-238845D01*
X618303Y-238841D01*
X618288Y-238837D01*
X618266D01*
X618201Y-238841D01*
X618139Y-238856D01*
X618084Y-238874D01*
X618041Y-238896D01*
X618004Y-238914D01*
X617975Y-238932D01*
X617961Y-238947D01*
X617953Y-238950D01*
X617910Y-239001D01*
X617873Y-239059D01*
X617840Y-239121D01*
X617815Y-239187D01*
X617797Y-239242D01*
X617790Y-239267D01*
X617786Y-239289D01*
X617782Y-239307D01*
X617779Y-239322D01*
X617775Y-239329D01*
Y-239333D01*
X617466Y-239293D01*
X617473Y-239234D01*
X617484Y-239180D01*
X617517Y-239078D01*
X617557Y-238990D01*
X617579Y-238954D01*
X617600Y-238917D01*
X617622Y-238885D01*
X617644Y-238859D01*
X617662Y-238834D01*
X617680Y-238816D01*
X617691Y-238801D01*
X617702Y-238790D01*
X617709Y-238783D01*
X617713Y-238779D01*
X617757Y-238747D01*
X617801Y-238714D01*
X617844Y-238688D01*
X617892Y-238666D01*
X617982Y-238630D01*
X618070Y-238608D01*
X618110Y-238601D01*
X618146Y-238594D01*
X618179Y-238590D01*
X618208Y-238586D01*
X618230Y-238583D01*
X618263D01*
X618332Y-238586D01*
D02*
G37*
G36*
X615582Y-231106D02*
X615651Y-231113D01*
X615716Y-231120D01*
X615778Y-231135D01*
X615836Y-231153D01*
X615891Y-231171D01*
X615942Y-231190D01*
X615989Y-231211D01*
X616029Y-231230D01*
X616069Y-231248D01*
X616098Y-231266D01*
X616128Y-231284D01*
X616146Y-231299D01*
X616164Y-231306D01*
X616171Y-231313D01*
X616175Y-231317D01*
X616226Y-231361D01*
X616269Y-231404D01*
X616310Y-231455D01*
X616350Y-231506D01*
X616415Y-231608D01*
X616466Y-231710D01*
X616488Y-231757D01*
X616506Y-231801D01*
X616521Y-231841D01*
X616532Y-231874D01*
X616543Y-231903D01*
X616550Y-231925D01*
X616553Y-231940D01*
Y-231943D01*
X616219Y-232027D01*
X616204Y-231969D01*
X616186Y-231914D01*
X616168Y-231863D01*
X616149Y-231816D01*
X616128Y-231772D01*
X616106Y-231736D01*
X616080Y-231699D01*
X616058Y-231666D01*
X616040Y-231637D01*
X616018Y-231616D01*
X616000Y-231594D01*
X615986Y-231575D01*
X615971Y-231565D01*
X615960Y-231554D01*
X615956Y-231550D01*
X615953Y-231546D01*
X615916Y-231517D01*
X615876Y-231495D01*
X615796Y-231455D01*
X615720Y-231426D01*
X615644Y-231408D01*
X615578Y-231394D01*
X615553Y-231390D01*
X615527D01*
X615505Y-231386D01*
X615480D01*
X615396Y-231390D01*
X615316Y-231404D01*
X615243Y-231423D01*
X615177Y-231445D01*
X615127Y-231466D01*
X615105Y-231477D01*
X615087Y-231485D01*
X615072Y-231492D01*
X615061Y-231499D01*
X615054Y-231503D01*
X615050D01*
X614981Y-231554D01*
X614923Y-231608D01*
X614872Y-231670D01*
X614832Y-231728D01*
X614799Y-231779D01*
X614777Y-231823D01*
X614770Y-231841D01*
X614763Y-231852D01*
X614759Y-231859D01*
Y-231863D01*
X614730Y-231958D01*
X614708Y-232052D01*
X614690Y-232147D01*
X614679Y-232234D01*
X614675Y-232274D01*
X614672Y-232311D01*
Y-232344D01*
X614668Y-232369D01*
Y-232391D01*
Y-232409D01*
Y-232420D01*
Y-232424D01*
X614672Y-232518D01*
X614679Y-232606D01*
X614693Y-232686D01*
X614708Y-232758D01*
X614719Y-232820D01*
X614726Y-232846D01*
X614734Y-232868D01*
X614737Y-232886D01*
X614741Y-232897D01*
X614744Y-232904D01*
Y-232908D01*
X614781Y-232992D01*
X614821Y-233068D01*
X614864Y-233130D01*
X614912Y-233184D01*
X614952Y-233228D01*
X614985Y-233257D01*
X615010Y-233275D01*
X615014Y-233283D01*
X615017D01*
X615094Y-233330D01*
X615177Y-233366D01*
X615258Y-233392D01*
X615334Y-233406D01*
X615403Y-233417D01*
X615432Y-233421D01*
X615458D01*
X615476Y-233425D01*
X615505D01*
X615596Y-233421D01*
X615680Y-233406D01*
X615749Y-233385D01*
X615811Y-233363D01*
X615858Y-233337D01*
X615895Y-233319D01*
X615916Y-233305D01*
X615924Y-233297D01*
X615982Y-233243D01*
X616037Y-233181D01*
X616080Y-233115D01*
X616117Y-233050D01*
X616146Y-232992D01*
X616157Y-232962D01*
X616164Y-232941D01*
X616171Y-232922D01*
X616179Y-232908D01*
X616182Y-232901D01*
Y-232897D01*
X616510Y-232973D01*
X616488Y-233039D01*
X616466Y-233097D01*
X616437Y-233152D01*
X616411Y-233206D01*
X616382Y-233254D01*
X616350Y-233297D01*
X616321Y-233341D01*
X616291Y-233377D01*
X616262Y-233406D01*
X616237Y-233436D01*
X616211Y-233461D01*
X616193Y-233479D01*
X616175Y-233497D01*
X616160Y-233508D01*
X616153Y-233512D01*
X616149Y-233516D01*
X616098Y-233548D01*
X616047Y-233581D01*
X615997Y-233607D01*
X615942Y-233629D01*
X615833Y-233661D01*
X615734Y-233683D01*
X615687Y-233694D01*
X615647Y-233698D01*
X615607Y-233701D01*
X615574Y-233705D01*
X615549Y-233709D01*
X615512D01*
X615392Y-233701D01*
X615276Y-233683D01*
X615174Y-233661D01*
X615127Y-233647D01*
X615083Y-233632D01*
X615043Y-233618D01*
X615006Y-233603D01*
X614977Y-233592D01*
X614948Y-233581D01*
X614930Y-233570D01*
X614916Y-233563D01*
X614905Y-233559D01*
X614901Y-233556D01*
X614803Y-233494D01*
X614719Y-233421D01*
X614646Y-233348D01*
X614584Y-233275D01*
X614537Y-233210D01*
X614519Y-233181D01*
X614504Y-233155D01*
X614490Y-233137D01*
X614482Y-233122D01*
X614479Y-233112D01*
X614475Y-233108D01*
X614424Y-232995D01*
X614388Y-232879D01*
X614362Y-232762D01*
X614344Y-232657D01*
X614337Y-232609D01*
X614333Y-232562D01*
X614329Y-232526D01*
Y-232489D01*
X614326Y-232464D01*
Y-232442D01*
Y-232427D01*
Y-232424D01*
X614333Y-232293D01*
X614348Y-232165D01*
X614366Y-232052D01*
X614380Y-231998D01*
X614391Y-231950D01*
X614402Y-231907D01*
X614417Y-231867D01*
X614428Y-231830D01*
X614435Y-231801D01*
X614446Y-231779D01*
X614450Y-231761D01*
X614457Y-231750D01*
Y-231747D01*
X614511Y-231637D01*
X614573Y-231539D01*
X614639Y-231455D01*
X614672Y-231423D01*
X614701Y-231390D01*
X614730Y-231361D01*
X614759Y-231335D01*
X614784Y-231313D01*
X614806Y-231299D01*
X614821Y-231284D01*
X614835Y-231273D01*
X614843Y-231270D01*
X614846Y-231266D01*
X614897Y-231237D01*
X614948Y-231211D01*
X615057Y-231171D01*
X615167Y-231142D01*
X615272Y-231124D01*
X615323Y-231117D01*
X615367Y-231110D01*
X615407Y-231106D01*
X615440D01*
X615469Y-231102D01*
X615509D01*
X615582Y-231106D01*
D02*
G37*
G36*
X617693Y-231110D02*
X617784Y-231124D01*
X617868Y-231150D01*
X617937Y-231179D01*
X617966Y-231190D01*
X617995Y-231204D01*
X618017Y-231219D01*
X618039Y-231230D01*
X618053Y-231237D01*
X618064Y-231244D01*
X618071Y-231252D01*
X618075D01*
X618148Y-231313D01*
X618213Y-231383D01*
X618264Y-231455D01*
X618308Y-231525D01*
X618344Y-231587D01*
X618359Y-231616D01*
X618370Y-231637D01*
X618377Y-231659D01*
X618384Y-231674D01*
X618388Y-231681D01*
Y-231685D01*
X618406Y-231739D01*
X618424Y-231801D01*
X618450Y-231925D01*
X618468Y-232056D01*
X618479Y-232180D01*
X618486Y-232234D01*
X618490Y-232289D01*
Y-232336D01*
X618494Y-232376D01*
Y-232409D01*
Y-232435D01*
Y-232453D01*
Y-232456D01*
Y-232540D01*
X618490Y-232620D01*
X618483Y-232693D01*
X618475Y-232762D01*
X618468Y-232824D01*
X618461Y-232882D01*
X618450Y-232937D01*
X618439Y-232984D01*
X618428Y-233024D01*
X618421Y-233061D01*
X618410Y-233093D01*
X618403Y-233119D01*
X618395Y-233137D01*
X618388Y-233152D01*
X618384Y-233159D01*
Y-233163D01*
X618341Y-233250D01*
X618293Y-233326D01*
X618239Y-233392D01*
X618191Y-233447D01*
X618144Y-233487D01*
X618108Y-233516D01*
X618093Y-233527D01*
X618082Y-233534D01*
X618079Y-233541D01*
X618075D01*
X617999Y-233585D01*
X617922Y-233618D01*
X617846Y-233643D01*
X617776Y-233658D01*
X617715Y-233668D01*
X617689Y-233672D01*
X617671D01*
X617653Y-233676D01*
X617627D01*
X617565Y-233672D01*
X617507Y-233665D01*
X617449Y-233654D01*
X617398Y-233639D01*
X617300Y-233599D01*
X617256Y-233581D01*
X617220Y-233559D01*
X617183Y-233534D01*
X617154Y-233516D01*
X617125Y-233494D01*
X617103Y-233476D01*
X617085Y-233461D01*
X617074Y-233450D01*
X617067Y-233443D01*
X617063Y-233439D01*
X617023Y-233396D01*
X616990Y-233345D01*
X616958Y-233297D01*
X616932Y-233246D01*
X616910Y-233192D01*
X616892Y-233141D01*
X616866Y-233046D01*
X616856Y-232999D01*
X616848Y-232959D01*
X616845Y-232919D01*
X616841Y-232886D01*
X616837Y-232860D01*
Y-232842D01*
Y-232828D01*
Y-232824D01*
X616841Y-232755D01*
X616848Y-232693D01*
X616856Y-232631D01*
X616870Y-232573D01*
X616888Y-232522D01*
X616906Y-232471D01*
X616925Y-232427D01*
X616947Y-232387D01*
X616965Y-232351D01*
X616983Y-232318D01*
X617001Y-232293D01*
X617019Y-232267D01*
X617034Y-232249D01*
X617041Y-232238D01*
X617049Y-232231D01*
X617052Y-232227D01*
X617092Y-232187D01*
X617136Y-232154D01*
X617180Y-232121D01*
X617227Y-232096D01*
X617271Y-232074D01*
X617314Y-232056D01*
X617398Y-232031D01*
X617434Y-232020D01*
X617471Y-232012D01*
X617500Y-232009D01*
X617529Y-232005D01*
X617551Y-232001D01*
X617580D01*
X617649Y-232005D01*
X617715Y-232016D01*
X617773Y-232031D01*
X617828Y-232049D01*
X617868Y-232063D01*
X617900Y-232078D01*
X617922Y-232089D01*
X617929Y-232092D01*
X617988Y-232129D01*
X618039Y-232169D01*
X618082Y-232209D01*
X618119Y-232245D01*
X618144Y-232282D01*
X618166Y-232307D01*
X618181Y-232325D01*
X618184Y-232333D01*
Y-232304D01*
Y-232285D01*
Y-232274D01*
Y-232271D01*
X618181Y-232198D01*
X618177Y-232129D01*
X618170Y-232067D01*
X618162Y-232009D01*
X618151Y-231961D01*
X618144Y-231925D01*
X618141Y-231910D01*
Y-231899D01*
X618137Y-231896D01*
Y-231892D01*
X618119Y-231827D01*
X618101Y-231768D01*
X618082Y-231717D01*
X618064Y-231674D01*
X618049Y-231641D01*
X618035Y-231616D01*
X618028Y-231597D01*
X618024Y-231594D01*
X617995Y-231554D01*
X617966Y-231521D01*
X617937Y-231492D01*
X617907Y-231466D01*
X617886Y-231445D01*
X617864Y-231430D01*
X617849Y-231423D01*
X617846Y-231419D01*
X617806Y-231397D01*
X617762Y-231383D01*
X617722Y-231372D01*
X617682Y-231364D01*
X617649Y-231361D01*
X617624Y-231357D01*
X617598D01*
X617540Y-231361D01*
X617485Y-231372D01*
X617438Y-231386D01*
X617398Y-231404D01*
X617369Y-231419D01*
X617343Y-231434D01*
X617329Y-231445D01*
X617325Y-231448D01*
X617289Y-231488D01*
X617260Y-231536D01*
X617234Y-231587D01*
X617216Y-231637D01*
X617201Y-231681D01*
X617191Y-231721D01*
X617187Y-231736D01*
Y-231743D01*
X617183Y-231750D01*
Y-231754D01*
X616885Y-231728D01*
X616906Y-231623D01*
X616936Y-231532D01*
X616972Y-231452D01*
X617008Y-231386D01*
X617045Y-231335D01*
X617063Y-231313D01*
X617078Y-231295D01*
X617089Y-231284D01*
X617100Y-231273D01*
X617103Y-231270D01*
X617107Y-231266D01*
X617143Y-231237D01*
X617183Y-231211D01*
X617263Y-231171D01*
X617343Y-231142D01*
X617420Y-231124D01*
X617489Y-231110D01*
X617518Y-231106D01*
X617544D01*
X617562Y-231102D01*
X617591D01*
X617693Y-231110D01*
D02*
G37*
G36*
X620423Y-231445D02*
X619181D01*
X619225Y-231506D01*
X619247Y-231532D01*
X619265Y-231557D01*
X619283Y-231579D01*
X619298Y-231594D01*
X619309Y-231605D01*
X619313Y-231608D01*
X619331Y-231627D01*
X619353Y-231645D01*
X619404Y-231692D01*
X619462Y-231747D01*
X619524Y-231801D01*
X619582Y-231849D01*
X619607Y-231870D01*
X619629Y-231892D01*
X619648Y-231907D01*
X619662Y-231918D01*
X619669Y-231925D01*
X619673Y-231929D01*
X619731Y-231980D01*
X619789Y-232027D01*
X619840Y-232074D01*
X619888Y-232114D01*
X619931Y-232154D01*
X619968Y-232191D01*
X620004Y-232224D01*
X620033Y-232253D01*
X620062Y-232282D01*
X620084Y-232304D01*
X620103Y-232322D01*
X620121Y-232340D01*
X620139Y-232362D01*
X620146Y-232369D01*
X620197Y-232431D01*
X620241Y-232486D01*
X620277Y-232540D01*
X620306Y-232584D01*
X620328Y-232624D01*
X620343Y-232653D01*
X620350Y-232671D01*
X620354Y-232679D01*
X620375Y-232733D01*
X620390Y-232788D01*
X620405Y-232839D01*
X620412Y-232882D01*
X620415Y-232922D01*
X620419Y-232951D01*
Y-232970D01*
Y-232977D01*
X620415Y-233032D01*
X620408Y-233083D01*
X620401Y-233133D01*
X620386Y-233177D01*
X620350Y-233264D01*
X620314Y-233334D01*
X620292Y-233366D01*
X620273Y-233392D01*
X620255Y-233417D01*
X620237Y-233436D01*
X620223Y-233450D01*
X620215Y-233465D01*
X620208Y-233468D01*
X620204Y-233472D01*
X620164Y-233508D01*
X620121Y-233541D01*
X620073Y-233567D01*
X620026Y-233589D01*
X619931Y-233625D01*
X619837Y-233650D01*
X619797Y-233658D01*
X619757Y-233665D01*
X619720Y-233668D01*
X619691Y-233672D01*
X619666Y-233676D01*
X619629D01*
X619564Y-233672D01*
X619502Y-233668D01*
X619444Y-233658D01*
X619389Y-233647D01*
X619338Y-233632D01*
X619291Y-233618D01*
X619247Y-233599D01*
X619207Y-233581D01*
X619171Y-233563D01*
X619141Y-233545D01*
X619116Y-233530D01*
X619094Y-233516D01*
X619076Y-233505D01*
X619065Y-233494D01*
X619058Y-233490D01*
X619054Y-233487D01*
X619018Y-233450D01*
X618985Y-233410D01*
X618952Y-233366D01*
X618927Y-233323D01*
X618883Y-233235D01*
X618854Y-233148D01*
X618843Y-233108D01*
X618832Y-233068D01*
X618825Y-233035D01*
X618818Y-233006D01*
X618814Y-232981D01*
Y-232962D01*
X618810Y-232951D01*
Y-232948D01*
X619127Y-232915D01*
X619134Y-232999D01*
X619149Y-233072D01*
X619171Y-233137D01*
X619196Y-233188D01*
X619218Y-233232D01*
X619240Y-233261D01*
X619254Y-233279D01*
X619262Y-233286D01*
X619316Y-233330D01*
X619375Y-233363D01*
X619436Y-233388D01*
X619491Y-233403D01*
X619542Y-233414D01*
X619586Y-233417D01*
X619600Y-233421D01*
X619622D01*
X619698Y-233417D01*
X619768Y-233403D01*
X619826Y-233381D01*
X619877Y-233359D01*
X619917Y-233334D01*
X619942Y-233315D01*
X619960Y-233301D01*
X619968Y-233294D01*
X620012Y-233243D01*
X620044Y-233192D01*
X620070Y-233141D01*
X620084Y-233090D01*
X620095Y-233050D01*
X620099Y-233013D01*
X620103Y-232992D01*
Y-232988D01*
Y-232984D01*
X620095Y-232919D01*
X620081Y-232850D01*
X620055Y-232788D01*
X620030Y-232729D01*
X620001Y-232682D01*
X619975Y-232642D01*
X619968Y-232628D01*
X619960Y-232617D01*
X619953Y-232613D01*
Y-232609D01*
X619924Y-232569D01*
X619888Y-232529D01*
X619848Y-232486D01*
X619804Y-232442D01*
X619713Y-232354D01*
X619622Y-232267D01*
X619575Y-232227D01*
X619535Y-232191D01*
X619495Y-232158D01*
X619462Y-232129D01*
X619436Y-232107D01*
X619415Y-232089D01*
X619400Y-232078D01*
X619396Y-232074D01*
X619305Y-231998D01*
X619222Y-231925D01*
X619152Y-231859D01*
X619098Y-231805D01*
X619051Y-231757D01*
X619018Y-231725D01*
X618999Y-231703D01*
X618992Y-231699D01*
Y-231696D01*
X618941Y-231634D01*
X618901Y-231575D01*
X618865Y-231517D01*
X618836Y-231466D01*
X618814Y-231423D01*
X618799Y-231390D01*
X618792Y-231368D01*
X618788Y-231364D01*
Y-231361D01*
X618774Y-231321D01*
X618767Y-231284D01*
X618759Y-231248D01*
X618756Y-231215D01*
X618752Y-231186D01*
Y-231164D01*
Y-231150D01*
Y-231146D01*
X620423D01*
Y-231445D01*
D02*
G37*
G36*
X615527Y-302018D02*
X615597Y-302026D01*
X615662Y-302033D01*
X615724Y-302048D01*
X615782Y-302066D01*
X615837Y-302084D01*
X615888Y-302102D01*
X615935Y-302124D01*
X615975Y-302142D01*
X616015Y-302160D01*
X616044Y-302179D01*
X616073Y-302197D01*
X616092Y-302211D01*
X616110Y-302219D01*
X616117Y-302226D01*
X616121Y-302230D01*
X616172Y-302273D01*
X616215Y-302317D01*
X616255Y-302368D01*
X616295Y-302419D01*
X616361Y-302521D01*
X616412Y-302623D01*
X616434Y-302670D01*
X616452Y-302714D01*
X616467Y-302754D01*
X616477Y-302786D01*
X616488Y-302816D01*
X616496Y-302837D01*
X616499Y-302852D01*
Y-302856D01*
X616164Y-302939D01*
X616150Y-302881D01*
X616132Y-302826D01*
X616114Y-302776D01*
X616095Y-302728D01*
X616073Y-302685D01*
X616052Y-302648D01*
X616026Y-302612D01*
X616004Y-302579D01*
X615986Y-302550D01*
X615964Y-302528D01*
X615946Y-302506D01*
X615932Y-302488D01*
X615917Y-302477D01*
X615906Y-302466D01*
X615902Y-302463D01*
X615899Y-302459D01*
X615862Y-302430D01*
X615822Y-302408D01*
X615742Y-302368D01*
X615666Y-302339D01*
X615589Y-302321D01*
X615524Y-302306D01*
X615498Y-302302D01*
X615473D01*
X615451Y-302299D01*
X615425D01*
X615342Y-302302D01*
X615262Y-302317D01*
X615189Y-302335D01*
X615123Y-302357D01*
X615072Y-302379D01*
X615051Y-302390D01*
X615032Y-302397D01*
X615018Y-302404D01*
X615007Y-302412D01*
X615000Y-302415D01*
X614996D01*
X614927Y-302466D01*
X614869Y-302521D01*
X614818Y-302583D01*
X614778Y-302641D01*
X614745Y-302692D01*
X614723Y-302735D01*
X614716Y-302754D01*
X614708Y-302765D01*
X614705Y-302772D01*
Y-302776D01*
X614676Y-302870D01*
X614654Y-302965D01*
X614636Y-303060D01*
X614625Y-303147D01*
X614621Y-303187D01*
X614617Y-303223D01*
Y-303256D01*
X614614Y-303281D01*
Y-303303D01*
Y-303322D01*
Y-303332D01*
Y-303336D01*
X614617Y-303431D01*
X614625Y-303518D01*
X614639Y-303598D01*
X614654Y-303671D01*
X614665Y-303733D01*
X614672Y-303758D01*
X614679Y-303780D01*
X614683Y-303798D01*
X614687Y-303809D01*
X614690Y-303817D01*
Y-303820D01*
X614727Y-303904D01*
X614767Y-303980D01*
X614810Y-304042D01*
X614858Y-304097D01*
X614898Y-304141D01*
X614930Y-304170D01*
X614956Y-304188D01*
X614960Y-304195D01*
X614963D01*
X615040Y-304242D01*
X615123Y-304279D01*
X615204Y-304304D01*
X615280Y-304319D01*
X615349Y-304330D01*
X615378Y-304333D01*
X615404D01*
X615422Y-304337D01*
X615451D01*
X615542Y-304333D01*
X615626Y-304319D01*
X615695Y-304297D01*
X615757Y-304275D01*
X615804Y-304250D01*
X615840Y-304232D01*
X615862Y-304217D01*
X615870Y-304210D01*
X615928Y-304155D01*
X615982Y-304093D01*
X616026Y-304028D01*
X616062Y-303962D01*
X616092Y-303904D01*
X616103Y-303875D01*
X616110Y-303853D01*
X616117Y-303835D01*
X616124Y-303820D01*
X616128Y-303813D01*
Y-303809D01*
X616456Y-303886D01*
X616434Y-303951D01*
X616412Y-304010D01*
X616383Y-304064D01*
X616357Y-304119D01*
X616328Y-304166D01*
X616295Y-304210D01*
X616266Y-304253D01*
X616237Y-304290D01*
X616208Y-304319D01*
X616183Y-304348D01*
X616157Y-304374D01*
X616139Y-304392D01*
X616121Y-304410D01*
X616106Y-304421D01*
X616099Y-304425D01*
X616095Y-304428D01*
X616044Y-304461D01*
X615993Y-304494D01*
X615942Y-304519D01*
X615888Y-304541D01*
X615779Y-304574D01*
X615680Y-304596D01*
X615633Y-304607D01*
X615593Y-304610D01*
X615553Y-304614D01*
X615520Y-304617D01*
X615495Y-304621D01*
X615458D01*
X615338Y-304614D01*
X615222Y-304596D01*
X615120Y-304574D01*
X615072Y-304559D01*
X615029Y-304545D01*
X614989Y-304530D01*
X614952Y-304516D01*
X614923Y-304505D01*
X614894Y-304494D01*
X614876Y-304483D01*
X614861Y-304475D01*
X614850Y-304472D01*
X614847Y-304468D01*
X614748Y-304406D01*
X614665Y-304333D01*
X614592Y-304261D01*
X614530Y-304188D01*
X614483Y-304122D01*
X614465Y-304093D01*
X614450Y-304068D01*
X614435Y-304050D01*
X614428Y-304035D01*
X614425Y-304024D01*
X614421Y-304020D01*
X614370Y-303908D01*
X614333Y-303791D01*
X614308Y-303675D01*
X614290Y-303569D01*
X614283Y-303522D01*
X614279Y-303474D01*
X614275Y-303438D01*
Y-303402D01*
X614272Y-303376D01*
Y-303354D01*
Y-303340D01*
Y-303336D01*
X614279Y-303205D01*
X614293Y-303078D01*
X614312Y-302965D01*
X614326Y-302910D01*
X614337Y-302863D01*
X614348Y-302819D01*
X614363Y-302779D01*
X614373Y-302743D01*
X614381Y-302714D01*
X614392Y-302692D01*
X614395Y-302674D01*
X614403Y-302663D01*
Y-302659D01*
X614457Y-302550D01*
X614519Y-302452D01*
X614585Y-302368D01*
X614617Y-302335D01*
X614647Y-302302D01*
X614676Y-302273D01*
X614705Y-302248D01*
X614730Y-302226D01*
X614752Y-302211D01*
X614767Y-302197D01*
X614781Y-302186D01*
X614788Y-302182D01*
X614792Y-302179D01*
X614843Y-302150D01*
X614894Y-302124D01*
X615003Y-302084D01*
X615112Y-302055D01*
X615218Y-302037D01*
X615269Y-302029D01*
X615313Y-302022D01*
X615353Y-302018D01*
X615385D01*
X615415Y-302015D01*
X615455D01*
X615527Y-302018D01*
D02*
G37*
G36*
X617639Y-302022D02*
X617730Y-302037D01*
X617813Y-302062D01*
X617882Y-302091D01*
X617912Y-302102D01*
X617941Y-302117D01*
X617963Y-302131D01*
X617984Y-302142D01*
X617999Y-302150D01*
X618010Y-302157D01*
X618017Y-302164D01*
X618021D01*
X618094Y-302226D01*
X618159Y-302295D01*
X618210Y-302368D01*
X618254Y-302437D01*
X618290Y-302499D01*
X618305Y-302528D01*
X618316Y-302550D01*
X618323Y-302572D01*
X618330Y-302586D01*
X618334Y-302594D01*
Y-302597D01*
X618352Y-302652D01*
X618370Y-302714D01*
X618396Y-302837D01*
X618414Y-302969D01*
X618425Y-303092D01*
X618432Y-303147D01*
X618436Y-303202D01*
Y-303249D01*
X618439Y-303289D01*
Y-303322D01*
Y-303347D01*
Y-303365D01*
Y-303369D01*
Y-303453D01*
X618436Y-303533D01*
X618429Y-303606D01*
X618421Y-303675D01*
X618414Y-303736D01*
X618407Y-303795D01*
X618396Y-303849D01*
X618385Y-303897D01*
X618374Y-303937D01*
X618367Y-303973D01*
X618356Y-304006D01*
X618348Y-304031D01*
X618341Y-304050D01*
X618334Y-304064D01*
X618330Y-304071D01*
Y-304075D01*
X618287Y-304162D01*
X618239Y-304239D01*
X618185Y-304304D01*
X618137Y-304359D01*
X618090Y-304399D01*
X618054Y-304428D01*
X618039Y-304439D01*
X618028Y-304446D01*
X618024Y-304454D01*
X618021D01*
X617944Y-304497D01*
X617868Y-304530D01*
X617792Y-304556D01*
X617722Y-304570D01*
X617661Y-304581D01*
X617635Y-304585D01*
X617617D01*
X617599Y-304588D01*
X617573D01*
X617511Y-304585D01*
X617453Y-304577D01*
X617395Y-304566D01*
X617344Y-304552D01*
X617245Y-304512D01*
X617202Y-304494D01*
X617165Y-304472D01*
X617129Y-304446D01*
X617100Y-304428D01*
X617071Y-304406D01*
X617049Y-304388D01*
X617031Y-304374D01*
X617020Y-304363D01*
X617013Y-304355D01*
X617009Y-304352D01*
X616969Y-304308D01*
X616936Y-304257D01*
X616903Y-304210D01*
X616878Y-304159D01*
X616856Y-304104D01*
X616838Y-304053D01*
X616812Y-303959D01*
X616801Y-303911D01*
X616794Y-303871D01*
X616790Y-303831D01*
X616787Y-303798D01*
X616783Y-303773D01*
Y-303755D01*
Y-303740D01*
Y-303736D01*
X616787Y-303667D01*
X616794Y-303606D01*
X616801Y-303544D01*
X616816Y-303485D01*
X616834Y-303434D01*
X616852Y-303383D01*
X616871Y-303340D01*
X616892Y-303300D01*
X616911Y-303263D01*
X616929Y-303231D01*
X616947Y-303205D01*
X616965Y-303180D01*
X616980Y-303161D01*
X616987Y-303151D01*
X616994Y-303143D01*
X616998Y-303140D01*
X617038Y-303099D01*
X617082Y-303067D01*
X617125Y-303034D01*
X617173Y-303009D01*
X617216Y-302987D01*
X617260Y-302969D01*
X617344Y-302943D01*
X617380Y-302932D01*
X617417Y-302925D01*
X617446Y-302921D01*
X617475Y-302918D01*
X617497Y-302914D01*
X617526D01*
X617595Y-302918D01*
X617661Y-302928D01*
X617719Y-302943D01*
X617773Y-302961D01*
X617813Y-302976D01*
X617846Y-302990D01*
X617868Y-303001D01*
X617875Y-303005D01*
X617934Y-303041D01*
X617984Y-303081D01*
X618028Y-303121D01*
X618064Y-303158D01*
X618090Y-303194D01*
X618112Y-303220D01*
X618126Y-303238D01*
X618130Y-303245D01*
Y-303216D01*
Y-303198D01*
Y-303187D01*
Y-303183D01*
X618126Y-303110D01*
X618123Y-303041D01*
X618116Y-302979D01*
X618108Y-302921D01*
X618097Y-302874D01*
X618090Y-302837D01*
X618086Y-302823D01*
Y-302812D01*
X618083Y-302808D01*
Y-302805D01*
X618064Y-302739D01*
X618046Y-302681D01*
X618028Y-302630D01*
X618010Y-302586D01*
X617995Y-302554D01*
X617981Y-302528D01*
X617974Y-302510D01*
X617970Y-302506D01*
X617941Y-302466D01*
X617912Y-302433D01*
X617882Y-302404D01*
X617853Y-302379D01*
X617832Y-302357D01*
X617810Y-302342D01*
X617795Y-302335D01*
X617792Y-302331D01*
X617752Y-302310D01*
X617708Y-302295D01*
X617668Y-302284D01*
X617628Y-302277D01*
X617595Y-302273D01*
X617569Y-302270D01*
X617544D01*
X617486Y-302273D01*
X617431Y-302284D01*
X617384Y-302299D01*
X617344Y-302317D01*
X617315Y-302331D01*
X617289Y-302346D01*
X617275Y-302357D01*
X617271Y-302361D01*
X617235Y-302401D01*
X617205Y-302448D01*
X617180Y-302499D01*
X617162Y-302550D01*
X617147Y-302594D01*
X617136Y-302634D01*
X617133Y-302648D01*
Y-302656D01*
X617129Y-302663D01*
Y-302666D01*
X616831Y-302641D01*
X616852Y-302535D01*
X616882Y-302444D01*
X616918Y-302364D01*
X616954Y-302299D01*
X616991Y-302248D01*
X617009Y-302226D01*
X617024Y-302208D01*
X617034Y-302197D01*
X617045Y-302186D01*
X617049Y-302182D01*
X617053Y-302179D01*
X617089Y-302150D01*
X617129Y-302124D01*
X617209Y-302084D01*
X617289Y-302055D01*
X617366Y-302037D01*
X617435Y-302022D01*
X617464Y-302018D01*
X617489D01*
X617508Y-302015D01*
X617537D01*
X617639Y-302022D01*
D02*
G37*
G36*
X619663D02*
X619754Y-302037D01*
X619830Y-302062D01*
X619895Y-302088D01*
X619950Y-302113D01*
X619968Y-302128D01*
X619986Y-302139D01*
X620001Y-302146D01*
X620012Y-302153D01*
X620015Y-302160D01*
X620019D01*
X620085Y-302222D01*
X620139Y-302288D01*
X620187Y-302361D01*
X620223Y-302426D01*
X620252Y-302488D01*
X620267Y-302514D01*
X620274Y-302539D01*
X620281Y-302557D01*
X620289Y-302572D01*
X620292Y-302579D01*
Y-302583D01*
X620310Y-302637D01*
X620325Y-302692D01*
X620347Y-302808D01*
X620365Y-302928D01*
X620376Y-303045D01*
X620380Y-303096D01*
X620383Y-303143D01*
Y-303187D01*
X620387Y-303227D01*
Y-303256D01*
Y-303281D01*
Y-303296D01*
Y-303300D01*
Y-303369D01*
X620383Y-303434D01*
Y-303493D01*
X620380Y-303551D01*
X620372Y-303602D01*
X620369Y-303653D01*
X620365Y-303696D01*
X620358Y-303736D01*
X620354Y-303773D01*
X620347Y-303806D01*
X620343Y-303831D01*
X620339Y-303853D01*
X620336Y-303871D01*
X620332Y-303882D01*
X620329Y-303889D01*
Y-303893D01*
X620307Y-303973D01*
X620281Y-304046D01*
X620252Y-304108D01*
X620230Y-304162D01*
X620205Y-304210D01*
X620190Y-304242D01*
X620176Y-304261D01*
X620172Y-304268D01*
X620132Y-304323D01*
X620092Y-304370D01*
X620048Y-304410D01*
X620008Y-304446D01*
X619972Y-304472D01*
X619943Y-304490D01*
X619924Y-304501D01*
X619921Y-304505D01*
X619917D01*
X619859Y-304534D01*
X619797Y-304552D01*
X619739Y-304566D01*
X619684Y-304577D01*
X619637Y-304585D01*
X619597Y-304588D01*
X619564D01*
X619466Y-304581D01*
X619375Y-304566D01*
X619299Y-304541D01*
X619233Y-304516D01*
X619178Y-304486D01*
X619157Y-304475D01*
X619138Y-304461D01*
X619124Y-304454D01*
X619113Y-304446D01*
X619109Y-304439D01*
X619106D01*
X619040Y-304381D01*
X618985Y-304312D01*
X618938Y-304242D01*
X618902Y-304177D01*
X618873Y-304115D01*
X618858Y-304090D01*
X618851Y-304064D01*
X618844Y-304046D01*
X618836Y-304031D01*
X618832Y-304024D01*
Y-304020D01*
X618818Y-303966D01*
X618803Y-303911D01*
X618782Y-303791D01*
X618763Y-303671D01*
X618752Y-303558D01*
X618749Y-303504D01*
X618745Y-303456D01*
Y-303413D01*
X618742Y-303373D01*
Y-303343D01*
Y-303318D01*
Y-303303D01*
Y-303300D01*
X618745Y-303172D01*
X618752Y-303052D01*
X618763Y-302943D01*
X618782Y-302841D01*
X618800Y-302747D01*
X618822Y-302663D01*
X618844Y-302586D01*
X618865Y-302521D01*
X618887Y-302463D01*
X618913Y-302412D01*
X618931Y-302368D01*
X618949Y-302335D01*
X618967Y-302306D01*
X618978Y-302288D01*
X618985Y-302277D01*
X618989Y-302273D01*
X619029Y-302230D01*
X619073Y-302189D01*
X619120Y-302153D01*
X619167Y-302124D01*
X619215Y-302098D01*
X619262Y-302077D01*
X619309Y-302062D01*
X619353Y-302048D01*
X619397Y-302037D01*
X619437Y-302029D01*
X619473Y-302022D01*
X619502Y-302018D01*
X619528Y-302015D01*
X619564D01*
X619663Y-302022D01*
D02*
G37*
G36*
X381432Y-133806D02*
X381141Y-133845D01*
X381115Y-133806D01*
X381083Y-133773D01*
X381053Y-133740D01*
X381024Y-133714D01*
X380995Y-133696D01*
X380974Y-133678D01*
X380959Y-133671D01*
X380955Y-133667D01*
X380908Y-133645D01*
X380861Y-133627D01*
X380817Y-133616D01*
X380773Y-133605D01*
X380737Y-133602D01*
X380708Y-133598D01*
X380639D01*
X380595Y-133605D01*
X380519Y-133624D01*
X380453Y-133649D01*
X380395Y-133674D01*
X380351Y-133703D01*
X380318Y-133729D01*
X380300Y-133747D01*
X380293Y-133751D01*
Y-133755D01*
X380242Y-133816D01*
X380205Y-133882D01*
X380180Y-133951D01*
X380162Y-134020D01*
X380151Y-134079D01*
X380147Y-134104D01*
Y-134126D01*
X380144Y-134144D01*
Y-134159D01*
Y-134166D01*
Y-134169D01*
Y-134220D01*
X380151Y-134268D01*
X380169Y-134359D01*
X380194Y-134435D01*
X380220Y-134497D01*
X380249Y-134548D01*
X380275Y-134588D01*
X380286Y-134599D01*
X380293Y-134610D01*
X380296Y-134614D01*
X380300Y-134617D01*
X380329Y-134646D01*
X380358Y-134672D01*
X380424Y-134715D01*
X380486Y-134745D01*
X380548Y-134763D01*
X380598Y-134777D01*
X380642Y-134781D01*
X380657Y-134785D01*
X380679D01*
X380748Y-134781D01*
X380810Y-134766D01*
X380864Y-134748D01*
X380908Y-134726D01*
X380948Y-134704D01*
X380977Y-134686D01*
X380992Y-134672D01*
X380999Y-134668D01*
X381043Y-134617D01*
X381079Y-134563D01*
X381108Y-134501D01*
X381130Y-134446D01*
X381144Y-134391D01*
X381155Y-134352D01*
X381159Y-134333D01*
X381163Y-134322D01*
Y-134315D01*
Y-134311D01*
X381487Y-134337D01*
X381479Y-134395D01*
X381469Y-134450D01*
X381436Y-134552D01*
X381396Y-134639D01*
X381374Y-134679D01*
X381352Y-134712D01*
X381334Y-134745D01*
X381312Y-134774D01*
X381294Y-134795D01*
X381276Y-134814D01*
X381261Y-134828D01*
X381254Y-134843D01*
X381246Y-134846D01*
X381243Y-134850D01*
X381199Y-134883D01*
X381155Y-134912D01*
X381108Y-134938D01*
X381061Y-134959D01*
X380970Y-134992D01*
X380879Y-135014D01*
X380839Y-135025D01*
X380799Y-135029D01*
X380766Y-135032D01*
X380737Y-135036D01*
X380711Y-135039D01*
X380679D01*
X380602Y-135036D01*
X380529Y-135025D01*
X380460Y-135010D01*
X380398Y-134992D01*
X380340Y-134967D01*
X380286Y-134941D01*
X380235Y-134916D01*
X380191Y-134887D01*
X380151Y-134857D01*
X380114Y-134832D01*
X380085Y-134803D01*
X380060Y-134781D01*
X380042Y-134763D01*
X380027Y-134748D01*
X380020Y-134737D01*
X380016Y-134734D01*
X379980Y-134686D01*
X379951Y-134635D01*
X379922Y-134588D01*
X379900Y-134537D01*
X379863Y-134439D01*
X379841Y-134344D01*
X379834Y-134304D01*
X379827Y-134264D01*
X379823Y-134231D01*
X379820Y-134202D01*
X379816Y-134177D01*
Y-134159D01*
Y-134148D01*
Y-134144D01*
X379820Y-134079D01*
X379827Y-134017D01*
X379838Y-133955D01*
X379852Y-133900D01*
X379871Y-133849D01*
X379889Y-133798D01*
X379911Y-133755D01*
X379929Y-133714D01*
X379951Y-133678D01*
X379973Y-133645D01*
X379991Y-133620D01*
X380009Y-133594D01*
X380023Y-133576D01*
X380034Y-133565D01*
X380042Y-133558D01*
X380045Y-133554D01*
X380089Y-133514D01*
X380133Y-133478D01*
X380180Y-133449D01*
X380227Y-133423D01*
X380275Y-133398D01*
X380322Y-133380D01*
X380409Y-133354D01*
X380449Y-133343D01*
X380486Y-133336D01*
X380519Y-133332D01*
X380548Y-133329D01*
X380569Y-133325D01*
X380649D01*
X380693Y-133332D01*
X380781Y-133351D01*
X380861Y-133376D01*
X380933Y-133405D01*
X380992Y-133434D01*
X381017Y-133449D01*
X381039Y-133460D01*
X381057Y-133471D01*
X381068Y-133478D01*
X381075Y-133482D01*
X381079Y-133485D01*
X380944Y-132805D01*
X379936D01*
Y-132510D01*
X381188D01*
X381432Y-133806D01*
D02*
G37*
G36*
X384890Y-132440D02*
X385007Y-132459D01*
X385108Y-132481D01*
X385156Y-132495D01*
X385199Y-132510D01*
X385240Y-132524D01*
X385276Y-132539D01*
X385305Y-132550D01*
X385334Y-132561D01*
X385352Y-132571D01*
X385367Y-132579D01*
X385378Y-132582D01*
X385382Y-132586D01*
X385480Y-132648D01*
X385563Y-132721D01*
X385636Y-132793D01*
X385698Y-132866D01*
X385746Y-132932D01*
X385764Y-132961D01*
X385778Y-132986D01*
X385793Y-133005D01*
X385800Y-133019D01*
X385804Y-133030D01*
X385807Y-133034D01*
X385858Y-133147D01*
X385895Y-133263D01*
X385920Y-133380D01*
X385938Y-133485D01*
X385946Y-133533D01*
X385949Y-133580D01*
X385953Y-133616D01*
Y-133653D01*
X385957Y-133678D01*
Y-133700D01*
Y-133714D01*
Y-133718D01*
X385949Y-133849D01*
X385935Y-133976D01*
X385917Y-134089D01*
X385902Y-134144D01*
X385891Y-134191D01*
X385880Y-134235D01*
X385866Y-134275D01*
X385855Y-134311D01*
X385847Y-134341D01*
X385837Y-134362D01*
X385833Y-134381D01*
X385826Y-134391D01*
Y-134395D01*
X385771Y-134504D01*
X385709Y-134603D01*
X385644Y-134686D01*
X385611Y-134719D01*
X385582Y-134752D01*
X385553Y-134781D01*
X385524Y-134807D01*
X385498Y-134828D01*
X385476Y-134843D01*
X385462Y-134857D01*
X385447Y-134868D01*
X385440Y-134872D01*
X385436Y-134876D01*
X385385Y-134905D01*
X385334Y-134930D01*
X385225Y-134970D01*
X385116Y-134999D01*
X385010Y-135018D01*
X384959Y-135025D01*
X384916Y-135032D01*
X384876Y-135036D01*
X384843D01*
X384814Y-135039D01*
X384774D01*
X384701Y-135036D01*
X384632Y-135029D01*
X384566Y-135021D01*
X384504Y-135007D01*
X384446Y-134988D01*
X384391Y-134970D01*
X384341Y-134952D01*
X384293Y-134930D01*
X384253Y-134912D01*
X384213Y-134894D01*
X384184Y-134876D01*
X384155Y-134857D01*
X384137Y-134843D01*
X384118Y-134836D01*
X384111Y-134828D01*
X384107Y-134825D01*
X384057Y-134781D01*
X384013Y-134737D01*
X383973Y-134686D01*
X383933Y-134635D01*
X383867Y-134534D01*
X383816Y-134432D01*
X383794Y-134384D01*
X383776Y-134341D01*
X383762Y-134300D01*
X383751Y-134268D01*
X383740Y-134239D01*
X383733Y-134217D01*
X383729Y-134202D01*
Y-134199D01*
X384064Y-134115D01*
X384078Y-134173D01*
X384097Y-134228D01*
X384115Y-134279D01*
X384133Y-134326D01*
X384155Y-134370D01*
X384177Y-134406D01*
X384202Y-134442D01*
X384224Y-134475D01*
X384242Y-134504D01*
X384264Y-134526D01*
X384282Y-134548D01*
X384297Y-134566D01*
X384311Y-134577D01*
X384322Y-134588D01*
X384326Y-134592D01*
X384330Y-134595D01*
X384366Y-134625D01*
X384406Y-134646D01*
X384486Y-134686D01*
X384562Y-134715D01*
X384639Y-134734D01*
X384704Y-134748D01*
X384730Y-134752D01*
X384755D01*
X384777Y-134756D01*
X384803D01*
X384887Y-134752D01*
X384967Y-134737D01*
X385039Y-134719D01*
X385105Y-134697D01*
X385156Y-134675D01*
X385178Y-134664D01*
X385196Y-134657D01*
X385210Y-134650D01*
X385221Y-134643D01*
X385229Y-134639D01*
X385232D01*
X385301Y-134588D01*
X385360Y-134534D01*
X385411Y-134472D01*
X385451Y-134413D01*
X385483Y-134362D01*
X385505Y-134319D01*
X385513Y-134300D01*
X385520Y-134290D01*
X385524Y-134282D01*
Y-134279D01*
X385553Y-134184D01*
X385574Y-134089D01*
X385593Y-133995D01*
X385603Y-133907D01*
X385607Y-133867D01*
X385611Y-133831D01*
Y-133798D01*
X385614Y-133773D01*
Y-133751D01*
Y-133733D01*
Y-133722D01*
Y-133718D01*
X385611Y-133624D01*
X385603Y-133536D01*
X385589Y-133456D01*
X385574Y-133383D01*
X385563Y-133321D01*
X385556Y-133296D01*
X385549Y-133274D01*
X385545Y-133256D01*
X385542Y-133245D01*
X385538Y-133238D01*
Y-133234D01*
X385502Y-133150D01*
X385462Y-133074D01*
X385418Y-133012D01*
X385371Y-132957D01*
X385331Y-132914D01*
X385298Y-132885D01*
X385272Y-132866D01*
X385269Y-132859D01*
X385265D01*
X385189Y-132812D01*
X385105Y-132775D01*
X385025Y-132750D01*
X384948Y-132735D01*
X384879Y-132724D01*
X384850Y-132721D01*
X384825D01*
X384806Y-132717D01*
X384777D01*
X384686Y-132721D01*
X384603Y-132735D01*
X384533Y-132757D01*
X384472Y-132779D01*
X384424Y-132805D01*
X384388Y-132823D01*
X384366Y-132837D01*
X384359Y-132844D01*
X384300Y-132899D01*
X384246Y-132961D01*
X384202Y-133027D01*
X384166Y-133092D01*
X384137Y-133150D01*
X384126Y-133179D01*
X384118Y-133201D01*
X384111Y-133219D01*
X384104Y-133234D01*
X384100Y-133241D01*
Y-133245D01*
X383773Y-133168D01*
X383794Y-133103D01*
X383816Y-133045D01*
X383845Y-132990D01*
X383871Y-132936D01*
X383900Y-132888D01*
X383933Y-132844D01*
X383962Y-132801D01*
X383991Y-132764D01*
X384020Y-132735D01*
X384046Y-132706D01*
X384071Y-132681D01*
X384089Y-132662D01*
X384107Y-132644D01*
X384122Y-132633D01*
X384129Y-132630D01*
X384133Y-132626D01*
X384184Y-132593D01*
X384235Y-132561D01*
X384286Y-132535D01*
X384341Y-132513D01*
X384450Y-132481D01*
X384548Y-132459D01*
X384595Y-132448D01*
X384635Y-132444D01*
X384675Y-132440D01*
X384708Y-132437D01*
X384734Y-132433D01*
X384770D01*
X384890Y-132440D01*
D02*
G37*
G36*
X382684Y-132470D02*
X382743Y-132473D01*
X382844Y-132495D01*
X382892Y-132510D01*
X382935Y-132524D01*
X382976Y-132542D01*
X383012Y-132561D01*
X383041Y-132579D01*
X383070Y-132597D01*
X383096Y-132612D01*
X383114Y-132626D01*
X383128Y-132637D01*
X383139Y-132648D01*
X383147Y-132652D01*
X383150Y-132655D01*
X383183Y-132692D01*
X383216Y-132728D01*
X383241Y-132768D01*
X383263Y-132808D01*
X383299Y-132885D01*
X383321Y-132957D01*
X383336Y-133019D01*
X383340Y-133048D01*
X383343Y-133070D01*
X383347Y-133092D01*
Y-133107D01*
Y-133114D01*
Y-133117D01*
X383343Y-133183D01*
X383332Y-133245D01*
X383318Y-133300D01*
X383299Y-133347D01*
X383285Y-133383D01*
X383270Y-133412D01*
X383259Y-133427D01*
X383256Y-133434D01*
X383216Y-133478D01*
X383172Y-133518D01*
X383125Y-133554D01*
X383077Y-133583D01*
X383034Y-133605D01*
X383001Y-133620D01*
X382986Y-133627D01*
X382976Y-133631D01*
X382972Y-133634D01*
X382968D01*
X383052Y-133660D01*
X383121Y-133693D01*
X383183Y-133733D01*
X383234Y-133769D01*
X383274Y-133806D01*
X383303Y-133835D01*
X383318Y-133853D01*
X383325Y-133856D01*
Y-133860D01*
X383365Y-133926D01*
X383398Y-133995D01*
X383419Y-134060D01*
X383434Y-134126D01*
X383441Y-134184D01*
X383445Y-134210D01*
Y-134231D01*
X383449Y-134246D01*
Y-134260D01*
Y-134268D01*
Y-134271D01*
X383445Y-134330D01*
X383438Y-134388D01*
X383427Y-134442D01*
X383412Y-134497D01*
X383376Y-134588D01*
X383358Y-134632D01*
X383336Y-134668D01*
X383314Y-134704D01*
X383296Y-134734D01*
X383274Y-134759D01*
X383259Y-134781D01*
X383245Y-134799D01*
X383234Y-134810D01*
X383227Y-134817D01*
X383223Y-134821D01*
X383179Y-134861D01*
X383132Y-134894D01*
X383081Y-134923D01*
X383030Y-134948D01*
X382983Y-134967D01*
X382932Y-134985D01*
X382834Y-135010D01*
X382790Y-135021D01*
X382750Y-135029D01*
X382713Y-135032D01*
X382681Y-135036D01*
X382655Y-135039D01*
X382619D01*
X382550Y-135036D01*
X382488Y-135029D01*
X382426Y-135018D01*
X382368Y-135007D01*
X382317Y-134988D01*
X382266Y-134970D01*
X382218Y-134952D01*
X382178Y-134930D01*
X382142Y-134908D01*
X382109Y-134890D01*
X382084Y-134872D01*
X382058Y-134854D01*
X382040Y-134843D01*
X382029Y-134832D01*
X382022Y-134825D01*
X382018Y-134821D01*
X381978Y-134777D01*
X381942Y-134734D01*
X381913Y-134690D01*
X381887Y-134643D01*
X381862Y-134599D01*
X381843Y-134552D01*
X381818Y-134468D01*
X381807Y-134428D01*
X381800Y-134391D01*
X381796Y-134359D01*
X381792Y-134333D01*
X381789Y-134311D01*
Y-134293D01*
Y-134282D01*
Y-134279D01*
X381792Y-134195D01*
X381807Y-134118D01*
X381829Y-134049D01*
X381851Y-133991D01*
X381873Y-133944D01*
X381894Y-133907D01*
X381909Y-133886D01*
X381913Y-133882D01*
Y-133878D01*
X381963Y-133820D01*
X382018Y-133769D01*
X382076Y-133729D01*
X382131Y-133693D01*
X382182Y-133667D01*
X382226Y-133649D01*
X382240Y-133642D01*
X382251Y-133638D01*
X382258Y-133634D01*
X382262D01*
X382196Y-133605D01*
X382142Y-133572D01*
X382095Y-133540D01*
X382055Y-133507D01*
X382025Y-133478D01*
X382004Y-133456D01*
X381989Y-133441D01*
X381985Y-133434D01*
X381953Y-133383D01*
X381931Y-133332D01*
X381913Y-133281D01*
X381902Y-133230D01*
X381894Y-133190D01*
X381891Y-133158D01*
Y-133136D01*
Y-133132D01*
Y-133128D01*
X381894Y-133078D01*
X381898Y-133030D01*
X381924Y-132939D01*
X381956Y-132859D01*
X381993Y-132790D01*
X382029Y-132735D01*
X382047Y-132713D01*
X382062Y-132692D01*
X382076Y-132677D01*
X382087Y-132666D01*
X382091Y-132662D01*
X382095Y-132659D01*
X382135Y-132626D01*
X382175Y-132593D01*
X382218Y-132568D01*
X382262Y-132546D01*
X382349Y-132513D01*
X382437Y-132491D01*
X382473Y-132481D01*
X382509Y-132477D01*
X382542Y-132473D01*
X382571Y-132470D01*
X382593Y-132466D01*
X382626D01*
X382684Y-132470D01*
D02*
G37*
G36*
X64870Y-51118D02*
X64932Y-51074D01*
X64957Y-51052D01*
X64982Y-51034D01*
X65004Y-51016D01*
X65019Y-51001D01*
X65030Y-50990D01*
X65034Y-50987D01*
X65052Y-50968D01*
X65070Y-50947D01*
X65117Y-50896D01*
X65172Y-50837D01*
X65226Y-50776D01*
X65274Y-50717D01*
X65296Y-50692D01*
X65317Y-50670D01*
X65332Y-50652D01*
X65343Y-50637D01*
X65350Y-50630D01*
X65354Y-50626D01*
X65405Y-50568D01*
X65452Y-50510D01*
X65499Y-50459D01*
X65539Y-50412D01*
X65579Y-50368D01*
X65616Y-50331D01*
X65649Y-50295D01*
X65678Y-50266D01*
X65707Y-50237D01*
X65729Y-50215D01*
X65747Y-50197D01*
X65765Y-50179D01*
X65787Y-50160D01*
X65794Y-50153D01*
X65856Y-50102D01*
X65911Y-50059D01*
X65965Y-50022D01*
X66009Y-49993D01*
X66049Y-49971D01*
X66078Y-49957D01*
X66096Y-49949D01*
X66104Y-49946D01*
X66158Y-49924D01*
X66213Y-49909D01*
X66264Y-49895D01*
X66307Y-49887D01*
X66347Y-49884D01*
X66377Y-49880D01*
X66395D01*
X66402D01*
X66457Y-49884D01*
X66508Y-49891D01*
X66559Y-49898D01*
X66602Y-49913D01*
X66690Y-49949D01*
X66759Y-49986D01*
X66792Y-50008D01*
X66817Y-50026D01*
X66843Y-50044D01*
X66861Y-50062D01*
X66875Y-50077D01*
X66890Y-50084D01*
X66894Y-50091D01*
X66897Y-50095D01*
X66934Y-50135D01*
X66966Y-50179D01*
X66992Y-50226D01*
X67014Y-50273D01*
X67050Y-50368D01*
X67076Y-50463D01*
X67083Y-50503D01*
X67090Y-50543D01*
X67094Y-50579D01*
X67097Y-50608D01*
X67101Y-50634D01*
Y-50670D01*
X67097Y-50736D01*
X67094Y-50797D01*
X67083Y-50856D01*
X67072Y-50910D01*
X67057Y-50961D01*
X67043Y-51009D01*
X67025Y-51052D01*
X67006Y-51092D01*
X66988Y-51129D01*
X66970Y-51158D01*
X66955Y-51183D01*
X66941Y-51205D01*
X66930Y-51223D01*
X66919Y-51234D01*
X66915Y-51241D01*
X66912Y-51245D01*
X66875Y-51282D01*
X66835Y-51314D01*
X66792Y-51347D01*
X66748Y-51373D01*
X66661Y-51416D01*
X66573Y-51445D01*
X66533Y-51456D01*
X66493Y-51467D01*
X66460Y-51474D01*
X66431Y-51482D01*
X66406Y-51485D01*
X66388D01*
X66377Y-51489D01*
X66373D01*
X66340Y-51172D01*
X66424Y-51165D01*
X66497Y-51151D01*
X66562Y-51129D01*
X66613Y-51103D01*
X66657Y-51081D01*
X66686Y-51060D01*
X66704Y-51045D01*
X66711Y-51038D01*
X66755Y-50983D01*
X66788Y-50925D01*
X66813Y-50863D01*
X66828Y-50808D01*
X66839Y-50757D01*
X66843Y-50714D01*
X66846Y-50699D01*
Y-50677D01*
X66843Y-50601D01*
X66828Y-50532D01*
X66806Y-50473D01*
X66784Y-50423D01*
X66759Y-50383D01*
X66741Y-50357D01*
X66726Y-50339D01*
X66719Y-50331D01*
X66668Y-50288D01*
X66617Y-50255D01*
X66566Y-50230D01*
X66515Y-50215D01*
X66475Y-50204D01*
X66439Y-50200D01*
X66417Y-50197D01*
X66413D01*
X66409D01*
X66344Y-50204D01*
X66275Y-50219D01*
X66213Y-50244D01*
X66155Y-50270D01*
X66107Y-50299D01*
X66067Y-50324D01*
X66053Y-50331D01*
X66042Y-50339D01*
X66038Y-50346D01*
X66035D01*
X65994Y-50375D01*
X65954Y-50412D01*
X65911Y-50452D01*
X65867Y-50495D01*
X65780Y-50586D01*
X65692Y-50677D01*
X65652Y-50725D01*
X65616Y-50765D01*
X65583Y-50805D01*
X65554Y-50837D01*
X65532Y-50863D01*
X65514Y-50885D01*
X65503Y-50899D01*
X65499Y-50903D01*
X65423Y-50994D01*
X65350Y-51078D01*
X65285Y-51147D01*
X65230Y-51201D01*
X65183Y-51249D01*
X65150Y-51282D01*
X65128Y-51300D01*
X65124Y-51307D01*
X65121D01*
X65059Y-51358D01*
X65001Y-51398D01*
X64943Y-51434D01*
X64891Y-51464D01*
X64848Y-51485D01*
X64815Y-51500D01*
X64793Y-51507D01*
X64790Y-51511D01*
X64786D01*
X64746Y-51525D01*
X64710Y-51533D01*
X64673Y-51540D01*
X64640Y-51544D01*
X64611Y-51547D01*
X64589D01*
X64575D01*
X64571D01*
Y-49876D01*
X64870D01*
Y-51118D01*
D02*
G37*
G36*
Y-53076D02*
X64932Y-53032D01*
X64957Y-53011D01*
X64982Y-52992D01*
X65004Y-52974D01*
X65019Y-52960D01*
X65030Y-52949D01*
X65034Y-52945D01*
X65052Y-52927D01*
X65070Y-52905D01*
X65117Y-52854D01*
X65172Y-52796D01*
X65226Y-52734D01*
X65274Y-52676D01*
X65296Y-52650D01*
X65317Y-52628D01*
X65332Y-52610D01*
X65343Y-52596D01*
X65350Y-52588D01*
X65354Y-52585D01*
X65405Y-52526D01*
X65452Y-52468D01*
X65499Y-52417D01*
X65539Y-52370D01*
X65579Y-52326D01*
X65616Y-52290D01*
X65649Y-52254D01*
X65678Y-52224D01*
X65707Y-52195D01*
X65729Y-52173D01*
X65747Y-52155D01*
X65765Y-52137D01*
X65787Y-52119D01*
X65794Y-52112D01*
X65856Y-52061D01*
X65911Y-52017D01*
X65965Y-51981D01*
X66009Y-51951D01*
X66049Y-51929D01*
X66078Y-51915D01*
X66096Y-51908D01*
X66104Y-51904D01*
X66158Y-51882D01*
X66213Y-51868D01*
X66264Y-51853D01*
X66307Y-51846D01*
X66347Y-51842D01*
X66377Y-51838D01*
X66395D01*
X66402D01*
X66457Y-51842D01*
X66508Y-51849D01*
X66559Y-51857D01*
X66602Y-51871D01*
X66690Y-51908D01*
X66759Y-51944D01*
X66792Y-51966D01*
X66817Y-51984D01*
X66843Y-52002D01*
X66861Y-52021D01*
X66875Y-52035D01*
X66890Y-52042D01*
X66894Y-52050D01*
X66897Y-52053D01*
X66934Y-52093D01*
X66966Y-52137D01*
X66992Y-52184D01*
X67014Y-52232D01*
X67050Y-52326D01*
X67076Y-52421D01*
X67083Y-52461D01*
X67090Y-52501D01*
X67094Y-52537D01*
X67097Y-52566D01*
X67101Y-52592D01*
Y-52628D01*
X67097Y-52694D01*
X67094Y-52756D01*
X67083Y-52814D01*
X67072Y-52869D01*
X67057Y-52920D01*
X67043Y-52967D01*
X67025Y-53011D01*
X67006Y-53051D01*
X66988Y-53087D01*
X66970Y-53116D01*
X66955Y-53142D01*
X66941Y-53163D01*
X66930Y-53182D01*
X66919Y-53193D01*
X66915Y-53200D01*
X66912Y-53203D01*
X66875Y-53240D01*
X66835Y-53273D01*
X66792Y-53305D01*
X66748Y-53331D01*
X66661Y-53375D01*
X66573Y-53404D01*
X66533Y-53415D01*
X66493Y-53426D01*
X66460Y-53433D01*
X66431Y-53440D01*
X66406Y-53444D01*
X66388D01*
X66377Y-53447D01*
X66373D01*
X66340Y-53131D01*
X66424Y-53123D01*
X66497Y-53109D01*
X66562Y-53087D01*
X66613Y-53061D01*
X66657Y-53040D01*
X66686Y-53018D01*
X66704Y-53003D01*
X66711Y-52996D01*
X66755Y-52941D01*
X66788Y-52883D01*
X66813Y-52821D01*
X66828Y-52767D01*
X66839Y-52716D01*
X66843Y-52672D01*
X66846Y-52658D01*
Y-52636D01*
X66843Y-52559D01*
X66828Y-52490D01*
X66806Y-52432D01*
X66784Y-52381D01*
X66759Y-52341D01*
X66741Y-52315D01*
X66726Y-52297D01*
X66719Y-52290D01*
X66668Y-52246D01*
X66617Y-52213D01*
X66566Y-52188D01*
X66515Y-52173D01*
X66475Y-52162D01*
X66439Y-52159D01*
X66417Y-52155D01*
X66413D01*
X66409D01*
X66344Y-52162D01*
X66275Y-52177D01*
X66213Y-52202D01*
X66155Y-52228D01*
X66107Y-52257D01*
X66067Y-52283D01*
X66053Y-52290D01*
X66042Y-52297D01*
X66038Y-52304D01*
X66035D01*
X65994Y-52334D01*
X65954Y-52370D01*
X65911Y-52410D01*
X65867Y-52454D01*
X65780Y-52545D01*
X65692Y-52636D01*
X65652Y-52683D01*
X65616Y-52723D01*
X65583Y-52763D01*
X65554Y-52796D01*
X65532Y-52821D01*
X65514Y-52843D01*
X65503Y-52858D01*
X65499Y-52861D01*
X65423Y-52952D01*
X65350Y-53036D01*
X65285Y-53105D01*
X65230Y-53160D01*
X65183Y-53207D01*
X65150Y-53240D01*
X65128Y-53258D01*
X65124Y-53265D01*
X65121D01*
X65059Y-53316D01*
X65001Y-53356D01*
X64943Y-53393D01*
X64891Y-53422D01*
X64848Y-53444D01*
X64815Y-53458D01*
X64793Y-53466D01*
X64790Y-53469D01*
X64786D01*
X64746Y-53484D01*
X64710Y-53491D01*
X64673Y-53498D01*
X64640Y-53502D01*
X64611Y-53506D01*
X64589D01*
X64575D01*
X64571D01*
Y-51835D01*
X64870D01*
Y-53076D01*
D02*
G37*
G36*
X65452Y-54081D02*
X65394Y-54095D01*
X65339Y-54114D01*
X65288Y-54132D01*
X65241Y-54150D01*
X65197Y-54172D01*
X65161Y-54194D01*
X65124Y-54219D01*
X65092Y-54241D01*
X65063Y-54259D01*
X65041Y-54281D01*
X65019Y-54299D01*
X65001Y-54314D01*
X64990Y-54328D01*
X64979Y-54339D01*
X64975Y-54343D01*
X64972Y-54347D01*
X64943Y-54383D01*
X64921Y-54423D01*
X64881Y-54503D01*
X64851Y-54579D01*
X64833Y-54656D01*
X64819Y-54721D01*
X64815Y-54747D01*
Y-54772D01*
X64811Y-54794D01*
Y-54820D01*
X64815Y-54903D01*
X64830Y-54984D01*
X64848Y-55056D01*
X64870Y-55122D01*
X64891Y-55173D01*
X64902Y-55195D01*
X64910Y-55213D01*
X64917Y-55227D01*
X64924Y-55238D01*
X64928Y-55246D01*
Y-55249D01*
X64979Y-55318D01*
X65034Y-55377D01*
X65095Y-55427D01*
X65154Y-55468D01*
X65205Y-55500D01*
X65248Y-55522D01*
X65266Y-55529D01*
X65277Y-55537D01*
X65285Y-55540D01*
X65288D01*
X65383Y-55569D01*
X65478Y-55591D01*
X65572Y-55610D01*
X65660Y-55620D01*
X65700Y-55624D01*
X65736Y-55628D01*
X65769D01*
X65794Y-55631D01*
X65816D01*
X65834D01*
X65845D01*
X65849D01*
X65943Y-55628D01*
X66031Y-55620D01*
X66111Y-55606D01*
X66184Y-55591D01*
X66246Y-55580D01*
X66271Y-55573D01*
X66293Y-55566D01*
X66311Y-55562D01*
X66322Y-55559D01*
X66329Y-55555D01*
X66333D01*
X66417Y-55519D01*
X66493Y-55479D01*
X66555Y-55435D01*
X66610Y-55388D01*
X66653Y-55348D01*
X66682Y-55315D01*
X66701Y-55289D01*
X66708Y-55286D01*
Y-55282D01*
X66755Y-55206D01*
X66792Y-55122D01*
X66817Y-55042D01*
X66832Y-54965D01*
X66843Y-54896D01*
X66846Y-54867D01*
Y-54842D01*
X66850Y-54823D01*
Y-54794D01*
X66846Y-54703D01*
X66832Y-54619D01*
X66810Y-54550D01*
X66788Y-54488D01*
X66763Y-54441D01*
X66744Y-54405D01*
X66730Y-54383D01*
X66723Y-54376D01*
X66668Y-54317D01*
X66606Y-54263D01*
X66540Y-54219D01*
X66475Y-54183D01*
X66417Y-54154D01*
X66388Y-54143D01*
X66366Y-54135D01*
X66347Y-54128D01*
X66333Y-54121D01*
X66326Y-54117D01*
X66322D01*
X66399Y-53790D01*
X66464Y-53811D01*
X66522Y-53833D01*
X66577Y-53862D01*
X66631Y-53888D01*
X66679Y-53917D01*
X66723Y-53950D01*
X66766Y-53979D01*
X66803Y-54008D01*
X66832Y-54037D01*
X66861Y-54062D01*
X66886Y-54088D01*
X66904Y-54106D01*
X66923Y-54124D01*
X66934Y-54139D01*
X66937Y-54146D01*
X66941Y-54150D01*
X66974Y-54201D01*
X67006Y-54252D01*
X67032Y-54303D01*
X67054Y-54357D01*
X67086Y-54467D01*
X67108Y-54565D01*
X67119Y-54612D01*
X67123Y-54652D01*
X67127Y-54692D01*
X67130Y-54725D01*
X67134Y-54751D01*
Y-54787D01*
X67127Y-54907D01*
X67108Y-55023D01*
X67086Y-55125D01*
X67072Y-55173D01*
X67057Y-55216D01*
X67043Y-55256D01*
X67028Y-55293D01*
X67017Y-55322D01*
X67006Y-55351D01*
X66996Y-55369D01*
X66988Y-55384D01*
X66984Y-55395D01*
X66981Y-55398D01*
X66919Y-55497D01*
X66846Y-55580D01*
X66773Y-55653D01*
X66701Y-55715D01*
X66635Y-55762D01*
X66606Y-55781D01*
X66580Y-55795D01*
X66562Y-55810D01*
X66548Y-55817D01*
X66537Y-55821D01*
X66533Y-55824D01*
X66420Y-55875D01*
X66304Y-55912D01*
X66187Y-55937D01*
X66082Y-55955D01*
X66035Y-55963D01*
X65987Y-55966D01*
X65951Y-55970D01*
X65914D01*
X65889Y-55974D01*
X65867D01*
X65852D01*
X65849D01*
X65718Y-55966D01*
X65590Y-55952D01*
X65478Y-55933D01*
X65423Y-55919D01*
X65376Y-55908D01*
X65332Y-55897D01*
X65292Y-55883D01*
X65255Y-55872D01*
X65226Y-55864D01*
X65205Y-55853D01*
X65186Y-55850D01*
X65175Y-55843D01*
X65172D01*
X65063Y-55788D01*
X64964Y-55726D01*
X64881Y-55660D01*
X64848Y-55628D01*
X64815Y-55599D01*
X64786Y-55569D01*
X64761Y-55540D01*
X64739Y-55515D01*
X64724Y-55493D01*
X64710Y-55479D01*
X64699Y-55464D01*
X64695Y-55457D01*
X64691Y-55453D01*
X64662Y-55402D01*
X64637Y-55351D01*
X64597Y-55242D01*
X64568Y-55133D01*
X64549Y-55027D01*
X64542Y-54976D01*
X64535Y-54932D01*
X64531Y-54892D01*
Y-54860D01*
X64527Y-54831D01*
Y-54791D01*
X64531Y-54718D01*
X64539Y-54649D01*
X64546Y-54583D01*
X64560Y-54521D01*
X64578Y-54463D01*
X64597Y-54408D01*
X64615Y-54357D01*
X64637Y-54310D01*
X64655Y-54270D01*
X64673Y-54230D01*
X64691Y-54201D01*
X64710Y-54172D01*
X64724Y-54154D01*
X64731Y-54135D01*
X64739Y-54128D01*
X64742Y-54124D01*
X64786Y-54074D01*
X64830Y-54030D01*
X64881Y-53990D01*
X64932Y-53950D01*
X65034Y-53884D01*
X65135Y-53833D01*
X65183Y-53811D01*
X65226Y-53793D01*
X65266Y-53779D01*
X65299Y-53768D01*
X65328Y-53757D01*
X65350Y-53750D01*
X65365Y-53746D01*
X65368D01*
X65452Y-54081D01*
D02*
G37*
G36*
X94873Y-46858D02*
X95000Y-46872D01*
X95113Y-46890D01*
X95168Y-46905D01*
X95215Y-46916D01*
X95259Y-46927D01*
X95299Y-46941D01*
X95335Y-46952D01*
X95364Y-46960D01*
X95386Y-46970D01*
X95404Y-46974D01*
X95415Y-46981D01*
X95419D01*
X95528Y-47036D01*
X95626Y-47098D01*
X95710Y-47163D01*
X95743Y-47196D01*
X95776Y-47225D01*
X95805Y-47254D01*
X95830Y-47284D01*
X95852Y-47309D01*
X95867Y-47331D01*
X95881Y-47345D01*
X95892Y-47360D01*
X95896Y-47367D01*
X95899Y-47371D01*
X95928Y-47422D01*
X95954Y-47473D01*
X95994Y-47582D01*
X96023Y-47691D01*
X96041Y-47797D01*
X96048Y-47848D01*
X96056Y-47891D01*
X96059Y-47931D01*
Y-47964D01*
X96063Y-47993D01*
Y-48033D01*
X96059Y-48106D01*
X96052Y-48175D01*
X96045Y-48241D01*
X96030Y-48303D01*
X96012Y-48361D01*
X95994Y-48416D01*
X95976Y-48467D01*
X95954Y-48514D01*
X95936Y-48554D01*
X95917Y-48594D01*
X95899Y-48623D01*
X95881Y-48652D01*
X95867Y-48670D01*
X95859Y-48689D01*
X95852Y-48696D01*
X95848Y-48700D01*
X95805Y-48750D01*
X95761Y-48794D01*
X95710Y-48834D01*
X95659Y-48874D01*
X95557Y-48940D01*
X95455Y-48991D01*
X95408Y-49013D01*
X95364Y-49031D01*
X95324Y-49045D01*
X95291Y-49056D01*
X95262Y-49067D01*
X95240Y-49074D01*
X95226Y-49078D01*
X95222D01*
X95139Y-48743D01*
X95197Y-48729D01*
X95251Y-48710D01*
X95302Y-48692D01*
X95350Y-48674D01*
X95393Y-48652D01*
X95430Y-48630D01*
X95466Y-48605D01*
X95499Y-48583D01*
X95528Y-48565D01*
X95550Y-48543D01*
X95572Y-48525D01*
X95590Y-48510D01*
X95601Y-48496D01*
X95612Y-48485D01*
X95615Y-48481D01*
X95619Y-48477D01*
X95648Y-48441D01*
X95670Y-48401D01*
X95710Y-48321D01*
X95739Y-48245D01*
X95757Y-48168D01*
X95772Y-48103D01*
X95776Y-48077D01*
Y-48052D01*
X95779Y-48030D01*
Y-48004D01*
X95776Y-47921D01*
X95761Y-47840D01*
X95743Y-47768D01*
X95721Y-47702D01*
X95699Y-47651D01*
X95688Y-47629D01*
X95681Y-47611D01*
X95674Y-47597D01*
X95666Y-47586D01*
X95663Y-47578D01*
Y-47575D01*
X95612Y-47506D01*
X95557Y-47447D01*
X95495Y-47396D01*
X95437Y-47356D01*
X95386Y-47324D01*
X95342Y-47302D01*
X95324Y-47294D01*
X95313Y-47287D01*
X95306Y-47284D01*
X95302D01*
X95208Y-47254D01*
X95113Y-47232D01*
X95018Y-47214D01*
X94931Y-47203D01*
X94891Y-47200D01*
X94854Y-47196D01*
X94822D01*
X94796Y-47192D01*
X94775D01*
X94756D01*
X94745D01*
X94742D01*
X94647Y-47196D01*
X94560Y-47203D01*
X94480Y-47218D01*
X94407Y-47232D01*
X94345Y-47243D01*
X94319Y-47251D01*
X94298Y-47258D01*
X94279Y-47262D01*
X94269Y-47265D01*
X94261Y-47269D01*
X94258D01*
X94174Y-47305D01*
X94097Y-47345D01*
X94036Y-47389D01*
X93981Y-47436D01*
X93937Y-47476D01*
X93908Y-47509D01*
X93890Y-47535D01*
X93883Y-47538D01*
Y-47542D01*
X93835Y-47618D01*
X93799Y-47702D01*
X93774Y-47782D01*
X93759Y-47859D01*
X93748Y-47928D01*
X93744Y-47957D01*
Y-47982D01*
X93741Y-48001D01*
Y-48030D01*
X93744Y-48121D01*
X93759Y-48204D01*
X93781Y-48274D01*
X93803Y-48335D01*
X93828Y-48383D01*
X93846Y-48419D01*
X93861Y-48441D01*
X93868Y-48448D01*
X93923Y-48507D01*
X93985Y-48561D01*
X94050Y-48605D01*
X94116Y-48641D01*
X94174Y-48670D01*
X94203Y-48681D01*
X94225Y-48689D01*
X94243Y-48696D01*
X94258Y-48703D01*
X94265Y-48707D01*
X94269D01*
X94192Y-49034D01*
X94126Y-49013D01*
X94068Y-48991D01*
X94014Y-48961D01*
X93959Y-48936D01*
X93912Y-48907D01*
X93868Y-48874D01*
X93824Y-48845D01*
X93788Y-48816D01*
X93759Y-48787D01*
X93730Y-48761D01*
X93704Y-48736D01*
X93686Y-48718D01*
X93668Y-48700D01*
X93657Y-48685D01*
X93653Y-48678D01*
X93650Y-48674D01*
X93617Y-48623D01*
X93584Y-48572D01*
X93559Y-48521D01*
X93537Y-48467D01*
X93504Y-48357D01*
X93482Y-48259D01*
X93471Y-48212D01*
X93468Y-48172D01*
X93464Y-48132D01*
X93460Y-48099D01*
X93457Y-48073D01*
Y-48037D01*
X93464Y-47917D01*
X93482Y-47800D01*
X93504Y-47699D01*
X93519Y-47651D01*
X93533Y-47607D01*
X93548Y-47567D01*
X93562Y-47531D01*
X93573Y-47502D01*
X93584Y-47473D01*
X93595Y-47455D01*
X93602Y-47440D01*
X93606Y-47429D01*
X93610Y-47425D01*
X93672Y-47327D01*
X93744Y-47243D01*
X93817Y-47171D01*
X93890Y-47109D01*
X93955Y-47061D01*
X93985Y-47043D01*
X94010Y-47029D01*
X94028Y-47014D01*
X94043Y-47007D01*
X94054Y-47003D01*
X94057Y-47000D01*
X94170Y-46949D01*
X94287Y-46912D01*
X94403Y-46887D01*
X94509Y-46869D01*
X94556Y-46861D01*
X94603Y-46858D01*
X94640Y-46854D01*
X94676D01*
X94702Y-46850D01*
X94723D01*
X94738D01*
X94742D01*
X94873Y-46858D01*
D02*
G37*
G36*
X94399Y-49653D02*
X94374Y-49708D01*
X94349Y-49762D01*
X94323Y-49813D01*
X94301Y-49857D01*
X94283Y-49893D01*
X94269Y-49915D01*
X94265Y-49919D01*
Y-49922D01*
X94225Y-49988D01*
X94185Y-50046D01*
X94148Y-50097D01*
X94116Y-50137D01*
X94090Y-50174D01*
X94068Y-50195D01*
X94054Y-50214D01*
X94050Y-50217D01*
X96019D01*
Y-50527D01*
X93489D01*
Y-50327D01*
X93551Y-50290D01*
X93610Y-50250D01*
X93668Y-50203D01*
X93719Y-50159D01*
X93762Y-50115D01*
X93799Y-50083D01*
X93810Y-50068D01*
X93821Y-50057D01*
X93824Y-50054D01*
X93828Y-50050D01*
X93890Y-49973D01*
X93948Y-49897D01*
X93999Y-49824D01*
X94039Y-49751D01*
X94076Y-49690D01*
X94090Y-49664D01*
X94101Y-49642D01*
X94112Y-49624D01*
X94116Y-49610D01*
X94123Y-49602D01*
Y-49599D01*
X94421D01*
X94399Y-49653D01*
D02*
G37*
G36*
X94960Y-51309D02*
X95069Y-51317D01*
X95171Y-51328D01*
X95266Y-51346D01*
X95350Y-51364D01*
X95426Y-51382D01*
X95495Y-51404D01*
X95557Y-51429D01*
X95608Y-51451D01*
X95655Y-51473D01*
X95692Y-51491D01*
X95724Y-51513D01*
X95750Y-51528D01*
X95764Y-51539D01*
X95776Y-51546D01*
X95779Y-51550D01*
X95830Y-51597D01*
X95874Y-51648D01*
X95910Y-51699D01*
X95943Y-51750D01*
X95972Y-51804D01*
X95994Y-51855D01*
X96012Y-51906D01*
X96027Y-51957D01*
X96038Y-52001D01*
X96048Y-52045D01*
X96056Y-52081D01*
X96059Y-52114D01*
Y-52143D01*
X96063Y-52161D01*
Y-52179D01*
X96059Y-52263D01*
X96045Y-52340D01*
X96030Y-52409D01*
X96008Y-52470D01*
X95990Y-52518D01*
X95972Y-52554D01*
X95968Y-52569D01*
X95961Y-52580D01*
X95957Y-52583D01*
Y-52587D01*
X95914Y-52649D01*
X95863Y-52707D01*
X95812Y-52754D01*
X95761Y-52794D01*
X95714Y-52827D01*
X95677Y-52849D01*
X95663Y-52856D01*
X95652Y-52864D01*
X95648Y-52867D01*
X95644D01*
X95568Y-52904D01*
X95488Y-52929D01*
X95415Y-52947D01*
X95346Y-52958D01*
X95288Y-52969D01*
X95266D01*
X95244Y-52973D01*
X95226D01*
X95215D01*
X95208D01*
X95204D01*
X95139Y-52969D01*
X95077Y-52962D01*
X95015Y-52951D01*
X94960Y-52940D01*
X94909Y-52922D01*
X94858Y-52904D01*
X94814Y-52886D01*
X94775Y-52864D01*
X94738Y-52842D01*
X94705Y-52824D01*
X94680Y-52805D01*
X94654Y-52787D01*
X94636Y-52776D01*
X94625Y-52765D01*
X94618Y-52758D01*
X94614Y-52754D01*
X94574Y-52714D01*
X94538Y-52671D01*
X94509Y-52623D01*
X94483Y-52580D01*
X94458Y-52536D01*
X94440Y-52492D01*
X94414Y-52409D01*
X94403Y-52372D01*
X94396Y-52336D01*
X94392Y-52307D01*
X94389Y-52278D01*
X94385Y-52256D01*
Y-52227D01*
X94389Y-52161D01*
X94399Y-52099D01*
X94411Y-52041D01*
X94425Y-51990D01*
X94443Y-51946D01*
X94454Y-51914D01*
X94465Y-51892D01*
X94469Y-51888D01*
Y-51885D01*
X94505Y-51826D01*
X94545Y-51775D01*
X94585Y-51728D01*
X94629Y-51692D01*
X94665Y-51659D01*
X94694Y-51633D01*
X94716Y-51619D01*
X94720Y-51615D01*
X94654D01*
X94589Y-51619D01*
X94531Y-51622D01*
X94472Y-51630D01*
X94421Y-51633D01*
X94374Y-51641D01*
X94330Y-51648D01*
X94290Y-51659D01*
X94254Y-51666D01*
X94225Y-51673D01*
X94199Y-51681D01*
X94178Y-51684D01*
X94163Y-51692D01*
X94152Y-51695D01*
X94145Y-51699D01*
X94141D01*
X94068Y-51735D01*
X94003Y-51772D01*
X93952Y-51812D01*
X93908Y-51848D01*
X93872Y-51881D01*
X93846Y-51906D01*
X93832Y-51925D01*
X93828Y-51932D01*
X93799Y-51976D01*
X93781Y-52019D01*
X93766Y-52063D01*
X93755Y-52106D01*
X93748Y-52139D01*
X93744Y-52168D01*
Y-52194D01*
X93752Y-52259D01*
X93766Y-52321D01*
X93788Y-52372D01*
X93810Y-52420D01*
X93835Y-52456D01*
X93857Y-52481D01*
X93872Y-52496D01*
X93879Y-52503D01*
X93912Y-52529D01*
X93952Y-52554D01*
X93995Y-52576D01*
X94039Y-52591D01*
X94079Y-52605D01*
X94112Y-52616D01*
X94134Y-52620D01*
X94138Y-52623D01*
X94141D01*
X94116Y-52933D01*
X94014Y-52911D01*
X93923Y-52878D01*
X93843Y-52842D01*
X93777Y-52802D01*
X93726Y-52762D01*
X93704Y-52747D01*
X93686Y-52729D01*
X93675Y-52718D01*
X93664Y-52707D01*
X93661Y-52703D01*
X93657Y-52700D01*
X93628Y-52663D01*
X93602Y-52623D01*
X93559Y-52543D01*
X93530Y-52463D01*
X93511Y-52387D01*
X93497Y-52318D01*
X93493Y-52289D01*
Y-52263D01*
X93489Y-52241D01*
Y-52212D01*
X93493Y-52139D01*
X93501Y-52070D01*
X93515Y-52005D01*
X93533Y-51943D01*
X93559Y-51888D01*
X93581Y-51833D01*
X93610Y-51786D01*
X93635Y-51743D01*
X93661Y-51706D01*
X93690Y-51670D01*
X93712Y-51641D01*
X93733Y-51619D01*
X93755Y-51600D01*
X93770Y-51586D01*
X93777Y-51579D01*
X93781Y-51575D01*
X93846Y-51528D01*
X93923Y-51488D01*
X94003Y-51451D01*
X94086Y-51419D01*
X94174Y-51393D01*
X94261Y-51371D01*
X94352Y-51353D01*
X94436Y-51338D01*
X94520Y-51328D01*
X94596Y-51320D01*
X94665Y-51313D01*
X94723Y-51309D01*
X94775D01*
X94811Y-51306D01*
X94825D01*
X94836D01*
X94840D01*
X94844D01*
X94960Y-51309D01*
D02*
G37*
G36*
X100778Y-46464D02*
X100906Y-46479D01*
X101019Y-46497D01*
X101073Y-46511D01*
X101120Y-46522D01*
X101164Y-46533D01*
X101204Y-46548D01*
X101241Y-46559D01*
X101270Y-46566D01*
X101292Y-46577D01*
X101310Y-46580D01*
X101321Y-46588D01*
X101324D01*
X101434Y-46642D01*
X101532Y-46704D01*
X101616Y-46770D01*
X101648Y-46802D01*
X101681Y-46832D01*
X101710Y-46861D01*
X101736Y-46890D01*
X101757Y-46915D01*
X101772Y-46937D01*
X101786Y-46952D01*
X101797Y-46966D01*
X101801Y-46973D01*
X101805Y-46977D01*
X101834Y-47028D01*
X101859Y-47079D01*
X101899Y-47188D01*
X101928Y-47297D01*
X101947Y-47403D01*
X101954Y-47454D01*
X101961Y-47498D01*
X101965Y-47538D01*
Y-47570D01*
X101969Y-47600D01*
Y-47640D01*
X101965Y-47712D01*
X101958Y-47782D01*
X101950Y-47847D01*
X101936Y-47909D01*
X101918Y-47967D01*
X101899Y-48022D01*
X101881Y-48073D01*
X101859Y-48120D01*
X101841Y-48160D01*
X101823Y-48200D01*
X101805Y-48229D01*
X101786Y-48258D01*
X101772Y-48277D01*
X101765Y-48295D01*
X101757Y-48302D01*
X101754Y-48306D01*
X101710Y-48357D01*
X101666Y-48400D01*
X101616Y-48440D01*
X101565Y-48480D01*
X101463Y-48546D01*
X101361Y-48597D01*
X101313Y-48619D01*
X101270Y-48637D01*
X101230Y-48652D01*
X101197Y-48662D01*
X101168Y-48673D01*
X101146Y-48681D01*
X101131Y-48684D01*
X101128D01*
X101044Y-48349D01*
X101102Y-48335D01*
X101157Y-48317D01*
X101208Y-48298D01*
X101255Y-48280D01*
X101299Y-48258D01*
X101335Y-48237D01*
X101372Y-48211D01*
X101404Y-48189D01*
X101434Y-48171D01*
X101455Y-48149D01*
X101477Y-48131D01*
X101495Y-48116D01*
X101506Y-48102D01*
X101517Y-48091D01*
X101521Y-48087D01*
X101524Y-48084D01*
X101554Y-48047D01*
X101575Y-48007D01*
X101616Y-47927D01*
X101645Y-47851D01*
X101663Y-47774D01*
X101677Y-47709D01*
X101681Y-47683D01*
Y-47658D01*
X101685Y-47636D01*
Y-47611D01*
X101681Y-47527D01*
X101666Y-47447D01*
X101648Y-47374D01*
X101626Y-47308D01*
X101604Y-47257D01*
X101594Y-47236D01*
X101586Y-47217D01*
X101579Y-47203D01*
X101572Y-47192D01*
X101568Y-47185D01*
Y-47181D01*
X101517Y-47112D01*
X101463Y-47054D01*
X101401Y-47003D01*
X101342Y-46963D01*
X101292Y-46930D01*
X101248Y-46908D01*
X101230Y-46901D01*
X101219Y-46893D01*
X101211Y-46890D01*
X101208D01*
X101113Y-46861D01*
X101019Y-46839D01*
X100924Y-46821D01*
X100837Y-46810D01*
X100796Y-46806D01*
X100760Y-46802D01*
X100727D01*
X100702Y-46799D01*
X100680D01*
X100662D01*
X100651D01*
X100647D01*
X100553Y-46802D01*
X100465Y-46810D01*
X100385Y-46824D01*
X100312Y-46839D01*
X100250Y-46850D01*
X100225Y-46857D01*
X100203Y-46864D01*
X100185Y-46868D01*
X100174Y-46872D01*
X100167Y-46875D01*
X100163D01*
X100079Y-46912D01*
X100003Y-46952D01*
X99941Y-46995D01*
X99887Y-47043D01*
X99843Y-47083D01*
X99814Y-47115D01*
X99796Y-47141D01*
X99788Y-47145D01*
Y-47148D01*
X99741Y-47225D01*
X99704Y-47308D01*
X99679Y-47388D01*
X99664Y-47465D01*
X99654Y-47534D01*
X99650Y-47563D01*
Y-47589D01*
X99646Y-47607D01*
Y-47636D01*
X99650Y-47727D01*
X99664Y-47811D01*
X99686Y-47880D01*
X99708Y-47942D01*
X99734Y-47989D01*
X99752Y-48026D01*
X99766Y-48047D01*
X99774Y-48055D01*
X99828Y-48113D01*
X99890Y-48167D01*
X99956Y-48211D01*
X100021Y-48248D01*
X100079Y-48277D01*
X100109Y-48288D01*
X100130Y-48295D01*
X100149Y-48302D01*
X100163Y-48309D01*
X100170Y-48313D01*
X100174D01*
X100098Y-48641D01*
X100032Y-48619D01*
X99974Y-48597D01*
X99919Y-48568D01*
X99865Y-48542D01*
X99817Y-48513D01*
X99774Y-48480D01*
X99730Y-48451D01*
X99694Y-48422D01*
X99664Y-48393D01*
X99635Y-48368D01*
X99610Y-48342D01*
X99592Y-48324D01*
X99573Y-48306D01*
X99563Y-48291D01*
X99559Y-48284D01*
X99555Y-48280D01*
X99523Y-48229D01*
X99490Y-48178D01*
X99464Y-48127D01*
X99442Y-48073D01*
X99410Y-47964D01*
X99388Y-47865D01*
X99377Y-47818D01*
X99373Y-47778D01*
X99370Y-47738D01*
X99366Y-47705D01*
X99362Y-47680D01*
Y-47643D01*
X99370Y-47523D01*
X99388Y-47407D01*
X99410Y-47305D01*
X99424Y-47257D01*
X99439Y-47214D01*
X99453Y-47174D01*
X99468Y-47137D01*
X99479Y-47108D01*
X99490Y-47079D01*
X99501Y-47061D01*
X99508Y-47046D01*
X99511Y-47035D01*
X99515Y-47032D01*
X99577Y-46933D01*
X99650Y-46850D01*
X99723Y-46777D01*
X99796Y-46715D01*
X99861Y-46668D01*
X99890Y-46650D01*
X99916Y-46635D01*
X99934Y-46620D01*
X99948Y-46613D01*
X99959Y-46610D01*
X99963Y-46606D01*
X100076Y-46555D01*
X100192Y-46518D01*
X100309Y-46493D01*
X100414Y-46475D01*
X100462Y-46468D01*
X100509Y-46464D01*
X100545Y-46460D01*
X100582D01*
X100607Y-46457D01*
X100629D01*
X100644D01*
X100647D01*
X100778Y-46464D01*
D02*
G37*
G36*
X100305Y-49259D02*
X100280Y-49314D01*
X100254Y-49369D01*
X100229Y-49420D01*
X100207Y-49463D01*
X100189Y-49500D01*
X100174Y-49521D01*
X100170Y-49525D01*
Y-49529D01*
X100130Y-49594D01*
X100090Y-49653D01*
X100054Y-49703D01*
X100021Y-49744D01*
X99996Y-49780D01*
X99974Y-49802D01*
X99959Y-49820D01*
X99956Y-49824D01*
X101925D01*
Y-50133D01*
X99395D01*
Y-49933D01*
X99457Y-49896D01*
X99515Y-49856D01*
X99573Y-49809D01*
X99624Y-49765D01*
X99668Y-49722D01*
X99704Y-49689D01*
X99715Y-49674D01*
X99726Y-49663D01*
X99730Y-49660D01*
X99734Y-49656D01*
X99796Y-49580D01*
X99854Y-49503D01*
X99905Y-49431D01*
X99945Y-49358D01*
X99981Y-49296D01*
X99996Y-49270D01*
X100007Y-49248D01*
X100017Y-49230D01*
X100021Y-49216D01*
X100028Y-49209D01*
Y-49205D01*
X100327D01*
X100305Y-49259D01*
D02*
G37*
G36*
X101324Y-50934D02*
X101379Y-50945D01*
X101481Y-50977D01*
X101568Y-51018D01*
X101608Y-51039D01*
X101641Y-51061D01*
X101674Y-51079D01*
X101703Y-51101D01*
X101725Y-51120D01*
X101743Y-51138D01*
X101757Y-51152D01*
X101772Y-51160D01*
X101776Y-51167D01*
X101779Y-51170D01*
X101812Y-51214D01*
X101841Y-51258D01*
X101867Y-51305D01*
X101889Y-51352D01*
X101921Y-51443D01*
X101943Y-51534D01*
X101954Y-51574D01*
X101958Y-51614D01*
X101961Y-51647D01*
X101965Y-51676D01*
X101969Y-51702D01*
Y-51735D01*
X101965Y-51811D01*
X101954Y-51884D01*
X101939Y-51953D01*
X101921Y-52015D01*
X101896Y-52073D01*
X101870Y-52128D01*
X101845Y-52179D01*
X101816Y-52222D01*
X101786Y-52262D01*
X101761Y-52299D01*
X101732Y-52328D01*
X101710Y-52353D01*
X101692Y-52372D01*
X101677Y-52386D01*
X101666Y-52394D01*
X101663Y-52397D01*
X101616Y-52434D01*
X101565Y-52463D01*
X101517Y-52492D01*
X101466Y-52514D01*
X101368Y-52550D01*
X101273Y-52572D01*
X101233Y-52579D01*
X101193Y-52586D01*
X101161Y-52590D01*
X101131Y-52594D01*
X101106Y-52597D01*
X101088D01*
X101077D01*
X101073D01*
X101008Y-52594D01*
X100946Y-52586D01*
X100884Y-52575D01*
X100829Y-52561D01*
X100778Y-52543D01*
X100727Y-52525D01*
X100684Y-52503D01*
X100644Y-52485D01*
X100607Y-52463D01*
X100574Y-52441D01*
X100549Y-52423D01*
X100523Y-52404D01*
X100505Y-52390D01*
X100494Y-52379D01*
X100487Y-52372D01*
X100483Y-52368D01*
X100443Y-52324D01*
X100407Y-52281D01*
X100378Y-52233D01*
X100352Y-52186D01*
X100327Y-52139D01*
X100309Y-52091D01*
X100283Y-52004D01*
X100272Y-51964D01*
X100265Y-51928D01*
X100261Y-51895D01*
X100258Y-51866D01*
X100254Y-51844D01*
Y-51764D01*
X100261Y-51720D01*
X100280Y-51633D01*
X100305Y-51553D01*
X100334Y-51480D01*
X100363Y-51422D01*
X100378Y-51396D01*
X100389Y-51374D01*
X100400Y-51356D01*
X100407Y-51345D01*
X100411Y-51338D01*
X100414Y-51334D01*
X99734Y-51469D01*
Y-52477D01*
X99439D01*
Y-51225D01*
X100735Y-50981D01*
X100775Y-51272D01*
X100735Y-51298D01*
X100702Y-51331D01*
X100669Y-51360D01*
X100644Y-51389D01*
X100625Y-51418D01*
X100607Y-51440D01*
X100600Y-51454D01*
X100596Y-51458D01*
X100574Y-51505D01*
X100556Y-51553D01*
X100545Y-51596D01*
X100534Y-51640D01*
X100531Y-51676D01*
X100527Y-51705D01*
Y-51775D01*
X100534Y-51818D01*
X100553Y-51895D01*
X100578Y-51960D01*
X100603Y-52019D01*
X100633Y-52062D01*
X100658Y-52095D01*
X100676Y-52113D01*
X100680Y-52121D01*
X100684D01*
X100745Y-52171D01*
X100811Y-52208D01*
X100880Y-52233D01*
X100949Y-52251D01*
X101008Y-52262D01*
X101033Y-52266D01*
X101055D01*
X101073Y-52270D01*
X101088D01*
X101095D01*
X101099D01*
X101149D01*
X101197Y-52262D01*
X101288Y-52244D01*
X101364Y-52219D01*
X101426Y-52193D01*
X101477Y-52164D01*
X101517Y-52139D01*
X101528Y-52128D01*
X101539Y-52121D01*
X101543Y-52117D01*
X101546Y-52113D01*
X101575Y-52084D01*
X101601Y-52055D01*
X101645Y-51989D01*
X101674Y-51928D01*
X101692Y-51866D01*
X101707Y-51815D01*
X101710Y-51771D01*
X101714Y-51757D01*
Y-51735D01*
X101710Y-51666D01*
X101696Y-51604D01*
X101677Y-51549D01*
X101655Y-51505D01*
X101634Y-51465D01*
X101616Y-51436D01*
X101601Y-51422D01*
X101597Y-51414D01*
X101546Y-51371D01*
X101492Y-51334D01*
X101430Y-51305D01*
X101375Y-51283D01*
X101321Y-51269D01*
X101281Y-51258D01*
X101262Y-51254D01*
X101251Y-51250D01*
X101244D01*
X101241D01*
X101266Y-50927D01*
X101324Y-50934D01*
D02*
G37*
G36*
X607744Y-62391D02*
X607806Y-62394D01*
X607864Y-62405D01*
X607919Y-62416D01*
X607970Y-62431D01*
X608017Y-62445D01*
X608061Y-62464D01*
X608101Y-62482D01*
X608137Y-62500D01*
X608166Y-62518D01*
X608192Y-62533D01*
X608214Y-62547D01*
X608232Y-62558D01*
X608243Y-62569D01*
X608250Y-62573D01*
X608254Y-62577D01*
X608290Y-62613D01*
X608323Y-62653D01*
X608356Y-62697D01*
X608381Y-62740D01*
X608425Y-62828D01*
X608454Y-62915D01*
X608465Y-62955D01*
X608476Y-62995D01*
X608483Y-63028D01*
X608490Y-63057D01*
X608494Y-63082D01*
Y-63101D01*
X608497Y-63112D01*
Y-63115D01*
X608181Y-63148D01*
X608174Y-63064D01*
X608159Y-62991D01*
X608137Y-62926D01*
X608112Y-62875D01*
X608090Y-62831D01*
X608068Y-62802D01*
X608053Y-62784D01*
X608046Y-62777D01*
X607992Y-62733D01*
X607933Y-62700D01*
X607871Y-62675D01*
X607817Y-62660D01*
X607766Y-62649D01*
X607722Y-62646D01*
X607708Y-62642D01*
X607686D01*
X607609Y-62646D01*
X607540Y-62660D01*
X607482Y-62682D01*
X607431Y-62704D01*
X607391Y-62729D01*
X607366Y-62748D01*
X607347Y-62762D01*
X607340Y-62769D01*
X607296Y-62820D01*
X607264Y-62871D01*
X607238Y-62922D01*
X607224Y-62973D01*
X607213Y-63013D01*
X607209Y-63050D01*
X607205Y-63072D01*
Y-63075D01*
Y-63079D01*
X607213Y-63144D01*
X607227Y-63213D01*
X607253Y-63275D01*
X607278Y-63334D01*
X607307Y-63381D01*
X607333Y-63421D01*
X607340Y-63436D01*
X607347Y-63446D01*
X607355Y-63450D01*
Y-63454D01*
X607384Y-63494D01*
X607420Y-63534D01*
X607460Y-63578D01*
X607504Y-63621D01*
X607595Y-63709D01*
X607686Y-63796D01*
X607733Y-63836D01*
X607773Y-63872D01*
X607813Y-63905D01*
X607846Y-63934D01*
X607871Y-63956D01*
X607893Y-63974D01*
X607908Y-63985D01*
X607911Y-63989D01*
X608003Y-64065D01*
X608086Y-64138D01*
X608155Y-64204D01*
X608210Y-64258D01*
X608257Y-64306D01*
X608290Y-64338D01*
X608308Y-64360D01*
X608316Y-64364D01*
Y-64367D01*
X608366Y-64429D01*
X608406Y-64487D01*
X608443Y-64546D01*
X608472Y-64597D01*
X608494Y-64640D01*
X608508Y-64673D01*
X608516Y-64695D01*
X608519Y-64699D01*
Y-64702D01*
X608534Y-64742D01*
X608541Y-64779D01*
X608548Y-64815D01*
X608552Y-64848D01*
X608556Y-64877D01*
Y-64899D01*
Y-64913D01*
Y-64917D01*
X606885D01*
Y-64618D01*
X608126D01*
X608082Y-64557D01*
X608061Y-64531D01*
X608042Y-64506D01*
X608024Y-64484D01*
X608010Y-64469D01*
X607999Y-64458D01*
X607995Y-64455D01*
X607977Y-64437D01*
X607955Y-64418D01*
X607904Y-64371D01*
X607846Y-64316D01*
X607784Y-64262D01*
X607726Y-64214D01*
X607700Y-64193D01*
X607679Y-64171D01*
X607660Y-64156D01*
X607646Y-64145D01*
X607639Y-64138D01*
X607635Y-64134D01*
X607577Y-64083D01*
X607518Y-64036D01*
X607467Y-63989D01*
X607420Y-63949D01*
X607376Y-63909D01*
X607340Y-63872D01*
X607304Y-63840D01*
X607274Y-63810D01*
X607245Y-63781D01*
X607224Y-63759D01*
X607205Y-63741D01*
X607187Y-63723D01*
X607169Y-63701D01*
X607162Y-63694D01*
X607111Y-63632D01*
X607067Y-63578D01*
X607031Y-63523D01*
X607001Y-63479D01*
X606980Y-63439D01*
X606965Y-63410D01*
X606958Y-63392D01*
X606954Y-63385D01*
X606932Y-63330D01*
X606918Y-63275D01*
X606903Y-63224D01*
X606896Y-63181D01*
X606892Y-63141D01*
X606889Y-63112D01*
Y-63093D01*
Y-63086D01*
X606892Y-63032D01*
X606899Y-62981D01*
X606907Y-62930D01*
X606921Y-62886D01*
X606958Y-62799D01*
X606994Y-62729D01*
X607016Y-62697D01*
X607034Y-62671D01*
X607052Y-62646D01*
X607071Y-62627D01*
X607085Y-62613D01*
X607093Y-62598D01*
X607100Y-62595D01*
X607103Y-62591D01*
X607143Y-62555D01*
X607187Y-62522D01*
X607234Y-62496D01*
X607282Y-62475D01*
X607376Y-62438D01*
X607471Y-62413D01*
X607511Y-62405D01*
X607551Y-62398D01*
X607587Y-62394D01*
X607617Y-62391D01*
X607642Y-62387D01*
X607679D01*
X607744Y-62391D01*
D02*
G37*
G36*
X609957Y-62362D02*
X610074Y-62380D01*
X610176Y-62402D01*
X610223Y-62416D01*
X610267Y-62431D01*
X610307Y-62445D01*
X610343Y-62460D01*
X610372Y-62471D01*
X610401Y-62482D01*
X610419Y-62493D01*
X610434Y-62500D01*
X610445Y-62504D01*
X610449Y-62507D01*
X610547Y-62569D01*
X610631Y-62642D01*
X610703Y-62715D01*
X610765Y-62788D01*
X610813Y-62853D01*
X610831Y-62882D01*
X610845Y-62908D01*
X610860Y-62926D01*
X610867Y-62941D01*
X610871Y-62951D01*
X610874Y-62955D01*
X610925Y-63068D01*
X610962Y-63184D01*
X610987Y-63301D01*
X611005Y-63406D01*
X611013Y-63454D01*
X611016Y-63501D01*
X611020Y-63537D01*
Y-63574D01*
X611024Y-63599D01*
Y-63621D01*
Y-63636D01*
Y-63639D01*
X611016Y-63770D01*
X611002Y-63898D01*
X610984Y-64011D01*
X610969Y-64065D01*
X610958Y-64113D01*
X610947Y-64156D01*
X610933Y-64196D01*
X610922Y-64233D01*
X610915Y-64262D01*
X610904Y-64284D01*
X610900Y-64302D01*
X610893Y-64313D01*
Y-64316D01*
X610838Y-64426D01*
X610776Y-64524D01*
X610711Y-64608D01*
X610678Y-64640D01*
X610649Y-64673D01*
X610620Y-64702D01*
X610591Y-64728D01*
X610565Y-64750D01*
X610543Y-64764D01*
X610529Y-64779D01*
X610514Y-64790D01*
X610507Y-64793D01*
X610503Y-64797D01*
X610452Y-64826D01*
X610401Y-64851D01*
X610292Y-64891D01*
X610183Y-64921D01*
X610077Y-64939D01*
X610026Y-64946D01*
X609983Y-64953D01*
X609943Y-64957D01*
X609910D01*
X609881Y-64961D01*
X609841D01*
X609768Y-64957D01*
X609699Y-64950D01*
X609633Y-64943D01*
X609571Y-64928D01*
X609513Y-64910D01*
X609458Y-64891D01*
X609408Y-64873D01*
X609360Y-64851D01*
X609320Y-64833D01*
X609280Y-64815D01*
X609251Y-64797D01*
X609222Y-64779D01*
X609204Y-64764D01*
X609186Y-64757D01*
X609178Y-64750D01*
X609174Y-64746D01*
X609124Y-64702D01*
X609080Y-64659D01*
X609040Y-64608D01*
X609000Y-64557D01*
X608934Y-64455D01*
X608883Y-64353D01*
X608861Y-64306D01*
X608843Y-64262D01*
X608829Y-64222D01*
X608818Y-64189D01*
X608807Y-64160D01*
X608800Y-64138D01*
X608796Y-64123D01*
Y-64120D01*
X609131Y-64036D01*
X609145Y-64094D01*
X609164Y-64149D01*
X609182Y-64200D01*
X609200Y-64247D01*
X609222Y-64291D01*
X609244Y-64327D01*
X609269Y-64364D01*
X609291Y-64397D01*
X609309Y-64426D01*
X609331Y-64447D01*
X609349Y-64469D01*
X609364Y-64487D01*
X609378Y-64498D01*
X609389Y-64509D01*
X609393Y-64513D01*
X609397Y-64517D01*
X609433Y-64546D01*
X609473Y-64568D01*
X609553Y-64608D01*
X609630Y-64637D01*
X609706Y-64655D01*
X609771Y-64670D01*
X609797Y-64673D01*
X609823D01*
X609844Y-64677D01*
X609870D01*
X609953Y-64673D01*
X610034Y-64659D01*
X610106Y-64640D01*
X610172Y-64618D01*
X610223Y-64597D01*
X610245Y-64586D01*
X610263Y-64578D01*
X610278Y-64571D01*
X610288Y-64564D01*
X610296Y-64560D01*
X610299D01*
X610368Y-64509D01*
X610427Y-64455D01*
X610478Y-64393D01*
X610518Y-64335D01*
X610550Y-64284D01*
X610572Y-64240D01*
X610580Y-64222D01*
X610587Y-64211D01*
X610591Y-64204D01*
Y-64200D01*
X610620Y-64105D01*
X610641Y-64011D01*
X610660Y-63916D01*
X610671Y-63829D01*
X610674Y-63789D01*
X610678Y-63752D01*
Y-63719D01*
X610681Y-63694D01*
Y-63672D01*
Y-63654D01*
Y-63643D01*
Y-63639D01*
X610678Y-63545D01*
X610671Y-63457D01*
X610656Y-63377D01*
X610641Y-63305D01*
X610631Y-63243D01*
X610623Y-63217D01*
X610616Y-63195D01*
X610612Y-63177D01*
X610609Y-63166D01*
X610605Y-63159D01*
Y-63155D01*
X610569Y-63072D01*
X610529Y-62995D01*
X610485Y-62933D01*
X610438Y-62879D01*
X610398Y-62835D01*
X610365Y-62806D01*
X610339Y-62788D01*
X610336Y-62780D01*
X610332D01*
X610256Y-62733D01*
X610172Y-62697D01*
X610092Y-62671D01*
X610015Y-62657D01*
X609946Y-62646D01*
X609917Y-62642D01*
X609892D01*
X609873Y-62638D01*
X609844D01*
X609753Y-62642D01*
X609670Y-62657D01*
X609600Y-62678D01*
X609539Y-62700D01*
X609491Y-62726D01*
X609455Y-62744D01*
X609433Y-62758D01*
X609426Y-62766D01*
X609368Y-62820D01*
X609313Y-62882D01*
X609269Y-62948D01*
X609233Y-63013D01*
X609204Y-63072D01*
X609193Y-63101D01*
X609186Y-63122D01*
X609178Y-63141D01*
X609171Y-63155D01*
X609167Y-63162D01*
Y-63166D01*
X608840Y-63090D01*
X608861Y-63024D01*
X608883Y-62966D01*
X608913Y-62911D01*
X608938Y-62857D01*
X608967Y-62809D01*
X609000Y-62766D01*
X609029Y-62722D01*
X609058Y-62686D01*
X609087Y-62657D01*
X609113Y-62627D01*
X609138Y-62602D01*
X609156Y-62584D01*
X609174Y-62566D01*
X609189Y-62555D01*
X609196Y-62551D01*
X609200Y-62547D01*
X609251Y-62515D01*
X609302Y-62482D01*
X609353Y-62456D01*
X609408Y-62435D01*
X609517Y-62402D01*
X609615Y-62380D01*
X609662Y-62369D01*
X609702Y-62365D01*
X609742Y-62362D01*
X609775Y-62358D01*
X609801Y-62354D01*
X609837D01*
X609957Y-62362D01*
D02*
G37*
G36*
X605829Y-62394D02*
X605920Y-62409D01*
X605997Y-62435D01*
X606062Y-62460D01*
X606117Y-62489D01*
X606139Y-62500D01*
X606157Y-62515D01*
X606172Y-62522D01*
X606182Y-62529D01*
X606186Y-62536D01*
X606190D01*
X606255Y-62595D01*
X606310Y-62664D01*
X606357Y-62733D01*
X606394Y-62799D01*
X606423Y-62860D01*
X606437Y-62886D01*
X606445Y-62911D01*
X606452Y-62930D01*
X606459Y-62944D01*
X606463Y-62951D01*
Y-62955D01*
X606477Y-63010D01*
X606492Y-63064D01*
X606514Y-63184D01*
X606532Y-63305D01*
X606543Y-63417D01*
X606546Y-63472D01*
X606550Y-63519D01*
Y-63563D01*
X606554Y-63603D01*
Y-63632D01*
Y-63658D01*
Y-63672D01*
Y-63676D01*
X606550Y-63803D01*
X606543Y-63923D01*
X606532Y-64033D01*
X606514Y-64134D01*
X606496Y-64229D01*
X606474Y-64313D01*
X606452Y-64389D01*
X606430Y-64455D01*
X606408Y-64513D01*
X606383Y-64564D01*
X606364Y-64608D01*
X606346Y-64640D01*
X606328Y-64670D01*
X606317Y-64688D01*
X606310Y-64699D01*
X606306Y-64702D01*
X606266Y-64746D01*
X606222Y-64786D01*
X606175Y-64822D01*
X606128Y-64851D01*
X606081Y-64877D01*
X606033Y-64899D01*
X605986Y-64913D01*
X605942Y-64928D01*
X605899Y-64939D01*
X605859Y-64946D01*
X605822Y-64953D01*
X605793Y-64957D01*
X605767Y-64961D01*
X605731D01*
X605633Y-64953D01*
X605542Y-64939D01*
X605465Y-64913D01*
X605400Y-64888D01*
X605345Y-64862D01*
X605327Y-64848D01*
X605309Y-64837D01*
X605294Y-64830D01*
X605283Y-64822D01*
X605280Y-64815D01*
X605276D01*
X605211Y-64753D01*
X605156Y-64688D01*
X605109Y-64615D01*
X605072Y-64549D01*
X605043Y-64487D01*
X605029Y-64462D01*
X605021Y-64437D01*
X605014Y-64418D01*
X605007Y-64404D01*
X605003Y-64397D01*
Y-64393D01*
X604985Y-64338D01*
X604970Y-64284D01*
X604949Y-64167D01*
X604930Y-64047D01*
X604919Y-63931D01*
X604916Y-63880D01*
X604912Y-63832D01*
Y-63789D01*
X604909Y-63749D01*
Y-63719D01*
Y-63694D01*
Y-63679D01*
Y-63676D01*
Y-63607D01*
X604912Y-63541D01*
Y-63483D01*
X604916Y-63425D01*
X604923Y-63374D01*
X604927Y-63323D01*
X604930Y-63279D01*
X604938Y-63239D01*
X604941Y-63203D01*
X604949Y-63170D01*
X604952Y-63144D01*
X604956Y-63122D01*
X604959Y-63104D01*
X604963Y-63093D01*
X604967Y-63086D01*
Y-63082D01*
X604989Y-63002D01*
X605014Y-62930D01*
X605043Y-62868D01*
X605065Y-62813D01*
X605091Y-62766D01*
X605105Y-62733D01*
X605120Y-62715D01*
X605123Y-62708D01*
X605163Y-62653D01*
X605203Y-62606D01*
X605247Y-62566D01*
X605287Y-62529D01*
X605323Y-62504D01*
X605352Y-62485D01*
X605371Y-62475D01*
X605374Y-62471D01*
X605378D01*
X605436Y-62442D01*
X605498Y-62424D01*
X605556Y-62409D01*
X605611Y-62398D01*
X605658Y-62391D01*
X605698Y-62387D01*
X605731D01*
X605829Y-62394D01*
D02*
G37*
G36*
X146889Y-122979D02*
X146598Y-123019D01*
X146573Y-122979D01*
X146540Y-122946D01*
X146511Y-122913D01*
X146482Y-122888D01*
X146453Y-122870D01*
X146431Y-122851D01*
X146416Y-122844D01*
X146413Y-122840D01*
X146365Y-122819D01*
X146318Y-122800D01*
X146274Y-122789D01*
X146231Y-122778D01*
X146194Y-122775D01*
X146165Y-122771D01*
X146096D01*
X146052Y-122778D01*
X145976Y-122797D01*
X145910Y-122822D01*
X145852Y-122848D01*
X145808Y-122877D01*
X145776Y-122902D01*
X145757Y-122921D01*
X145750Y-122924D01*
Y-122928D01*
X145699Y-122990D01*
X145663Y-123055D01*
X145637Y-123124D01*
X145619Y-123194D01*
X145608Y-123252D01*
X145605Y-123277D01*
Y-123299D01*
X145601Y-123317D01*
Y-123332D01*
Y-123339D01*
Y-123343D01*
Y-123394D01*
X145608Y-123441D01*
X145626Y-123532D01*
X145652Y-123608D01*
X145677Y-123670D01*
X145706Y-123721D01*
X145732Y-123761D01*
X145743Y-123772D01*
X145750Y-123783D01*
X145754Y-123787D01*
X145757Y-123790D01*
X145786Y-123819D01*
X145816Y-123845D01*
X145881Y-123889D01*
X145943Y-123918D01*
X146005Y-123936D01*
X146056Y-123951D01*
X146099Y-123954D01*
X146114Y-123958D01*
X146136D01*
X146205Y-123954D01*
X146267Y-123940D01*
X146322Y-123922D01*
X146365Y-123900D01*
X146405Y-123878D01*
X146434Y-123860D01*
X146449Y-123845D01*
X146456Y-123841D01*
X146500Y-123790D01*
X146536Y-123736D01*
X146565Y-123674D01*
X146587Y-123619D01*
X146602Y-123565D01*
X146613Y-123525D01*
X146616Y-123506D01*
X146620Y-123496D01*
Y-123488D01*
Y-123485D01*
X146944Y-123510D01*
X146937Y-123568D01*
X146926Y-123623D01*
X146893Y-123725D01*
X146853Y-123812D01*
X146831Y-123852D01*
X146809Y-123885D01*
X146791Y-123918D01*
X146769Y-123947D01*
X146751Y-123969D01*
X146733Y-123987D01*
X146718Y-124002D01*
X146711Y-124016D01*
X146704Y-124020D01*
X146700Y-124023D01*
X146656Y-124056D01*
X146613Y-124085D01*
X146565Y-124111D01*
X146518Y-124133D01*
X146427Y-124165D01*
X146336Y-124187D01*
X146296Y-124198D01*
X146256Y-124202D01*
X146223Y-124205D01*
X146194Y-124209D01*
X146169Y-124213D01*
X146136D01*
X146060Y-124209D01*
X145987Y-124198D01*
X145917Y-124183D01*
X145856Y-124165D01*
X145797Y-124140D01*
X145743Y-124114D01*
X145692Y-124089D01*
X145648Y-124060D01*
X145608Y-124031D01*
X145572Y-124005D01*
X145543Y-123976D01*
X145517Y-123954D01*
X145499Y-123936D01*
X145484Y-123922D01*
X145477Y-123910D01*
X145473Y-123907D01*
X145437Y-123860D01*
X145408Y-123809D01*
X145379Y-123761D01*
X145357Y-123710D01*
X145321Y-123612D01*
X145299Y-123517D01*
X145291Y-123477D01*
X145284Y-123437D01*
X145281Y-123405D01*
X145277Y-123375D01*
X145273Y-123350D01*
Y-123332D01*
Y-123321D01*
Y-123317D01*
X145277Y-123252D01*
X145284Y-123190D01*
X145295Y-123128D01*
X145310Y-123073D01*
X145328Y-123022D01*
X145346Y-122971D01*
X145368Y-122928D01*
X145386Y-122888D01*
X145408Y-122851D01*
X145430Y-122819D01*
X145448Y-122793D01*
X145466Y-122768D01*
X145481Y-122749D01*
X145492Y-122738D01*
X145499Y-122731D01*
X145503Y-122728D01*
X145546Y-122687D01*
X145590Y-122651D01*
X145637Y-122622D01*
X145685Y-122597D01*
X145732Y-122571D01*
X145779Y-122553D01*
X145867Y-122527D01*
X145907Y-122516D01*
X145943Y-122509D01*
X145976Y-122505D01*
X146005Y-122502D01*
X146027Y-122498D01*
X146107D01*
X146151Y-122505D01*
X146238Y-122524D01*
X146318Y-122549D01*
X146391Y-122578D01*
X146449Y-122607D01*
X146474Y-122622D01*
X146496Y-122633D01*
X146514Y-122644D01*
X146525Y-122651D01*
X146533Y-122655D01*
X146536Y-122658D01*
X146402Y-121978D01*
X145393D01*
Y-121683D01*
X146645D01*
X146889Y-122979D01*
D02*
G37*
G36*
X148083Y-121643D02*
X148152Y-121650D01*
X148218Y-121665D01*
X148280Y-121683D01*
X148335Y-121708D01*
X148389Y-121730D01*
X148436Y-121759D01*
X148480Y-121785D01*
X148516Y-121810D01*
X148553Y-121839D01*
X148582Y-121861D01*
X148604Y-121883D01*
X148622Y-121905D01*
X148637Y-121920D01*
X148644Y-121927D01*
X148647Y-121930D01*
X148695Y-121996D01*
X148735Y-122072D01*
X148771Y-122152D01*
X148804Y-122236D01*
X148829Y-122324D01*
X148851Y-122411D01*
X148870Y-122502D01*
X148884Y-122586D01*
X148895Y-122669D01*
X148902Y-122746D01*
X148910Y-122815D01*
X148913Y-122873D01*
Y-122924D01*
X148917Y-122960D01*
Y-122975D01*
Y-122986D01*
Y-122990D01*
Y-122993D01*
X148913Y-123110D01*
X148906Y-123219D01*
X148895Y-123321D01*
X148877Y-123416D01*
X148859Y-123499D01*
X148840Y-123576D01*
X148819Y-123645D01*
X148793Y-123707D01*
X148771Y-123758D01*
X148749Y-123805D01*
X148731Y-123841D01*
X148709Y-123874D01*
X148695Y-123900D01*
X148684Y-123914D01*
X148677Y-123925D01*
X148673Y-123929D01*
X148626Y-123980D01*
X148575Y-124023D01*
X148524Y-124060D01*
X148473Y-124092D01*
X148418Y-124122D01*
X148367Y-124144D01*
X148316Y-124162D01*
X148265Y-124176D01*
X148222Y-124187D01*
X148178Y-124198D01*
X148142Y-124205D01*
X148109Y-124209D01*
X148080D01*
X148062Y-124213D01*
X148043D01*
X147960Y-124209D01*
X147883Y-124195D01*
X147814Y-124180D01*
X147752Y-124158D01*
X147705Y-124140D01*
X147668Y-124122D01*
X147654Y-124118D01*
X147643Y-124111D01*
X147639Y-124107D01*
X147636D01*
X147574Y-124063D01*
X147515Y-124012D01*
X147468Y-123961D01*
X147428Y-123910D01*
X147395Y-123863D01*
X147373Y-123827D01*
X147366Y-123812D01*
X147359Y-123801D01*
X147355Y-123798D01*
Y-123794D01*
X147319Y-123718D01*
X147293Y-123637D01*
X147275Y-123565D01*
X147264Y-123496D01*
X147253Y-123437D01*
Y-123416D01*
X147250Y-123394D01*
Y-123375D01*
Y-123364D01*
Y-123357D01*
Y-123354D01*
X147253Y-123288D01*
X147261Y-123226D01*
X147272Y-123164D01*
X147283Y-123110D01*
X147301Y-123059D01*
X147319Y-123008D01*
X147337Y-122964D01*
X147359Y-122924D01*
X147381Y-122888D01*
X147399Y-122855D01*
X147417Y-122829D01*
X147435Y-122804D01*
X147446Y-122786D01*
X147457Y-122775D01*
X147465Y-122768D01*
X147468Y-122764D01*
X147508Y-122724D01*
X147552Y-122687D01*
X147599Y-122658D01*
X147643Y-122633D01*
X147687Y-122607D01*
X147730Y-122589D01*
X147814Y-122564D01*
X147850Y-122553D01*
X147887Y-122546D01*
X147916Y-122542D01*
X147945Y-122538D01*
X147967Y-122535D01*
X147996D01*
X148062Y-122538D01*
X148123Y-122549D01*
X148182Y-122560D01*
X148233Y-122575D01*
X148276Y-122593D01*
X148309Y-122604D01*
X148331Y-122615D01*
X148335Y-122618D01*
X148338D01*
X148396Y-122655D01*
X148447Y-122695D01*
X148495Y-122735D01*
X148531Y-122778D01*
X148564Y-122815D01*
X148589Y-122844D01*
X148604Y-122866D01*
X148608Y-122870D01*
Y-122804D01*
X148604Y-122738D01*
X148600Y-122680D01*
X148593Y-122622D01*
X148589Y-122571D01*
X148582Y-122524D01*
X148575Y-122480D01*
X148564Y-122440D01*
X148556Y-122404D01*
X148549Y-122374D01*
X148542Y-122349D01*
X148538Y-122327D01*
X148531Y-122313D01*
X148527Y-122302D01*
X148524Y-122294D01*
Y-122291D01*
X148487Y-122218D01*
X148451Y-122152D01*
X148411Y-122101D01*
X148374Y-122058D01*
X148342Y-122021D01*
X148316Y-121996D01*
X148298Y-121981D01*
X148291Y-121978D01*
X148247Y-121949D01*
X148203Y-121930D01*
X148160Y-121916D01*
X148116Y-121905D01*
X148083Y-121898D01*
X148054Y-121894D01*
X148029D01*
X147963Y-121901D01*
X147901Y-121916D01*
X147850Y-121938D01*
X147803Y-121959D01*
X147767Y-121985D01*
X147741Y-122007D01*
X147727Y-122021D01*
X147719Y-122029D01*
X147694Y-122061D01*
X147668Y-122101D01*
X147646Y-122145D01*
X147632Y-122189D01*
X147617Y-122229D01*
X147607Y-122262D01*
X147603Y-122283D01*
X147599Y-122287D01*
Y-122291D01*
X147290Y-122265D01*
X147312Y-122163D01*
X147344Y-122072D01*
X147381Y-121992D01*
X147421Y-121927D01*
X147461Y-121876D01*
X147475Y-121854D01*
X147494Y-121836D01*
X147505Y-121825D01*
X147515Y-121814D01*
X147519Y-121810D01*
X147523Y-121807D01*
X147559Y-121777D01*
X147599Y-121752D01*
X147679Y-121708D01*
X147759Y-121679D01*
X147836Y-121661D01*
X147905Y-121646D01*
X147934Y-121643D01*
X147960D01*
X147981Y-121639D01*
X148011D01*
X148083Y-121643D01*
D02*
G37*
G36*
X150347Y-121614D02*
X150464Y-121632D01*
X150566Y-121654D01*
X150613Y-121668D01*
X150657Y-121683D01*
X150697Y-121697D01*
X150733Y-121712D01*
X150762Y-121723D01*
X150792Y-121734D01*
X150810Y-121745D01*
X150824Y-121752D01*
X150835Y-121756D01*
X150839Y-121759D01*
X150937Y-121821D01*
X151021Y-121894D01*
X151094Y-121967D01*
X151155Y-122040D01*
X151203Y-122105D01*
X151221Y-122134D01*
X151236Y-122160D01*
X151250Y-122178D01*
X151257Y-122193D01*
X151261Y-122203D01*
X151265Y-122207D01*
X151316Y-122320D01*
X151352Y-122436D01*
X151377Y-122553D01*
X151396Y-122658D01*
X151403Y-122706D01*
X151407Y-122753D01*
X151410Y-122789D01*
Y-122826D01*
X151414Y-122851D01*
Y-122873D01*
Y-122888D01*
Y-122891D01*
X151407Y-123022D01*
X151392Y-123150D01*
X151374Y-123263D01*
X151359Y-123317D01*
X151348Y-123364D01*
X151338Y-123408D01*
X151323Y-123448D01*
X151312Y-123485D01*
X151305Y-123514D01*
X151294Y-123536D01*
X151290Y-123554D01*
X151283Y-123565D01*
Y-123568D01*
X151228Y-123678D01*
X151166Y-123776D01*
X151101Y-123860D01*
X151068Y-123892D01*
X151039Y-123925D01*
X151010Y-123954D01*
X150981Y-123980D01*
X150955Y-124002D01*
X150933Y-124016D01*
X150919Y-124031D01*
X150904Y-124042D01*
X150897Y-124045D01*
X150893Y-124049D01*
X150842Y-124078D01*
X150792Y-124103D01*
X150682Y-124144D01*
X150573Y-124173D01*
X150468Y-124191D01*
X150417Y-124198D01*
X150373Y-124205D01*
X150333Y-124209D01*
X150300D01*
X150271Y-124213D01*
X150231D01*
X150158Y-124209D01*
X150089Y-124202D01*
X150023Y-124195D01*
X149962Y-124180D01*
X149903Y-124162D01*
X149849Y-124144D01*
X149798Y-124125D01*
X149750Y-124103D01*
X149710Y-124085D01*
X149670Y-124067D01*
X149641Y-124049D01*
X149612Y-124031D01*
X149594Y-124016D01*
X149576Y-124009D01*
X149568Y-124002D01*
X149565Y-123998D01*
X149514Y-123954D01*
X149470Y-123910D01*
X149430Y-123860D01*
X149390Y-123809D01*
X149325Y-123707D01*
X149274Y-123605D01*
X149252Y-123557D01*
X149234Y-123514D01*
X149219Y-123474D01*
X149208Y-123441D01*
X149197Y-123412D01*
X149190Y-123390D01*
X149186Y-123375D01*
Y-123372D01*
X149521Y-123288D01*
X149536Y-123346D01*
X149554Y-123401D01*
X149572Y-123452D01*
X149590Y-123499D01*
X149612Y-123543D01*
X149634Y-123579D01*
X149659Y-123616D01*
X149681Y-123649D01*
X149699Y-123678D01*
X149721Y-123699D01*
X149740Y-123721D01*
X149754Y-123740D01*
X149769Y-123750D01*
X149780Y-123761D01*
X149783Y-123765D01*
X149787Y-123769D01*
X149823Y-123798D01*
X149863Y-123819D01*
X149943Y-123860D01*
X150020Y-123889D01*
X150096Y-123907D01*
X150162Y-123922D01*
X150187Y-123925D01*
X150213D01*
X150235Y-123929D01*
X150260D01*
X150344Y-123925D01*
X150424Y-123910D01*
X150497Y-123892D01*
X150562Y-123871D01*
X150613Y-123849D01*
X150635Y-123838D01*
X150653Y-123830D01*
X150668Y-123823D01*
X150679Y-123816D01*
X150686Y-123812D01*
X150690D01*
X150759Y-123761D01*
X150817Y-123707D01*
X150868Y-123645D01*
X150908Y-123587D01*
X150941Y-123536D01*
X150963Y-123492D01*
X150970Y-123474D01*
X150977Y-123463D01*
X150981Y-123456D01*
Y-123452D01*
X151010Y-123357D01*
X151032Y-123263D01*
X151050Y-123168D01*
X151061Y-123081D01*
X151065Y-123041D01*
X151068Y-123004D01*
Y-122971D01*
X151072Y-122946D01*
Y-122924D01*
Y-122906D01*
Y-122895D01*
Y-122891D01*
X151068Y-122797D01*
X151061Y-122709D01*
X151046Y-122629D01*
X151032Y-122556D01*
X151021Y-122495D01*
X151014Y-122469D01*
X151006Y-122447D01*
X151003Y-122429D01*
X150999Y-122418D01*
X150995Y-122411D01*
Y-122407D01*
X150959Y-122324D01*
X150919Y-122247D01*
X150875Y-122185D01*
X150828Y-122131D01*
X150788Y-122087D01*
X150755Y-122058D01*
X150730Y-122040D01*
X150726Y-122032D01*
X150722D01*
X150646Y-121985D01*
X150562Y-121949D01*
X150482Y-121923D01*
X150406Y-121908D01*
X150337Y-121898D01*
X150307Y-121894D01*
X150282D01*
X150264Y-121890D01*
X150235D01*
X150144Y-121894D01*
X150060Y-121908D01*
X149991Y-121930D01*
X149929Y-121952D01*
X149881Y-121978D01*
X149845Y-121996D01*
X149823Y-122010D01*
X149816Y-122018D01*
X149758Y-122072D01*
X149703Y-122134D01*
X149659Y-122200D01*
X149623Y-122265D01*
X149594Y-122324D01*
X149583Y-122353D01*
X149576Y-122374D01*
X149568Y-122393D01*
X149561Y-122407D01*
X149557Y-122415D01*
Y-122418D01*
X149230Y-122342D01*
X149252Y-122276D01*
X149274Y-122218D01*
X149303Y-122163D01*
X149328Y-122109D01*
X149357Y-122061D01*
X149390Y-122018D01*
X149419Y-121974D01*
X149448Y-121938D01*
X149477Y-121908D01*
X149503Y-121879D01*
X149528Y-121854D01*
X149547Y-121836D01*
X149565Y-121818D01*
X149579Y-121807D01*
X149587Y-121803D01*
X149590Y-121799D01*
X149641Y-121767D01*
X149692Y-121734D01*
X149743Y-121708D01*
X149798Y-121686D01*
X149907Y-121654D01*
X150005Y-121632D01*
X150053Y-121621D01*
X150093Y-121617D01*
X150133Y-121614D01*
X150165Y-121610D01*
X150191Y-121606D01*
X150227D01*
X150347Y-121614D01*
D02*
G37*
G36*
X163770Y-101582D02*
X163898Y-101597D01*
X164011Y-101615D01*
X164065Y-101629D01*
X164113Y-101640D01*
X164156Y-101651D01*
X164196Y-101666D01*
X164233Y-101677D01*
X164262Y-101684D01*
X164284Y-101695D01*
X164302Y-101699D01*
X164313Y-101706D01*
X164316D01*
X164426Y-101760D01*
X164524Y-101822D01*
X164608Y-101888D01*
X164640Y-101920D01*
X164673Y-101950D01*
X164702Y-101979D01*
X164728Y-102008D01*
X164750Y-102033D01*
X164764Y-102055D01*
X164779Y-102070D01*
X164790Y-102084D01*
X164793Y-102092D01*
X164797Y-102095D01*
X164826Y-102146D01*
X164851Y-102197D01*
X164892Y-102306D01*
X164921Y-102416D01*
X164939Y-102521D01*
X164946Y-102572D01*
X164953Y-102616D01*
X164957Y-102656D01*
Y-102689D01*
X164961Y-102718D01*
Y-102758D01*
X164957Y-102831D01*
X164950Y-102900D01*
X164943Y-102965D01*
X164928Y-103027D01*
X164910Y-103085D01*
X164892Y-103140D01*
X164873Y-103191D01*
X164851Y-103238D01*
X164833Y-103278D01*
X164815Y-103318D01*
X164797Y-103347D01*
X164779Y-103376D01*
X164764Y-103395D01*
X164757Y-103413D01*
X164750Y-103420D01*
X164746Y-103424D01*
X164702Y-103475D01*
X164659Y-103518D01*
X164608Y-103559D01*
X164557Y-103599D01*
X164455Y-103664D01*
X164353Y-103715D01*
X164305Y-103737D01*
X164262Y-103755D01*
X164222Y-103770D01*
X164189Y-103781D01*
X164160Y-103791D01*
X164138Y-103799D01*
X164123Y-103802D01*
X164120D01*
X164036Y-103468D01*
X164094Y-103453D01*
X164149Y-103435D01*
X164200Y-103417D01*
X164247Y-103398D01*
X164291Y-103376D01*
X164327Y-103355D01*
X164364Y-103329D01*
X164397Y-103307D01*
X164426Y-103289D01*
X164447Y-103267D01*
X164469Y-103249D01*
X164488Y-103235D01*
X164498Y-103220D01*
X164509Y-103209D01*
X164513Y-103206D01*
X164517Y-103202D01*
X164546Y-103165D01*
X164568Y-103125D01*
X164608Y-103045D01*
X164637Y-102969D01*
X164655Y-102892D01*
X164670Y-102827D01*
X164673Y-102801D01*
Y-102776D01*
X164677Y-102754D01*
Y-102729D01*
X164673Y-102645D01*
X164659Y-102565D01*
X164640Y-102492D01*
X164619Y-102427D01*
X164597Y-102375D01*
X164586Y-102354D01*
X164578Y-102336D01*
X164571Y-102321D01*
X164564Y-102310D01*
X164560Y-102303D01*
Y-102299D01*
X164509Y-102230D01*
X164455Y-102172D01*
X164393Y-102121D01*
X164335Y-102081D01*
X164284Y-102048D01*
X164240Y-102026D01*
X164222Y-102019D01*
X164211Y-102012D01*
X164204Y-102008D01*
X164200D01*
X164105Y-101979D01*
X164011Y-101957D01*
X163916Y-101939D01*
X163829Y-101928D01*
X163789Y-101924D01*
X163752Y-101920D01*
X163719D01*
X163694Y-101917D01*
X163672D01*
X163654D01*
X163643D01*
X163639D01*
X163545Y-101920D01*
X163457Y-101928D01*
X163377Y-101942D01*
X163304Y-101957D01*
X163243Y-101968D01*
X163217Y-101975D01*
X163195Y-101982D01*
X163177Y-101986D01*
X163166Y-101990D01*
X163159Y-101993D01*
X163155D01*
X163072Y-102030D01*
X162995Y-102070D01*
X162933Y-102113D01*
X162879Y-102161D01*
X162835Y-102201D01*
X162806Y-102234D01*
X162788Y-102259D01*
X162780Y-102263D01*
Y-102266D01*
X162733Y-102343D01*
X162697Y-102427D01*
X162671Y-102507D01*
X162657Y-102583D01*
X162646Y-102652D01*
X162642Y-102681D01*
Y-102707D01*
X162638Y-102725D01*
Y-102754D01*
X162642Y-102845D01*
X162657Y-102929D01*
X162678Y-102998D01*
X162700Y-103060D01*
X162726Y-103107D01*
X162744Y-103144D01*
X162759Y-103165D01*
X162766Y-103173D01*
X162820Y-103231D01*
X162882Y-103286D01*
X162948Y-103329D01*
X163013Y-103366D01*
X163072Y-103395D01*
X163101Y-103406D01*
X163122Y-103413D01*
X163141Y-103420D01*
X163155Y-103428D01*
X163163Y-103431D01*
X163166D01*
X163090Y-103759D01*
X163024Y-103737D01*
X162966Y-103715D01*
X162911Y-103686D01*
X162857Y-103661D01*
X162809Y-103631D01*
X162766Y-103599D01*
X162722Y-103569D01*
X162686Y-103540D01*
X162657Y-103511D01*
X162627Y-103486D01*
X162602Y-103460D01*
X162584Y-103442D01*
X162566Y-103424D01*
X162555Y-103409D01*
X162551Y-103402D01*
X162547Y-103398D01*
X162515Y-103347D01*
X162482Y-103296D01*
X162456Y-103245D01*
X162434Y-103191D01*
X162402Y-103082D01*
X162380Y-102983D01*
X162369Y-102936D01*
X162365Y-102896D01*
X162362Y-102856D01*
X162358Y-102823D01*
X162354Y-102798D01*
Y-102761D01*
X162362Y-102641D01*
X162380Y-102525D01*
X162402Y-102423D01*
X162416Y-102375D01*
X162431Y-102332D01*
X162445Y-102292D01*
X162460Y-102255D01*
X162471Y-102226D01*
X162482Y-102197D01*
X162493Y-102179D01*
X162500Y-102164D01*
X162504Y-102154D01*
X162507Y-102150D01*
X162569Y-102052D01*
X162642Y-101968D01*
X162715Y-101895D01*
X162788Y-101833D01*
X162853Y-101786D01*
X162882Y-101768D01*
X162908Y-101753D01*
X162926Y-101739D01*
X162941Y-101731D01*
X162951Y-101728D01*
X162955Y-101724D01*
X163068Y-101673D01*
X163184Y-101637D01*
X163301Y-101611D01*
X163406Y-101593D01*
X163454Y-101586D01*
X163501Y-101582D01*
X163537Y-101578D01*
X163574D01*
X163599Y-101575D01*
X163621D01*
X163636D01*
X163639D01*
X163770Y-101582D01*
D02*
G37*
G36*
X163858Y-104075D02*
X163967Y-104083D01*
X164069Y-104094D01*
X164163Y-104112D01*
X164247Y-104130D01*
X164324Y-104148D01*
X164393Y-104170D01*
X164455Y-104195D01*
X164506Y-104217D01*
X164553Y-104239D01*
X164589Y-104257D01*
X164622Y-104279D01*
X164648Y-104294D01*
X164662Y-104305D01*
X164673Y-104312D01*
X164677Y-104316D01*
X164728Y-104363D01*
X164771Y-104414D01*
X164808Y-104465D01*
X164841Y-104516D01*
X164870Y-104570D01*
X164892Y-104621D01*
X164910Y-104672D01*
X164924Y-104723D01*
X164935Y-104767D01*
X164946Y-104811D01*
X164953Y-104847D01*
X164957Y-104880D01*
Y-104909D01*
X164961Y-104927D01*
Y-104945D01*
X164957Y-105029D01*
X164943Y-105105D01*
X164928Y-105175D01*
X164906Y-105237D01*
X164888Y-105284D01*
X164870Y-105320D01*
X164866Y-105335D01*
X164859Y-105346D01*
X164855Y-105349D01*
Y-105353D01*
X164811Y-105415D01*
X164760Y-105473D01*
X164709Y-105520D01*
X164659Y-105561D01*
X164611Y-105593D01*
X164575Y-105615D01*
X164560Y-105622D01*
X164549Y-105630D01*
X164546Y-105633D01*
X164542D01*
X164466Y-105670D01*
X164386Y-105695D01*
X164313Y-105713D01*
X164244Y-105724D01*
X164185Y-105735D01*
X164163D01*
X164142Y-105739D01*
X164123D01*
X164113D01*
X164105D01*
X164102D01*
X164036Y-105735D01*
X163974Y-105728D01*
X163912Y-105717D01*
X163858Y-105706D01*
X163807Y-105688D01*
X163756Y-105670D01*
X163712Y-105651D01*
X163672Y-105630D01*
X163636Y-105608D01*
X163603Y-105590D01*
X163577Y-105571D01*
X163552Y-105553D01*
X163534Y-105542D01*
X163523Y-105531D01*
X163516Y-105524D01*
X163512Y-105520D01*
X163472Y-105481D01*
X163435Y-105437D01*
X163406Y-105389D01*
X163381Y-105346D01*
X163355Y-105302D01*
X163337Y-105258D01*
X163312Y-105175D01*
X163301Y-105138D01*
X163294Y-105102D01*
X163290Y-105073D01*
X163286Y-105044D01*
X163283Y-105022D01*
Y-104993D01*
X163286Y-104927D01*
X163297Y-104865D01*
X163308Y-104807D01*
X163323Y-104756D01*
X163341Y-104712D01*
X163352Y-104680D01*
X163363Y-104658D01*
X163366Y-104654D01*
Y-104650D01*
X163403Y-104592D01*
X163443Y-104541D01*
X163483Y-104494D01*
X163526Y-104458D01*
X163563Y-104425D01*
X163592Y-104399D01*
X163614Y-104385D01*
X163618Y-104381D01*
X163552D01*
X163487Y-104385D01*
X163428Y-104388D01*
X163370Y-104396D01*
X163319Y-104399D01*
X163272Y-104407D01*
X163228Y-104414D01*
X163188Y-104425D01*
X163152Y-104432D01*
X163122Y-104439D01*
X163097Y-104447D01*
X163075Y-104450D01*
X163061Y-104458D01*
X163050Y-104461D01*
X163042Y-104465D01*
X163039D01*
X162966Y-104501D01*
X162900Y-104538D01*
X162849Y-104578D01*
X162806Y-104614D01*
X162769Y-104647D01*
X162744Y-104672D01*
X162729Y-104691D01*
X162726Y-104698D01*
X162697Y-104742D01*
X162678Y-104785D01*
X162664Y-104829D01*
X162653Y-104873D01*
X162646Y-104905D01*
X162642Y-104935D01*
Y-104960D01*
X162649Y-105025D01*
X162664Y-105087D01*
X162686Y-105138D01*
X162707Y-105186D01*
X162733Y-105222D01*
X162755Y-105247D01*
X162769Y-105262D01*
X162777Y-105269D01*
X162809Y-105295D01*
X162849Y-105320D01*
X162893Y-105342D01*
X162937Y-105357D01*
X162977Y-105371D01*
X163010Y-105382D01*
X163031Y-105386D01*
X163035Y-105389D01*
X163039D01*
X163013Y-105699D01*
X162911Y-105677D01*
X162820Y-105644D01*
X162740Y-105608D01*
X162675Y-105568D01*
X162624Y-105528D01*
X162602Y-105513D01*
X162584Y-105495D01*
X162573Y-105484D01*
X162562Y-105473D01*
X162558Y-105470D01*
X162555Y-105466D01*
X162525Y-105429D01*
X162500Y-105389D01*
X162456Y-105309D01*
X162427Y-105229D01*
X162409Y-105153D01*
X162394Y-105084D01*
X162391Y-105055D01*
Y-105029D01*
X162387Y-105007D01*
Y-104978D01*
X162391Y-104905D01*
X162398Y-104836D01*
X162413Y-104771D01*
X162431Y-104709D01*
X162456Y-104654D01*
X162478Y-104600D01*
X162507Y-104552D01*
X162533Y-104509D01*
X162558Y-104472D01*
X162587Y-104436D01*
X162609Y-104407D01*
X162631Y-104385D01*
X162653Y-104367D01*
X162668Y-104352D01*
X162675Y-104345D01*
X162678Y-104341D01*
X162744Y-104294D01*
X162820Y-104254D01*
X162900Y-104217D01*
X162984Y-104185D01*
X163072Y-104159D01*
X163159Y-104137D01*
X163250Y-104119D01*
X163334Y-104104D01*
X163417Y-104094D01*
X163494Y-104086D01*
X163563Y-104079D01*
X163621Y-104075D01*
X163672D01*
X163708Y-104072D01*
X163723D01*
X163734D01*
X163738D01*
X163741D01*
X163858Y-104075D01*
D02*
G37*
G36*
X151959Y-101582D02*
X152087Y-101597D01*
X152200Y-101615D01*
X152254Y-101629D01*
X152302Y-101640D01*
X152345Y-101651D01*
X152385Y-101666D01*
X152422Y-101677D01*
X152451Y-101684D01*
X152473Y-101695D01*
X152491Y-101699D01*
X152502Y-101706D01*
X152505D01*
X152615Y-101760D01*
X152713Y-101822D01*
X152797Y-101888D01*
X152829Y-101921D01*
X152862Y-101950D01*
X152891Y-101979D01*
X152917Y-102008D01*
X152938Y-102033D01*
X152953Y-102055D01*
X152968Y-102070D01*
X152979Y-102084D01*
X152982Y-102092D01*
X152986Y-102095D01*
X153015Y-102146D01*
X153040Y-102197D01*
X153080Y-102306D01*
X153110Y-102416D01*
X153128Y-102521D01*
X153135Y-102572D01*
X153142Y-102616D01*
X153146Y-102656D01*
Y-102689D01*
X153150Y-102718D01*
Y-102758D01*
X153146Y-102831D01*
X153139Y-102900D01*
X153131Y-102965D01*
X153117Y-103027D01*
X153099Y-103085D01*
X153080Y-103140D01*
X153062Y-103191D01*
X153040Y-103238D01*
X153022Y-103278D01*
X153004Y-103318D01*
X152986Y-103347D01*
X152968Y-103376D01*
X152953Y-103395D01*
X152946Y-103413D01*
X152938Y-103420D01*
X152935Y-103424D01*
X152891Y-103475D01*
X152848Y-103518D01*
X152797Y-103559D01*
X152746Y-103599D01*
X152644Y-103664D01*
X152542Y-103715D01*
X152494Y-103737D01*
X152451Y-103755D01*
X152411Y-103770D01*
X152378Y-103781D01*
X152349Y-103791D01*
X152327Y-103799D01*
X152312Y-103802D01*
X152309D01*
X152225Y-103468D01*
X152283Y-103453D01*
X152338Y-103435D01*
X152389Y-103417D01*
X152436Y-103398D01*
X152480Y-103376D01*
X152516Y-103355D01*
X152553Y-103329D01*
X152585Y-103307D01*
X152615Y-103289D01*
X152636Y-103267D01*
X152658Y-103249D01*
X152676Y-103235D01*
X152687Y-103220D01*
X152698Y-103209D01*
X152702Y-103206D01*
X152706Y-103202D01*
X152735Y-103165D01*
X152757Y-103125D01*
X152797Y-103045D01*
X152826Y-102969D01*
X152844Y-102892D01*
X152858Y-102827D01*
X152862Y-102801D01*
Y-102776D01*
X152866Y-102754D01*
Y-102729D01*
X152862Y-102645D01*
X152848Y-102565D01*
X152829Y-102492D01*
X152807Y-102427D01*
X152786Y-102375D01*
X152775Y-102354D01*
X152767Y-102336D01*
X152760Y-102321D01*
X152753Y-102310D01*
X152749Y-102303D01*
Y-102299D01*
X152698Y-102230D01*
X152644Y-102172D01*
X152582Y-102121D01*
X152524Y-102081D01*
X152473Y-102048D01*
X152429Y-102026D01*
X152411Y-102019D01*
X152400Y-102012D01*
X152392Y-102008D01*
X152389D01*
X152294Y-101979D01*
X152200Y-101957D01*
X152105Y-101939D01*
X152018Y-101928D01*
X151978Y-101924D01*
X151941Y-101921D01*
X151908D01*
X151883Y-101917D01*
X151861D01*
X151843D01*
X151832D01*
X151828D01*
X151734Y-101921D01*
X151646Y-101928D01*
X151566Y-101942D01*
X151493Y-101957D01*
X151432Y-101968D01*
X151406Y-101975D01*
X151384Y-101982D01*
X151366Y-101986D01*
X151355Y-101990D01*
X151348Y-101993D01*
X151344D01*
X151260Y-102030D01*
X151184Y-102070D01*
X151122Y-102113D01*
X151068Y-102161D01*
X151024Y-102201D01*
X150995Y-102234D01*
X150977Y-102259D01*
X150969Y-102263D01*
Y-102266D01*
X150922Y-102343D01*
X150886Y-102427D01*
X150860Y-102507D01*
X150846Y-102583D01*
X150835Y-102652D01*
X150831Y-102681D01*
Y-102707D01*
X150827Y-102725D01*
Y-102754D01*
X150831Y-102845D01*
X150846Y-102929D01*
X150867Y-102998D01*
X150889Y-103060D01*
X150915Y-103107D01*
X150933Y-103144D01*
X150947Y-103165D01*
X150955Y-103173D01*
X151009Y-103231D01*
X151071Y-103286D01*
X151137Y-103329D01*
X151202Y-103366D01*
X151260Y-103395D01*
X151290Y-103406D01*
X151311Y-103413D01*
X151330Y-103420D01*
X151344Y-103428D01*
X151351Y-103431D01*
X151355D01*
X151279Y-103759D01*
X151213Y-103737D01*
X151155Y-103715D01*
X151100Y-103686D01*
X151046Y-103661D01*
X150998Y-103631D01*
X150955Y-103599D01*
X150911Y-103569D01*
X150875Y-103540D01*
X150846Y-103511D01*
X150816Y-103486D01*
X150791Y-103460D01*
X150773Y-103442D01*
X150754Y-103424D01*
X150744Y-103409D01*
X150740Y-103402D01*
X150736Y-103398D01*
X150704Y-103347D01*
X150671Y-103296D01*
X150645Y-103245D01*
X150624Y-103191D01*
X150591Y-103082D01*
X150569Y-102983D01*
X150558Y-102936D01*
X150554Y-102896D01*
X150551Y-102856D01*
X150547Y-102823D01*
X150543Y-102798D01*
Y-102761D01*
X150551Y-102641D01*
X150569Y-102525D01*
X150591Y-102423D01*
X150605Y-102375D01*
X150620Y-102332D01*
X150634Y-102292D01*
X150649Y-102255D01*
X150660Y-102226D01*
X150671Y-102197D01*
X150682Y-102179D01*
X150689Y-102164D01*
X150693Y-102154D01*
X150696Y-102150D01*
X150758Y-102052D01*
X150831Y-101968D01*
X150904Y-101895D01*
X150977Y-101833D01*
X151042Y-101786D01*
X151071Y-101768D01*
X151097Y-101753D01*
X151115Y-101739D01*
X151129Y-101731D01*
X151140Y-101728D01*
X151144Y-101724D01*
X151257Y-101673D01*
X151373Y-101637D01*
X151490Y-101611D01*
X151595Y-101593D01*
X151643Y-101586D01*
X151690Y-101582D01*
X151726Y-101578D01*
X151763D01*
X151788Y-101575D01*
X151810D01*
X151825D01*
X151828D01*
X151959Y-101582D01*
D02*
G37*
G36*
X151497Y-104090D02*
X151559Y-104097D01*
X151621Y-104104D01*
X151679Y-104119D01*
X151730Y-104137D01*
X151781Y-104156D01*
X151825Y-104174D01*
X151865Y-104196D01*
X151901Y-104214D01*
X151934Y-104232D01*
X151959Y-104250D01*
X151985Y-104268D01*
X152003Y-104283D01*
X152014Y-104290D01*
X152021Y-104297D01*
X152025Y-104301D01*
X152065Y-104341D01*
X152098Y-104385D01*
X152130Y-104429D01*
X152156Y-104476D01*
X152178Y-104519D01*
X152196Y-104563D01*
X152221Y-104647D01*
X152232Y-104683D01*
X152240Y-104720D01*
X152243Y-104749D01*
X152247Y-104778D01*
X152251Y-104800D01*
Y-104829D01*
X152247Y-104898D01*
X152236Y-104964D01*
X152221Y-105022D01*
X152203Y-105076D01*
X152189Y-105116D01*
X152174Y-105149D01*
X152163Y-105171D01*
X152160Y-105178D01*
X152123Y-105237D01*
X152083Y-105288D01*
X152043Y-105331D01*
X152007Y-105368D01*
X151970Y-105393D01*
X151945Y-105415D01*
X151927Y-105429D01*
X151919Y-105433D01*
X151948D01*
X151967D01*
X151978D01*
X151981D01*
X152054Y-105429D01*
X152123Y-105426D01*
X152185Y-105419D01*
X152243Y-105411D01*
X152291Y-105400D01*
X152327Y-105393D01*
X152342Y-105389D01*
X152352D01*
X152356Y-105386D01*
X152360D01*
X152425Y-105368D01*
X152483Y-105349D01*
X152534Y-105331D01*
X152578Y-105313D01*
X152611Y-105298D01*
X152636Y-105284D01*
X152655Y-105277D01*
X152658Y-105273D01*
X152698Y-105244D01*
X152731Y-105215D01*
X152760Y-105186D01*
X152786Y-105157D01*
X152807Y-105135D01*
X152822Y-105113D01*
X152829Y-105098D01*
X152833Y-105095D01*
X152855Y-105055D01*
X152869Y-105011D01*
X152880Y-104971D01*
X152888Y-104931D01*
X152891Y-104898D01*
X152895Y-104873D01*
Y-104847D01*
X152891Y-104789D01*
X152880Y-104734D01*
X152866Y-104687D01*
X152848Y-104647D01*
X152833Y-104618D01*
X152818Y-104592D01*
X152807Y-104578D01*
X152804Y-104574D01*
X152764Y-104538D01*
X152717Y-104509D01*
X152665Y-104483D01*
X152615Y-104465D01*
X152571Y-104450D01*
X152531Y-104439D01*
X152516Y-104436D01*
X152509D01*
X152502Y-104432D01*
X152498D01*
X152524Y-104134D01*
X152629Y-104156D01*
X152720Y-104185D01*
X152800Y-104221D01*
X152866Y-104257D01*
X152917Y-104294D01*
X152938Y-104312D01*
X152957Y-104327D01*
X152968Y-104338D01*
X152979Y-104348D01*
X152982Y-104352D01*
X152986Y-104356D01*
X153015Y-104392D01*
X153040Y-104432D01*
X153080Y-104512D01*
X153110Y-104592D01*
X153128Y-104669D01*
X153142Y-104738D01*
X153146Y-104767D01*
Y-104792D01*
X153150Y-104811D01*
Y-104840D01*
X153142Y-104942D01*
X153128Y-105033D01*
X153102Y-105116D01*
X153073Y-105186D01*
X153062Y-105215D01*
X153048Y-105244D01*
X153033Y-105266D01*
X153022Y-105288D01*
X153015Y-105302D01*
X153008Y-105313D01*
X153000Y-105320D01*
Y-105324D01*
X152938Y-105397D01*
X152869Y-105462D01*
X152797Y-105513D01*
X152727Y-105557D01*
X152665Y-105593D01*
X152636Y-105608D01*
X152615Y-105619D01*
X152593Y-105626D01*
X152578Y-105633D01*
X152571Y-105637D01*
X152567D01*
X152513Y-105655D01*
X152451Y-105673D01*
X152327Y-105699D01*
X152196Y-105717D01*
X152072Y-105728D01*
X152018Y-105735D01*
X151963Y-105739D01*
X151916D01*
X151876Y-105743D01*
X151843D01*
X151817D01*
X151799D01*
X151796D01*
X151712D01*
X151632Y-105739D01*
X151559Y-105732D01*
X151490Y-105724D01*
X151428Y-105717D01*
X151370Y-105710D01*
X151315Y-105699D01*
X151268Y-105688D01*
X151228Y-105677D01*
X151191Y-105670D01*
X151159Y-105659D01*
X151133Y-105651D01*
X151115Y-105644D01*
X151100Y-105637D01*
X151093Y-105633D01*
X151089D01*
X151002Y-105590D01*
X150926Y-105542D01*
X150860Y-105488D01*
X150805Y-105440D01*
X150765Y-105393D01*
X150736Y-105357D01*
X150725Y-105342D01*
X150718Y-105331D01*
X150711Y-105328D01*
Y-105324D01*
X150667Y-105247D01*
X150634Y-105171D01*
X150609Y-105095D01*
X150594Y-105025D01*
X150583Y-104964D01*
X150580Y-104938D01*
Y-104920D01*
X150576Y-104902D01*
Y-104876D01*
X150580Y-104814D01*
X150587Y-104756D01*
X150598Y-104698D01*
X150613Y-104647D01*
X150653Y-104549D01*
X150671Y-104505D01*
X150693Y-104469D01*
X150718Y-104432D01*
X150736Y-104403D01*
X150758Y-104374D01*
X150776Y-104352D01*
X150791Y-104334D01*
X150802Y-104323D01*
X150809Y-104316D01*
X150813Y-104312D01*
X150856Y-104272D01*
X150907Y-104239D01*
X150955Y-104207D01*
X151006Y-104181D01*
X151060Y-104159D01*
X151111Y-104141D01*
X151206Y-104115D01*
X151253Y-104104D01*
X151293Y-104097D01*
X151333Y-104094D01*
X151366Y-104090D01*
X151391Y-104086D01*
X151410D01*
X151424D01*
X151428D01*
X151497Y-104090D01*
D02*
G37*
G36*
X159535Y-93871D02*
X159615Y-93886D01*
X159684Y-93907D01*
X159742Y-93929D01*
X159790Y-93951D01*
X159826Y-93973D01*
X159848Y-93988D01*
X159855Y-93991D01*
X159910Y-94042D01*
X159957Y-94097D01*
X159994Y-94155D01*
X160023Y-94213D01*
X160045Y-94264D01*
X160059Y-94304D01*
X160063Y-94319D01*
X160066Y-94330D01*
X160070Y-94337D01*
Y-94341D01*
X160103Y-94279D01*
X160136Y-94228D01*
X160172Y-94184D01*
X160205Y-94148D01*
X160234Y-94119D01*
X160259Y-94097D01*
X160274Y-94086D01*
X160281Y-94082D01*
X160332Y-94053D01*
X160383Y-94031D01*
X160434Y-94013D01*
X160481Y-94002D01*
X160521Y-93995D01*
X160550Y-93991D01*
X160572D01*
X160580D01*
X160642Y-93995D01*
X160703Y-94006D01*
X160758Y-94020D01*
X160805Y-94038D01*
X160845Y-94057D01*
X160878Y-94071D01*
X160896Y-94082D01*
X160904Y-94086D01*
X160958Y-94122D01*
X161005Y-94166D01*
X161046Y-94210D01*
X161082Y-94253D01*
X161107Y-94290D01*
X161129Y-94322D01*
X161140Y-94344D01*
X161144Y-94348D01*
Y-94352D01*
X161173Y-94417D01*
X161195Y-94483D01*
X161213Y-94548D01*
X161224Y-94606D01*
X161231Y-94654D01*
X161235Y-94694D01*
Y-94785D01*
X161228Y-94836D01*
X161209Y-94934D01*
X161180Y-95018D01*
X161151Y-95091D01*
X161133Y-95123D01*
X161118Y-95149D01*
X161104Y-95174D01*
X161089Y-95192D01*
X161078Y-95207D01*
X161071Y-95218D01*
X161067Y-95225D01*
X161064Y-95229D01*
X160995Y-95298D01*
X160918Y-95353D01*
X160838Y-95396D01*
X160758Y-95433D01*
X160689Y-95455D01*
X160660Y-95465D01*
X160634Y-95473D01*
X160612Y-95476D01*
X160598Y-95480D01*
X160587Y-95484D01*
X160583D01*
X160529Y-95174D01*
X160609Y-95160D01*
X160678Y-95138D01*
X160736Y-95112D01*
X160784Y-95087D01*
X160820Y-95061D01*
X160845Y-95039D01*
X160864Y-95025D01*
X160867Y-95021D01*
X160904Y-94974D01*
X160933Y-94923D01*
X160951Y-94876D01*
X160966Y-94828D01*
X160973Y-94785D01*
X160980Y-94752D01*
Y-94723D01*
X160976Y-94657D01*
X160962Y-94599D01*
X160944Y-94548D01*
X160925Y-94504D01*
X160904Y-94472D01*
X160885Y-94446D01*
X160871Y-94428D01*
X160867Y-94424D01*
X160824Y-94384D01*
X160776Y-94355D01*
X160729Y-94337D01*
X160685Y-94322D01*
X160645Y-94315D01*
X160616Y-94308D01*
X160594D01*
X160591D01*
X160587D01*
X160547D01*
X160511Y-94315D01*
X160449Y-94333D01*
X160394Y-94359D01*
X160347Y-94388D01*
X160314Y-94417D01*
X160288Y-94443D01*
X160274Y-94461D01*
X160270Y-94464D01*
Y-94468D01*
X160238Y-94530D01*
X160212Y-94588D01*
X160194Y-94650D01*
X160183Y-94705D01*
X160176Y-94752D01*
X160168Y-94792D01*
Y-94839D01*
X160172Y-94854D01*
Y-94872D01*
X159899Y-94908D01*
X159910Y-94861D01*
X159917Y-94818D01*
X159924Y-94781D01*
X159928Y-94748D01*
X159932Y-94723D01*
Y-94690D01*
X159924Y-94614D01*
X159910Y-94545D01*
X159888Y-94483D01*
X159863Y-94432D01*
X159837Y-94392D01*
X159815Y-94362D01*
X159801Y-94344D01*
X159793Y-94337D01*
X159739Y-94290D01*
X159681Y-94253D01*
X159622Y-94228D01*
X159564Y-94213D01*
X159517Y-94202D01*
X159477Y-94199D01*
X159462Y-94195D01*
X159451D01*
X159444D01*
X159440D01*
X159360Y-94202D01*
X159287Y-94221D01*
X159226Y-94242D01*
X159171Y-94271D01*
X159127Y-94301D01*
X159095Y-94322D01*
X159073Y-94341D01*
X159065Y-94348D01*
X159014Y-94406D01*
X158978Y-94468D01*
X158953Y-94530D01*
X158934Y-94588D01*
X158923Y-94639D01*
X158920Y-94679D01*
X158916Y-94694D01*
Y-94716D01*
X158920Y-94781D01*
X158934Y-94843D01*
X158953Y-94898D01*
X158974Y-94941D01*
X158993Y-94978D01*
X159011Y-95007D01*
X159025Y-95021D01*
X159029Y-95029D01*
X159080Y-95072D01*
X159138Y-95109D01*
X159200Y-95141D01*
X159266Y-95167D01*
X159320Y-95185D01*
X159346Y-95192D01*
X159368Y-95196D01*
X159386Y-95200D01*
X159400Y-95203D01*
X159408Y-95207D01*
X159411D01*
X159371Y-95516D01*
X159313Y-95509D01*
X159258Y-95498D01*
X159156Y-95465D01*
X159069Y-95425D01*
X159033Y-95403D01*
X158996Y-95382D01*
X158964Y-95360D01*
X158938Y-95338D01*
X158913Y-95320D01*
X158894Y-95302D01*
X158880Y-95291D01*
X158869Y-95280D01*
X158862Y-95272D01*
X158858Y-95269D01*
X158825Y-95225D01*
X158792Y-95182D01*
X158767Y-95138D01*
X158745Y-95091D01*
X158709Y-94999D01*
X158687Y-94912D01*
X158680Y-94872D01*
X158672Y-94836D01*
X158669Y-94803D01*
X158665Y-94774D01*
X158661Y-94752D01*
Y-94719D01*
X158665Y-94650D01*
X158672Y-94588D01*
X158683Y-94526D01*
X158698Y-94468D01*
X158716Y-94413D01*
X158734Y-94366D01*
X158756Y-94319D01*
X158778Y-94279D01*
X158796Y-94239D01*
X158818Y-94206D01*
X158836Y-94177D01*
X158854Y-94155D01*
X158869Y-94137D01*
X158880Y-94122D01*
X158887Y-94115D01*
X158891Y-94111D01*
X158934Y-94068D01*
X158982Y-94031D01*
X159029Y-93998D01*
X159076Y-93969D01*
X159120Y-93947D01*
X159167Y-93926D01*
X159255Y-93897D01*
X159295Y-93889D01*
X159331Y-93882D01*
X159364Y-93875D01*
X159393Y-93871D01*
X159415Y-93867D01*
X159433D01*
X159444D01*
X159448D01*
X159535Y-93871D01*
D02*
G37*
G36*
Y-95829D02*
X159615Y-95844D01*
X159684Y-95866D01*
X159742Y-95888D01*
X159790Y-95910D01*
X159826Y-95931D01*
X159848Y-95946D01*
X159855Y-95950D01*
X159910Y-96000D01*
X159957Y-96055D01*
X159994Y-96113D01*
X160023Y-96172D01*
X160045Y-96223D01*
X160059Y-96263D01*
X160063Y-96277D01*
X160066Y-96288D01*
X160070Y-96295D01*
Y-96299D01*
X160103Y-96237D01*
X160136Y-96186D01*
X160172Y-96142D01*
X160205Y-96106D01*
X160234Y-96077D01*
X160259Y-96055D01*
X160274Y-96044D01*
X160281Y-96040D01*
X160332Y-96011D01*
X160383Y-95990D01*
X160434Y-95971D01*
X160481Y-95960D01*
X160521Y-95953D01*
X160550Y-95950D01*
X160572D01*
X160580D01*
X160642Y-95953D01*
X160703Y-95964D01*
X160758Y-95979D01*
X160805Y-95997D01*
X160845Y-96015D01*
X160878Y-96030D01*
X160896Y-96040D01*
X160904Y-96044D01*
X160958Y-96081D01*
X161005Y-96124D01*
X161046Y-96168D01*
X161082Y-96212D01*
X161107Y-96248D01*
X161129Y-96281D01*
X161140Y-96303D01*
X161144Y-96306D01*
Y-96310D01*
X161173Y-96375D01*
X161195Y-96441D01*
X161213Y-96506D01*
X161224Y-96565D01*
X161231Y-96612D01*
X161235Y-96652D01*
Y-96743D01*
X161228Y-96794D01*
X161209Y-96892D01*
X161180Y-96976D01*
X161151Y-97049D01*
X161133Y-97082D01*
X161118Y-97107D01*
X161104Y-97132D01*
X161089Y-97151D01*
X161078Y-97165D01*
X161071Y-97176D01*
X161067Y-97184D01*
X161064Y-97187D01*
X160995Y-97256D01*
X160918Y-97311D01*
X160838Y-97355D01*
X160758Y-97391D01*
X160689Y-97413D01*
X160660Y-97424D01*
X160634Y-97431D01*
X160612Y-97435D01*
X160598Y-97438D01*
X160587Y-97442D01*
X160583D01*
X160529Y-97132D01*
X160609Y-97118D01*
X160678Y-97096D01*
X160736Y-97071D01*
X160784Y-97045D01*
X160820Y-97020D01*
X160845Y-96998D01*
X160864Y-96983D01*
X160867Y-96980D01*
X160904Y-96932D01*
X160933Y-96881D01*
X160951Y-96834D01*
X160966Y-96787D01*
X160973Y-96743D01*
X160980Y-96710D01*
Y-96681D01*
X160976Y-96616D01*
X160962Y-96557D01*
X160944Y-96506D01*
X160925Y-96463D01*
X160904Y-96430D01*
X160885Y-96404D01*
X160871Y-96386D01*
X160867Y-96383D01*
X160824Y-96343D01*
X160776Y-96314D01*
X160729Y-96295D01*
X160685Y-96281D01*
X160645Y-96273D01*
X160616Y-96266D01*
X160594D01*
X160591D01*
X160587D01*
X160547D01*
X160511Y-96273D01*
X160449Y-96292D01*
X160394Y-96317D01*
X160347Y-96346D01*
X160314Y-96375D01*
X160288Y-96401D01*
X160274Y-96419D01*
X160270Y-96423D01*
Y-96426D01*
X160238Y-96488D01*
X160212Y-96547D01*
X160194Y-96608D01*
X160183Y-96663D01*
X160176Y-96710D01*
X160168Y-96750D01*
Y-96798D01*
X160172Y-96812D01*
Y-96830D01*
X159899Y-96867D01*
X159910Y-96820D01*
X159917Y-96776D01*
X159924Y-96739D01*
X159928Y-96707D01*
X159932Y-96681D01*
Y-96648D01*
X159924Y-96572D01*
X159910Y-96503D01*
X159888Y-96441D01*
X159863Y-96390D01*
X159837Y-96350D01*
X159815Y-96321D01*
X159801Y-96303D01*
X159793Y-96295D01*
X159739Y-96248D01*
X159681Y-96212D01*
X159622Y-96186D01*
X159564Y-96172D01*
X159517Y-96161D01*
X159477Y-96157D01*
X159462Y-96153D01*
X159451D01*
X159444D01*
X159440D01*
X159360Y-96161D01*
X159287Y-96179D01*
X159226Y-96201D01*
X159171Y-96230D01*
X159127Y-96259D01*
X159095Y-96281D01*
X159073Y-96299D01*
X159065Y-96306D01*
X159014Y-96364D01*
X158978Y-96426D01*
X158953Y-96488D01*
X158934Y-96547D01*
X158923Y-96597D01*
X158920Y-96637D01*
X158916Y-96652D01*
Y-96674D01*
X158920Y-96739D01*
X158934Y-96801D01*
X158953Y-96856D01*
X158974Y-96900D01*
X158993Y-96936D01*
X159011Y-96965D01*
X159025Y-96980D01*
X159029Y-96987D01*
X159080Y-97031D01*
X159138Y-97067D01*
X159200Y-97100D01*
X159266Y-97125D01*
X159320Y-97143D01*
X159346Y-97151D01*
X159368Y-97154D01*
X159386Y-97158D01*
X159400Y-97162D01*
X159408Y-97165D01*
X159411D01*
X159371Y-97475D01*
X159313Y-97467D01*
X159258Y-97457D01*
X159156Y-97424D01*
X159069Y-97384D01*
X159033Y-97362D01*
X158996Y-97340D01*
X158964Y-97318D01*
X158938Y-97296D01*
X158913Y-97278D01*
X158894Y-97260D01*
X158880Y-97249D01*
X158869Y-97238D01*
X158862Y-97231D01*
X158858Y-97227D01*
X158825Y-97184D01*
X158792Y-97140D01*
X158767Y-97096D01*
X158745Y-97049D01*
X158709Y-96958D01*
X158687Y-96870D01*
X158680Y-96830D01*
X158672Y-96794D01*
X158669Y-96761D01*
X158665Y-96732D01*
X158661Y-96710D01*
Y-96678D01*
X158665Y-96608D01*
X158672Y-96547D01*
X158683Y-96485D01*
X158698Y-96426D01*
X158716Y-96372D01*
X158734Y-96324D01*
X158756Y-96277D01*
X158778Y-96237D01*
X158796Y-96197D01*
X158818Y-96164D01*
X158836Y-96135D01*
X158854Y-96113D01*
X158869Y-96095D01*
X158880Y-96081D01*
X158887Y-96073D01*
X158891Y-96070D01*
X158934Y-96026D01*
X158982Y-95990D01*
X159029Y-95957D01*
X159076Y-95928D01*
X159120Y-95906D01*
X159167Y-95884D01*
X159255Y-95855D01*
X159295Y-95848D01*
X159331Y-95840D01*
X159364Y-95833D01*
X159393Y-95829D01*
X159415Y-95826D01*
X159433D01*
X159444D01*
X159448D01*
X159535Y-95829D01*
D02*
G37*
G36*
X159586Y-98097D02*
X159528Y-98112D01*
X159473Y-98130D01*
X159422Y-98148D01*
X159375Y-98166D01*
X159331Y-98188D01*
X159295Y-98210D01*
X159258Y-98235D01*
X159226Y-98257D01*
X159196Y-98276D01*
X159175Y-98297D01*
X159153Y-98316D01*
X159135Y-98330D01*
X159124Y-98345D01*
X159113Y-98356D01*
X159109Y-98359D01*
X159105Y-98363D01*
X159076Y-98399D01*
X159055Y-98439D01*
X159014Y-98519D01*
X158985Y-98596D01*
X158967Y-98672D01*
X158953Y-98738D01*
X158949Y-98763D01*
Y-98789D01*
X158945Y-98811D01*
Y-98836D01*
X158949Y-98920D01*
X158964Y-99000D01*
X158982Y-99073D01*
X159003Y-99138D01*
X159025Y-99189D01*
X159036Y-99211D01*
X159044Y-99229D01*
X159051Y-99244D01*
X159058Y-99255D01*
X159062Y-99262D01*
Y-99266D01*
X159113Y-99335D01*
X159167Y-99393D01*
X159229Y-99444D01*
X159287Y-99484D01*
X159338Y-99517D01*
X159382Y-99539D01*
X159400Y-99546D01*
X159411Y-99553D01*
X159418Y-99557D01*
X159422D01*
X159517Y-99586D01*
X159611Y-99608D01*
X159706Y-99626D01*
X159793Y-99637D01*
X159833Y-99641D01*
X159870Y-99644D01*
X159903D01*
X159928Y-99648D01*
X159950D01*
X159968D01*
X159979D01*
X159983D01*
X160077Y-99644D01*
X160165Y-99637D01*
X160245Y-99622D01*
X160318Y-99608D01*
X160379Y-99597D01*
X160405Y-99590D01*
X160427Y-99582D01*
X160445Y-99579D01*
X160456Y-99575D01*
X160463Y-99571D01*
X160467D01*
X160550Y-99535D01*
X160627Y-99495D01*
X160689Y-99451D01*
X160743Y-99404D01*
X160787Y-99364D01*
X160816Y-99331D01*
X160834Y-99306D01*
X160842Y-99302D01*
Y-99298D01*
X160889Y-99222D01*
X160925Y-99138D01*
X160951Y-99058D01*
X160966Y-98982D01*
X160976Y-98913D01*
X160980Y-98883D01*
Y-98858D01*
X160984Y-98840D01*
Y-98811D01*
X160980Y-98720D01*
X160966Y-98636D01*
X160944Y-98567D01*
X160922Y-98505D01*
X160896Y-98457D01*
X160878Y-98421D01*
X160864Y-98399D01*
X160856Y-98392D01*
X160802Y-98334D01*
X160740Y-98279D01*
X160674Y-98235D01*
X160609Y-98199D01*
X160550Y-98170D01*
X160521Y-98159D01*
X160500Y-98152D01*
X160481Y-98144D01*
X160467Y-98137D01*
X160459Y-98133D01*
X160456D01*
X160532Y-97806D01*
X160598Y-97828D01*
X160656Y-97850D01*
X160711Y-97879D01*
X160765Y-97904D01*
X160813Y-97933D01*
X160856Y-97966D01*
X160900Y-97995D01*
X160936Y-98024D01*
X160966Y-98053D01*
X160995Y-98079D01*
X161020Y-98104D01*
X161038Y-98123D01*
X161056Y-98141D01*
X161067Y-98155D01*
X161071Y-98163D01*
X161075Y-98166D01*
X161107Y-98217D01*
X161140Y-98268D01*
X161166Y-98319D01*
X161188Y-98374D01*
X161220Y-98483D01*
X161242Y-98581D01*
X161253Y-98629D01*
X161257Y-98669D01*
X161260Y-98709D01*
X161264Y-98741D01*
X161268Y-98767D01*
Y-98803D01*
X161260Y-98923D01*
X161242Y-99040D01*
X161220Y-99142D01*
X161206Y-99189D01*
X161191Y-99233D01*
X161177Y-99273D01*
X161162Y-99309D01*
X161151Y-99338D01*
X161140Y-99367D01*
X161129Y-99386D01*
X161122Y-99400D01*
X161118Y-99411D01*
X161115Y-99415D01*
X161053Y-99513D01*
X160980Y-99597D01*
X160907Y-99670D01*
X160834Y-99731D01*
X160769Y-99779D01*
X160740Y-99797D01*
X160714Y-99812D01*
X160696Y-99826D01*
X160682Y-99833D01*
X160671Y-99837D01*
X160667Y-99841D01*
X160554Y-99892D01*
X160438Y-99928D01*
X160321Y-99954D01*
X160216Y-99972D01*
X160168Y-99979D01*
X160121Y-99983D01*
X160085Y-99986D01*
X160048D01*
X160023Y-99990D01*
X160001D01*
X159986D01*
X159983D01*
X159852Y-99983D01*
X159724Y-99968D01*
X159611Y-99950D01*
X159557Y-99935D01*
X159510Y-99924D01*
X159466Y-99914D01*
X159426Y-99899D01*
X159389Y-99888D01*
X159360Y-99881D01*
X159338Y-99870D01*
X159320Y-99866D01*
X159309Y-99859D01*
X159306D01*
X159196Y-99804D01*
X159098Y-99742D01*
X159014Y-99677D01*
X158982Y-99644D01*
X158949Y-99615D01*
X158920Y-99586D01*
X158894Y-99557D01*
X158872Y-99531D01*
X158858Y-99509D01*
X158843Y-99495D01*
X158832Y-99480D01*
X158829Y-99473D01*
X158825Y-99469D01*
X158796Y-99418D01*
X158771Y-99367D01*
X158730Y-99258D01*
X158701Y-99149D01*
X158683Y-99044D01*
X158676Y-98993D01*
X158669Y-98949D01*
X158665Y-98909D01*
Y-98876D01*
X158661Y-98847D01*
Y-98807D01*
X158665Y-98734D01*
X158672Y-98665D01*
X158680Y-98599D01*
X158694Y-98538D01*
X158712Y-98479D01*
X158730Y-98425D01*
X158749Y-98374D01*
X158771Y-98326D01*
X158789Y-98286D01*
X158807Y-98246D01*
X158825Y-98217D01*
X158843Y-98188D01*
X158858Y-98170D01*
X158865Y-98152D01*
X158872Y-98144D01*
X158876Y-98141D01*
X158920Y-98090D01*
X158964Y-98046D01*
X159014Y-98006D01*
X159065Y-97966D01*
X159167Y-97901D01*
X159269Y-97850D01*
X159317Y-97828D01*
X159360Y-97810D01*
X159400Y-97795D01*
X159433Y-97784D01*
X159462Y-97773D01*
X159484Y-97766D01*
X159499Y-97762D01*
X159502D01*
X159586Y-98097D01*
D02*
G37*
%LPC*%
G36*
X595289Y-292384D02*
X594160Y-293178D01*
X595289D01*
Y-292384D01*
D02*
G37*
G36*
X545814Y-264094D02*
X545782D01*
X545763D01*
X545760D01*
X545756D01*
X545643D01*
X545541Y-264101D01*
X545450Y-264109D01*
X545363Y-264116D01*
X545290Y-264127D01*
X545221Y-264141D01*
X545163Y-264156D01*
X545108Y-264167D01*
X545064Y-264181D01*
X545028Y-264196D01*
X544995Y-264207D01*
X544970Y-264222D01*
X544952Y-264229D01*
X544941Y-264236D01*
X544933Y-264243D01*
X544930D01*
X544893Y-264272D01*
X544864Y-264302D01*
X544835Y-264331D01*
X544813Y-264360D01*
X544777Y-264422D01*
X544751Y-264476D01*
X544737Y-264527D01*
X544730Y-264564D01*
X544726Y-264578D01*
Y-264600D01*
X544730Y-264640D01*
X544733Y-264676D01*
X544759Y-264746D01*
X544791Y-264808D01*
X544828Y-264862D01*
X544864Y-264902D01*
X544897Y-264935D01*
X544922Y-264953D01*
X544926Y-264960D01*
X544930D01*
X544973Y-264986D01*
X545024Y-265008D01*
X545083Y-265030D01*
X545145Y-265044D01*
X545210Y-265059D01*
X545279Y-265070D01*
X545421Y-265088D01*
X545487Y-265095D01*
X545548Y-265099D01*
X545607Y-265102D01*
X545654D01*
X545698Y-265106D01*
X545730D01*
X545749D01*
X545756D01*
X545869Y-265102D01*
X545971Y-265099D01*
X546065Y-265091D01*
X546153Y-265080D01*
X546229Y-265070D01*
X546298Y-265055D01*
X546360Y-265040D01*
X546415Y-265026D01*
X546462Y-265011D01*
X546502Y-265000D01*
X546535Y-264986D01*
X546564Y-264975D01*
X546582Y-264964D01*
X546597Y-264957D01*
X546604Y-264949D01*
X546608D01*
X546640Y-264924D01*
X546670Y-264898D01*
X546692Y-264869D01*
X546713Y-264840D01*
X546746Y-264782D01*
X546768Y-264727D01*
X546779Y-264680D01*
X546786Y-264640D01*
X546790Y-264626D01*
Y-264604D01*
X546786Y-264564D01*
X546782Y-264524D01*
X546772Y-264487D01*
X546757Y-264454D01*
X546724Y-264393D01*
X546688Y-264338D01*
X546648Y-264298D01*
X546615Y-264265D01*
X546600Y-264254D01*
X546590Y-264247D01*
X546586Y-264240D01*
X546582D01*
X546539Y-264214D01*
X546488Y-264192D01*
X546429Y-264171D01*
X546368Y-264156D01*
X546302Y-264141D01*
X546233Y-264130D01*
X546095Y-264112D01*
X546025Y-264105D01*
X545963Y-264101D01*
X545905Y-264098D01*
X545858D01*
X545814Y-264094D01*
D02*
G37*
G36*
X476646Y-305174D02*
X476613D01*
X476595D01*
X476587D01*
X476475Y-305177D01*
X476373Y-305181D01*
X476278Y-305188D01*
X476191Y-305199D01*
X476114Y-305210D01*
X476045Y-305224D01*
X475983Y-305239D01*
X475929Y-305254D01*
X475881Y-305268D01*
X475841Y-305279D01*
X475809Y-305294D01*
X475779Y-305305D01*
X475761Y-305315D01*
X475747Y-305323D01*
X475739Y-305330D01*
X475736D01*
X475703Y-305356D01*
X475674Y-305381D01*
X475652Y-305410D01*
X475630Y-305439D01*
X475597Y-305498D01*
X475576Y-305552D01*
X475565Y-305599D01*
X475557Y-305640D01*
X475554Y-305654D01*
Y-305676D01*
X475557Y-305716D01*
X475561Y-305756D01*
X475572Y-305792D01*
X475587Y-305825D01*
X475619Y-305887D01*
X475656Y-305942D01*
X475696Y-305982D01*
X475729Y-306014D01*
X475743Y-306025D01*
X475754Y-306033D01*
X475758Y-306040D01*
X475761D01*
X475805Y-306065D01*
X475856Y-306087D01*
X475914Y-306109D01*
X475976Y-306124D01*
X476042Y-306138D01*
X476111Y-306149D01*
X476249Y-306167D01*
X476318Y-306175D01*
X476380Y-306178D01*
X476438Y-306182D01*
X476486D01*
X476529Y-306186D01*
X476562D01*
X476580D01*
X476584D01*
X476587D01*
X476700D01*
X476802Y-306178D01*
X476893Y-306171D01*
X476981Y-306164D01*
X477053Y-306153D01*
X477123Y-306138D01*
X477181Y-306124D01*
X477235Y-306113D01*
X477279Y-306098D01*
X477316Y-306084D01*
X477348Y-306073D01*
X477374Y-306058D01*
X477392Y-306051D01*
X477403Y-306044D01*
X477410Y-306036D01*
X477414D01*
X477450Y-306007D01*
X477479Y-305978D01*
X477508Y-305949D01*
X477530Y-305920D01*
X477567Y-305858D01*
X477592Y-305803D01*
X477607Y-305752D01*
X477614Y-305716D01*
X477618Y-305701D01*
Y-305679D01*
X477614Y-305640D01*
X477610Y-305603D01*
X477585Y-305534D01*
X477552Y-305472D01*
X477516Y-305417D01*
X477479Y-305377D01*
X477447Y-305345D01*
X477421Y-305327D01*
X477417Y-305319D01*
X477414D01*
X477370Y-305294D01*
X477319Y-305272D01*
X477261Y-305250D01*
X477199Y-305235D01*
X477134Y-305221D01*
X477064Y-305210D01*
X476922Y-305192D01*
X476857Y-305185D01*
X476795Y-305181D01*
X476737Y-305177D01*
X476689D01*
X476646Y-305174D01*
D02*
G37*
G36*
X475950Y-307230D02*
X475947D01*
X475943D01*
X475885Y-307234D01*
X475834Y-307248D01*
X475787Y-307267D01*
X475747Y-307288D01*
X475714Y-307307D01*
X475688Y-307325D01*
X475674Y-307339D01*
X475670Y-307343D01*
X475630Y-307390D01*
X475601Y-307438D01*
X475583Y-307489D01*
X475568Y-307536D01*
X475561Y-307580D01*
X475554Y-307612D01*
Y-307642D01*
X475557Y-307703D01*
X475572Y-307762D01*
X475590Y-307809D01*
X475612Y-307853D01*
X475634Y-307885D01*
X475652Y-307911D01*
X475667Y-307929D01*
X475670Y-307933D01*
X475718Y-307973D01*
X475765Y-308002D01*
X475812Y-308024D01*
X475856Y-308038D01*
X475896Y-308046D01*
X475929Y-308053D01*
X475950D01*
X475954D01*
X475958D01*
X476016Y-308049D01*
X476071Y-308035D01*
X476118Y-308016D01*
X476158Y-307995D01*
X476191Y-307973D01*
X476213Y-307955D01*
X476231Y-307940D01*
X476234Y-307936D01*
X476271Y-307893D01*
X476300Y-307842D01*
X476318Y-307794D01*
X476333Y-307747D01*
X476340Y-307703D01*
X476344Y-307671D01*
X476347Y-307649D01*
Y-307642D01*
X476344Y-307576D01*
X476329Y-307518D01*
X476311Y-307467D01*
X476289Y-307423D01*
X476271Y-307390D01*
X476253Y-307365D01*
X476238Y-307347D01*
X476234Y-307343D01*
X476191Y-307307D01*
X476140Y-307277D01*
X476092Y-307259D01*
X476045Y-307245D01*
X476005Y-307237D01*
X475972Y-307234D01*
X475950Y-307230D01*
D02*
G37*
G36*
X477126Y-307128D02*
X477112D01*
X477104D01*
X477028Y-307136D01*
X476959Y-307150D01*
X476897Y-307172D01*
X476842Y-307201D01*
X476802Y-307226D01*
X476769Y-307248D01*
X476751Y-307263D01*
X476744Y-307270D01*
X476697Y-307325D01*
X476660Y-307387D01*
X476635Y-307445D01*
X476617Y-307503D01*
X476606Y-307554D01*
X476602Y-307594D01*
X476598Y-307609D01*
Y-307631D01*
X476606Y-307711D01*
X476620Y-307783D01*
X476646Y-307849D01*
X476671Y-307904D01*
X476700Y-307947D01*
X476726Y-307980D01*
X476740Y-307998D01*
X476748Y-308005D01*
X476806Y-308056D01*
X476868Y-308093D01*
X476930Y-308118D01*
X476984Y-308137D01*
X477039Y-308147D01*
X477079Y-308151D01*
X477094Y-308155D01*
X477104D01*
X477112D01*
X477115D01*
X477192Y-308147D01*
X477264Y-308133D01*
X477326Y-308107D01*
X477377Y-308082D01*
X477417Y-308056D01*
X477450Y-308031D01*
X477468Y-308016D01*
X477476Y-308009D01*
X477523Y-307951D01*
X477559Y-307893D01*
X477581Y-307831D01*
X477599Y-307772D01*
X477610Y-307722D01*
X477614Y-307678D01*
X477618Y-307663D01*
Y-307642D01*
X477614Y-307591D01*
X477607Y-307540D01*
X477596Y-307492D01*
X477585Y-307452D01*
X477574Y-307419D01*
X477563Y-307394D01*
X477556Y-307379D01*
X477552Y-307372D01*
X477523Y-307329D01*
X477494Y-307292D01*
X477461Y-307259D01*
X477428Y-307234D01*
X477403Y-307212D01*
X477381Y-307197D01*
X477363Y-307190D01*
X477359Y-307187D01*
X477312Y-307168D01*
X477268Y-307154D01*
X477224Y-307143D01*
X477184Y-307136D01*
X477152Y-307132D01*
X477126Y-307128D01*
D02*
G37*
G36*
X473064Y-264343D02*
X473042D01*
X472966Y-264350D01*
X472897Y-264369D01*
X472838Y-264390D01*
X472788Y-264420D01*
X472748Y-264449D01*
X472718Y-264470D01*
X472700Y-264489D01*
X472693Y-264496D01*
X472646Y-264558D01*
X472609Y-264623D01*
X472584Y-264692D01*
X472569Y-264758D01*
X472558Y-264816D01*
X472554Y-264842D01*
Y-264864D01*
X472551Y-264882D01*
Y-264896D01*
Y-264904D01*
Y-264907D01*
X472558Y-265005D01*
X472573Y-265089D01*
X472595Y-265162D01*
X472620Y-265224D01*
X472649Y-265271D01*
X472671Y-265308D01*
X472686Y-265330D01*
X472693Y-265333D01*
Y-265337D01*
X472718Y-265366D01*
X472748Y-265388D01*
X472806Y-265428D01*
X472864Y-265453D01*
X472915Y-265475D01*
X472962Y-265486D01*
X472999Y-265490D01*
X473013Y-265493D01*
X473031D01*
X473082Y-265490D01*
X473130Y-265482D01*
X473173Y-265468D01*
X473210Y-265453D01*
X473243Y-265442D01*
X473268Y-265428D01*
X473282Y-265421D01*
X473290Y-265417D01*
X473334Y-265384D01*
X473370Y-265351D01*
X473403Y-265311D01*
X473428Y-265279D01*
X473450Y-265246D01*
X473464Y-265220D01*
X473476Y-265202D01*
X473479Y-265195D01*
X473501Y-265140D01*
X473516Y-265086D01*
X473530Y-265035D01*
X473537Y-264987D01*
X473541Y-264947D01*
X473545Y-264914D01*
Y-264896D01*
Y-264889D01*
X473537Y-264802D01*
X473523Y-264725D01*
X473497Y-264656D01*
X473472Y-264601D01*
X473446Y-264554D01*
X473421Y-264521D01*
X473406Y-264503D01*
X473399Y-264496D01*
X473341Y-264445D01*
X473282Y-264409D01*
X473221Y-264379D01*
X473166Y-264361D01*
X473115Y-264350D01*
X473079Y-264347D01*
X473064Y-264343D01*
D02*
G37*
G36*
X475048Y-263429D02*
X475026D01*
X474986Y-263433D01*
X474946Y-263437D01*
X474910Y-263448D01*
X474877Y-263462D01*
X474815Y-263495D01*
X474760Y-263531D01*
X474720Y-263571D01*
X474688Y-263604D01*
X474677Y-263619D01*
X474669Y-263630D01*
X474662Y-263633D01*
Y-263637D01*
X474637Y-263681D01*
X474615Y-263732D01*
X474593Y-263790D01*
X474578Y-263852D01*
X474564Y-263917D01*
X474553Y-263986D01*
X474535Y-264125D01*
X474527Y-264194D01*
X474524Y-264256D01*
X474520Y-264314D01*
Y-264361D01*
X474516Y-264405D01*
Y-264438D01*
Y-264456D01*
Y-264459D01*
Y-264463D01*
Y-264576D01*
X474524Y-264678D01*
X474531Y-264769D01*
X474538Y-264856D01*
X474549Y-264929D01*
X474564Y-264998D01*
X474578Y-265056D01*
X474589Y-265111D01*
X474604Y-265155D01*
X474618Y-265191D01*
X474629Y-265224D01*
X474644Y-265249D01*
X474651Y-265268D01*
X474658Y-265279D01*
X474666Y-265286D01*
Y-265289D01*
X474695Y-265326D01*
X474724Y-265355D01*
X474753Y-265384D01*
X474782Y-265406D01*
X474844Y-265442D01*
X474899Y-265468D01*
X474950Y-265482D01*
X474986Y-265490D01*
X475001Y-265493D01*
X475023D01*
X475063Y-265490D01*
X475099Y-265486D01*
X475168Y-265460D01*
X475230Y-265428D01*
X475284Y-265391D01*
X475325Y-265355D01*
X475357Y-265322D01*
X475376Y-265297D01*
X475383Y-265293D01*
Y-265289D01*
X475408Y-265246D01*
X475430Y-265195D01*
X475452Y-265137D01*
X475466Y-265075D01*
X475481Y-265009D01*
X475492Y-264940D01*
X475510Y-264798D01*
X475518Y-264733D01*
X475521Y-264671D01*
X475525Y-264612D01*
Y-264565D01*
X475528Y-264521D01*
Y-264489D01*
Y-264470D01*
Y-264463D01*
X475525Y-264350D01*
X475521Y-264248D01*
X475514Y-264154D01*
X475503Y-264066D01*
X475492Y-263990D01*
X475478Y-263921D01*
X475463Y-263859D01*
X475448Y-263804D01*
X475434Y-263757D01*
X475423Y-263717D01*
X475408Y-263684D01*
X475397Y-263655D01*
X475386Y-263637D01*
X475379Y-263622D01*
X475372Y-263615D01*
Y-263611D01*
X475346Y-263579D01*
X475321Y-263549D01*
X475292Y-263528D01*
X475263Y-263506D01*
X475204Y-263473D01*
X475150Y-263451D01*
X475103Y-263440D01*
X475063Y-263433D01*
X475048Y-263429D01*
D02*
G37*
G36*
X188537Y-99275D02*
X188504D01*
X188486D01*
X188479D01*
X188366Y-99278D01*
X188264Y-99282D01*
X188170Y-99289D01*
X188082Y-99300D01*
X188006Y-99311D01*
X187937Y-99326D01*
X187875Y-99340D01*
X187820Y-99355D01*
X187773Y-99369D01*
X187733Y-99380D01*
X187700Y-99395D01*
X187671Y-99406D01*
X187653Y-99417D01*
X187638Y-99424D01*
X187631Y-99431D01*
X187627D01*
X187594Y-99457D01*
X187565Y-99482D01*
X187543Y-99511D01*
X187522Y-99541D01*
X187489Y-99599D01*
X187467Y-99653D01*
X187456Y-99701D01*
X187449Y-99741D01*
X187445Y-99755D01*
Y-99777D01*
X187449Y-99817D01*
X187452Y-99857D01*
X187463Y-99893D01*
X187478Y-99926D01*
X187511Y-99988D01*
X187547Y-100043D01*
X187587Y-100083D01*
X187620Y-100116D01*
X187634Y-100127D01*
X187645Y-100134D01*
X187649Y-100141D01*
X187653D01*
X187696Y-100166D01*
X187747Y-100188D01*
X187805Y-100210D01*
X187867Y-100225D01*
X187933Y-100239D01*
X188002Y-100250D01*
X188140Y-100268D01*
X188209Y-100276D01*
X188271Y-100279D01*
X188330Y-100283D01*
X188377D01*
X188421Y-100287D01*
X188453D01*
X188472D01*
X188475D01*
X188479D01*
X188592D01*
X188694Y-100279D01*
X188785Y-100272D01*
X188872Y-100265D01*
X188945Y-100254D01*
X189014Y-100239D01*
X189072Y-100225D01*
X189127Y-100214D01*
X189171Y-100199D01*
X189207Y-100185D01*
X189240Y-100174D01*
X189265Y-100159D01*
X189283Y-100152D01*
X189294Y-100145D01*
X189302Y-100137D01*
X189305D01*
X189342Y-100108D01*
X189371Y-100079D01*
X189400Y-100050D01*
X189422Y-100021D01*
X189458Y-99959D01*
X189483Y-99905D01*
X189498Y-99853D01*
X189505Y-99817D01*
X189509Y-99803D01*
Y-99781D01*
X189505Y-99741D01*
X189502Y-99704D01*
X189476Y-99635D01*
X189444Y-99573D01*
X189407Y-99519D01*
X189371Y-99479D01*
X189338Y-99446D01*
X189313Y-99428D01*
X189309Y-99420D01*
X189305D01*
X189261Y-99395D01*
X189210Y-99373D01*
X189152Y-99351D01*
X189090Y-99337D01*
X189025Y-99322D01*
X188956Y-99311D01*
X188814Y-99293D01*
X188748Y-99286D01*
X188686Y-99282D01*
X188628Y-99278D01*
X188581D01*
X188537Y-99275D01*
D02*
G37*
G36*
X150524Y-843D02*
X150491D01*
X150473D01*
X150466D01*
X150353Y-847D01*
X150251Y-850D01*
X150156Y-857D01*
X150069Y-868D01*
X149992Y-879D01*
X149923Y-894D01*
X149861Y-908D01*
X149807Y-923D01*
X149759Y-938D01*
X149719Y-948D01*
X149687Y-963D01*
X149657Y-974D01*
X149639Y-985D01*
X149625Y-992D01*
X149618Y-999D01*
X149614D01*
X149581Y-1025D01*
X149552Y-1050D01*
X149530Y-1079D01*
X149508Y-1109D01*
X149476Y-1167D01*
X149454Y-1221D01*
X149443Y-1269D01*
X149435Y-1309D01*
X149432Y-1323D01*
Y-1345D01*
X149435Y-1385D01*
X149439Y-1425D01*
X149450Y-1462D01*
X149465Y-1494D01*
X149497Y-1556D01*
X149534Y-1611D01*
X149574Y-1651D01*
X149607Y-1684D01*
X149621Y-1695D01*
X149632Y-1702D01*
X149636Y-1709D01*
X149639D01*
X149683Y-1735D01*
X149734Y-1757D01*
X149792Y-1778D01*
X149854Y-1793D01*
X149920Y-1808D01*
X149989Y-1818D01*
X150127Y-1837D01*
X150196Y-1844D01*
X150258Y-1847D01*
X150316Y-1851D01*
X150364D01*
X150407Y-1855D01*
X150440D01*
X150458D01*
X150462D01*
X150466D01*
X150578D01*
X150680Y-1847D01*
X150771Y-1840D01*
X150859Y-1833D01*
X150932Y-1822D01*
X151001Y-1808D01*
X151059Y-1793D01*
X151113Y-1782D01*
X151157Y-1767D01*
X151194Y-1753D01*
X151226Y-1742D01*
X151252Y-1727D01*
X151270Y-1720D01*
X151281Y-1713D01*
X151288Y-1705D01*
X151292D01*
X151328Y-1676D01*
X151357Y-1647D01*
X151386Y-1618D01*
X151408Y-1589D01*
X151445Y-1527D01*
X151470Y-1473D01*
X151485Y-1422D01*
X151492Y-1385D01*
X151496Y-1371D01*
Y-1349D01*
X151492Y-1309D01*
X151488Y-1272D01*
X151463Y-1203D01*
X151430Y-1141D01*
X151394Y-1087D01*
X151357Y-1047D01*
X151325Y-1014D01*
X151299Y-996D01*
X151295Y-988D01*
X151292D01*
X151248Y-963D01*
X151197Y-941D01*
X151139Y-919D01*
X151077Y-905D01*
X151012Y-890D01*
X150942Y-879D01*
X150801Y-861D01*
X150735Y-854D01*
X150673Y-850D01*
X150615Y-847D01*
X150567D01*
X150524Y-843D01*
D02*
G37*
G36*
X150062Y-2801D02*
X150051D01*
X150043D01*
X150040D01*
X149945Y-2808D01*
X149858Y-2823D01*
X149781Y-2849D01*
X149719Y-2878D01*
X149668Y-2903D01*
X149632Y-2929D01*
X149621Y-2936D01*
X149610Y-2943D01*
X149607Y-2950D01*
X149603D01*
X149574Y-2980D01*
X149545Y-3009D01*
X149505Y-3070D01*
X149472Y-3132D01*
X149454Y-3191D01*
X149439Y-3238D01*
X149435Y-3278D01*
X149432Y-3293D01*
Y-3351D01*
X149439Y-3387D01*
X149457Y-3453D01*
X149483Y-3511D01*
X149508Y-3562D01*
X149537Y-3602D01*
X149563Y-3631D01*
X149581Y-3649D01*
X149585Y-3657D01*
X149588D01*
X149650Y-3704D01*
X149719Y-3740D01*
X149792Y-3766D01*
X149861Y-3780D01*
X149920Y-3791D01*
X149945Y-3795D01*
X149970D01*
X149989Y-3799D01*
X150003D01*
X150011D01*
X150014D01*
X150109Y-3791D01*
X150193Y-3777D01*
X150262Y-3755D01*
X150320Y-3729D01*
X150367Y-3700D01*
X150400Y-3678D01*
X150422Y-3664D01*
X150429Y-3657D01*
X150480Y-3602D01*
X150516Y-3544D01*
X150542Y-3486D01*
X150560Y-3427D01*
X150571Y-3380D01*
X150575Y-3340D01*
X150578Y-3325D01*
Y-3303D01*
X150571Y-3227D01*
X150557Y-3158D01*
X150531Y-3096D01*
X150502Y-3041D01*
X150477Y-3001D01*
X150451Y-2969D01*
X150436Y-2950D01*
X150429Y-2943D01*
X150371Y-2896D01*
X150305Y-2859D01*
X150240Y-2838D01*
X150178Y-2819D01*
X150123Y-2808D01*
X150102Y-2805D01*
X150080D01*
X150062Y-2801D01*
D02*
G37*
G36*
X491977Y-250044D02*
X491955D01*
X491915Y-250047D01*
X491875Y-250051D01*
X491839Y-250062D01*
X491806Y-250076D01*
X491744Y-250109D01*
X491689Y-250146D01*
X491649Y-250185D01*
X491617Y-250218D01*
X491606Y-250233D01*
X491599Y-250244D01*
X491591Y-250247D01*
Y-250251D01*
X491566Y-250295D01*
X491544Y-250346D01*
X491522Y-250404D01*
X491507Y-250466D01*
X491493Y-250531D01*
X491482Y-250601D01*
X491464Y-250739D01*
X491457Y-250808D01*
X491453Y-250870D01*
X491449Y-250928D01*
Y-250975D01*
X491446Y-251019D01*
Y-251052D01*
Y-251070D01*
Y-251074D01*
Y-251077D01*
Y-251190D01*
X491453Y-251292D01*
X491460Y-251383D01*
X491468Y-251470D01*
X491478Y-251543D01*
X491493Y-251612D01*
X491507Y-251671D01*
X491518Y-251725D01*
X491533Y-251769D01*
X491547Y-251805D01*
X491559Y-251838D01*
X491573Y-251864D01*
X491580Y-251882D01*
X491588Y-251893D01*
X491595Y-251900D01*
Y-251904D01*
X491624Y-251940D01*
X491653Y-251969D01*
X491682Y-251998D01*
X491711Y-252020D01*
X491773Y-252057D01*
X491828Y-252082D01*
X491879Y-252097D01*
X491915Y-252104D01*
X491930Y-252108D01*
X491952D01*
X491992Y-252104D01*
X492028Y-252100D01*
X492097Y-252075D01*
X492159Y-252042D01*
X492214Y-252006D01*
X492254Y-251969D01*
X492286Y-251936D01*
X492305Y-251911D01*
X492312Y-251907D01*
Y-251904D01*
X492337Y-251860D01*
X492359Y-251809D01*
X492381Y-251751D01*
X492396Y-251689D01*
X492410Y-251623D01*
X492421Y-251554D01*
X492439Y-251412D01*
X492447Y-251347D01*
X492450Y-251285D01*
X492454Y-251227D01*
Y-251179D01*
X492457Y-251136D01*
Y-251103D01*
Y-251085D01*
Y-251077D01*
X492454Y-250964D01*
X492450Y-250863D01*
X492443Y-250768D01*
X492432Y-250681D01*
X492421Y-250604D01*
X492407Y-250535D01*
X492392Y-250473D01*
X492378Y-250418D01*
X492363Y-250371D01*
X492352Y-250331D01*
X492337Y-250298D01*
X492326Y-250269D01*
X492316Y-250251D01*
X492308Y-250237D01*
X492301Y-250229D01*
Y-250226D01*
X492275Y-250193D01*
X492250Y-250164D01*
X492221Y-250142D01*
X492192Y-250120D01*
X492134Y-250087D01*
X492079Y-250065D01*
X492032Y-250055D01*
X491992Y-250047D01*
X491977Y-250044D01*
D02*
G37*
G36*
X512992Y-260391D02*
X512970D01*
X512930Y-260395D01*
X512893Y-260398D01*
X512824Y-260424D01*
X512762Y-260456D01*
X512708Y-260493D01*
X512668Y-260529D01*
X512635Y-260562D01*
X512617Y-260588D01*
X512609Y-260591D01*
Y-260595D01*
X512584Y-260638D01*
X512562Y-260689D01*
X512540Y-260748D01*
X512526Y-260809D01*
X512511Y-260875D01*
X512500Y-260944D01*
X512482Y-261086D01*
X512475Y-261152D01*
X512471Y-261214D01*
X512467Y-261272D01*
Y-261319D01*
X512464Y-261363D01*
Y-261396D01*
Y-261414D01*
Y-261421D01*
X512467Y-261534D01*
X512471Y-261636D01*
X512478Y-261731D01*
X512489Y-261818D01*
X512500Y-261894D01*
X512515Y-261963D01*
X512529Y-262025D01*
X512544Y-262080D01*
X512558Y-262127D01*
X512569Y-262167D01*
X512584Y-262200D01*
X512595Y-262229D01*
X512606Y-262247D01*
X512613Y-262262D01*
X512620Y-262269D01*
Y-262273D01*
X512646Y-262306D01*
X512671Y-262335D01*
X512700Y-262356D01*
X512729Y-262378D01*
X512788Y-262411D01*
X512842Y-262433D01*
X512890Y-262444D01*
X512930Y-262451D01*
X512944Y-262455D01*
X512966D01*
X513006Y-262451D01*
X513046Y-262448D01*
X513083Y-262437D01*
X513115Y-262422D01*
X513177Y-262389D01*
X513232Y-262353D01*
X513272Y-262313D01*
X513305Y-262280D01*
X513315Y-262265D01*
X513323Y-262255D01*
X513330Y-262251D01*
Y-262247D01*
X513355Y-262204D01*
X513377Y-262153D01*
X513399Y-262094D01*
X513414Y-262033D01*
X513428Y-261967D01*
X513439Y-261898D01*
X513457Y-261760D01*
X513465Y-261690D01*
X513468Y-261629D01*
X513472Y-261570D01*
Y-261523D01*
X513476Y-261479D01*
Y-261446D01*
Y-261428D01*
Y-261425D01*
Y-261421D01*
Y-261308D01*
X513468Y-261206D01*
X513461Y-261115D01*
X513454Y-261028D01*
X513443Y-260955D01*
X513428Y-260886D01*
X513414Y-260828D01*
X513403Y-260773D01*
X513388Y-260729D01*
X513374Y-260693D01*
X513363Y-260660D01*
X513348Y-260635D01*
X513341Y-260617D01*
X513334Y-260606D01*
X513326Y-260598D01*
Y-260595D01*
X513297Y-260558D01*
X513268Y-260529D01*
X513239Y-260500D01*
X513210Y-260478D01*
X513148Y-260442D01*
X513093Y-260416D01*
X513042Y-260402D01*
X513006Y-260395D01*
X512992Y-260391D01*
D02*
G37*
G36*
X492371Y-257524D02*
X492349D01*
X492309Y-257527D01*
X492269Y-257531D01*
X492232Y-257542D01*
X492200Y-257557D01*
X492138Y-257589D01*
X492083Y-257626D01*
X492043Y-257666D01*
X492010Y-257699D01*
X491999Y-257713D01*
X491992Y-257724D01*
X491985Y-257728D01*
Y-257731D01*
X491959Y-257775D01*
X491938Y-257826D01*
X491916Y-257884D01*
X491901Y-257946D01*
X491887Y-258012D01*
X491876Y-258081D01*
X491857Y-258219D01*
X491850Y-258288D01*
X491847Y-258350D01*
X491843Y-258408D01*
Y-258456D01*
X491839Y-258499D01*
Y-258532D01*
Y-258550D01*
Y-258554D01*
Y-258558D01*
Y-258670D01*
X491847Y-258772D01*
X491854Y-258863D01*
X491861Y-258951D01*
X491872Y-259024D01*
X491887Y-259093D01*
X491901Y-259151D01*
X491912Y-259206D01*
X491927Y-259249D01*
X491941Y-259286D01*
X491952Y-259318D01*
X491967Y-259344D01*
X491974Y-259362D01*
X491981Y-259373D01*
X491989Y-259380D01*
Y-259384D01*
X492018Y-259420D01*
X492047Y-259449D01*
X492076Y-259479D01*
X492105Y-259500D01*
X492167Y-259537D01*
X492221Y-259562D01*
X492273Y-259577D01*
X492309Y-259584D01*
X492323Y-259588D01*
X492345D01*
X492385Y-259584D01*
X492422Y-259580D01*
X492491Y-259555D01*
X492553Y-259522D01*
X492607Y-259486D01*
X492647Y-259449D01*
X492680Y-259417D01*
X492698Y-259391D01*
X492706Y-259388D01*
Y-259384D01*
X492731Y-259340D01*
X492753Y-259289D01*
X492775Y-259231D01*
X492789Y-259169D01*
X492804Y-259104D01*
X492815Y-259034D01*
X492833Y-258892D01*
X492840Y-258827D01*
X492844Y-258765D01*
X492848Y-258707D01*
Y-258660D01*
X492851Y-258616D01*
Y-258583D01*
Y-258565D01*
Y-258558D01*
X492848Y-258445D01*
X492844Y-258343D01*
X492837Y-258248D01*
X492826Y-258161D01*
X492815Y-258085D01*
X492800Y-258015D01*
X492786Y-257953D01*
X492771Y-257899D01*
X492757Y-257852D01*
X492746Y-257811D01*
X492731Y-257779D01*
X492720Y-257750D01*
X492709Y-257731D01*
X492702Y-257717D01*
X492695Y-257710D01*
Y-257706D01*
X492669Y-257673D01*
X492644Y-257644D01*
X492615Y-257622D01*
X492586Y-257600D01*
X492527Y-257568D01*
X492473Y-257546D01*
X492425Y-257535D01*
X492385Y-257527D01*
X492371Y-257524D01*
D02*
G37*
G36*
X558527Y-259059D02*
Y-260188D01*
X559320D01*
X558527Y-259059D01*
D02*
G37*
G36*
X560678Y-258801D02*
X560656D01*
X560616Y-258804D01*
X560576Y-258808D01*
X560539Y-258819D01*
X560507Y-258833D01*
X560445Y-258866D01*
X560390Y-258903D01*
X560350Y-258943D01*
X560318Y-258975D01*
X560307Y-258990D01*
X560299Y-259001D01*
X560292Y-259004D01*
Y-259008D01*
X560266Y-259052D01*
X560245Y-259103D01*
X560223Y-259161D01*
X560208Y-259223D01*
X560194Y-259288D01*
X560183Y-259358D01*
X560165Y-259496D01*
X560157Y-259565D01*
X560154Y-259627D01*
X560150Y-259685D01*
Y-259733D01*
X560146Y-259776D01*
Y-259809D01*
Y-259827D01*
Y-259831D01*
Y-259834D01*
Y-259947D01*
X560154Y-260049D01*
X560161Y-260140D01*
X560168Y-260227D01*
X560179Y-260300D01*
X560194Y-260369D01*
X560208Y-260428D01*
X560219Y-260482D01*
X560234Y-260526D01*
X560248Y-260562D01*
X560259Y-260595D01*
X560274Y-260621D01*
X560281Y-260639D01*
X560288Y-260650D01*
X560296Y-260657D01*
Y-260661D01*
X560325Y-260697D01*
X560354Y-260726D01*
X560383Y-260755D01*
X560412Y-260777D01*
X560474Y-260814D01*
X560529Y-260839D01*
X560580Y-260854D01*
X560616Y-260861D01*
X560631Y-260864D01*
X560652D01*
X560692Y-260861D01*
X560729Y-260857D01*
X560798Y-260832D01*
X560860Y-260799D01*
X560915Y-260763D01*
X560955Y-260726D01*
X560987Y-260693D01*
X561005Y-260668D01*
X561013Y-260664D01*
Y-260661D01*
X561038Y-260617D01*
X561060Y-260566D01*
X561082Y-260508D01*
X561096Y-260446D01*
X561111Y-260380D01*
X561122Y-260311D01*
X561140Y-260169D01*
X561147Y-260104D01*
X561151Y-260042D01*
X561155Y-259984D01*
Y-259936D01*
X561158Y-259893D01*
Y-259860D01*
Y-259842D01*
Y-259834D01*
X561155Y-259722D01*
X561151Y-259620D01*
X561144Y-259525D01*
X561133Y-259438D01*
X561122Y-259361D01*
X561107Y-259292D01*
X561093Y-259230D01*
X561078Y-259176D01*
X561064Y-259128D01*
X561053Y-259088D01*
X561038Y-259055D01*
X561027Y-259026D01*
X561016Y-259008D01*
X561009Y-258994D01*
X561002Y-258986D01*
Y-258983D01*
X560976Y-258950D01*
X560951Y-258921D01*
X560922Y-258899D01*
X560893Y-258877D01*
X560834Y-258844D01*
X560780Y-258822D01*
X560732Y-258812D01*
X560692Y-258804D01*
X560678Y-258801D01*
D02*
G37*
G36*
X578641Y-261377D02*
X578619D01*
X578579Y-261381D01*
X578543Y-261384D01*
X578474Y-261410D01*
X578412Y-261442D01*
X578357Y-261479D01*
X578317Y-261515D01*
X578284Y-261548D01*
X578266Y-261573D01*
X578259Y-261577D01*
Y-261581D01*
X578233Y-261624D01*
X578212Y-261675D01*
X578190Y-261734D01*
X578175Y-261795D01*
X578161Y-261861D01*
X578150Y-261930D01*
X578131Y-262072D01*
X578124Y-262138D01*
X578121Y-262199D01*
X578117Y-262258D01*
Y-262305D01*
X578113Y-262349D01*
Y-262381D01*
Y-262400D01*
Y-262407D01*
X578117Y-262520D01*
X578121Y-262622D01*
X578128Y-262716D01*
X578139Y-262804D01*
X578150Y-262880D01*
X578164Y-262949D01*
X578179Y-263011D01*
X578193Y-263066D01*
X578208Y-263113D01*
X578219Y-263153D01*
X578233Y-263186D01*
X578244Y-263215D01*
X578255Y-263233D01*
X578263Y-263248D01*
X578270Y-263255D01*
Y-263259D01*
X578295Y-263291D01*
X578321Y-263321D01*
X578350Y-263342D01*
X578379Y-263364D01*
X578437Y-263397D01*
X578492Y-263419D01*
X578539Y-263430D01*
X578579Y-263437D01*
X578594Y-263441D01*
X578616D01*
X578656Y-263437D01*
X578696Y-263433D01*
X578732Y-263422D01*
X578765Y-263408D01*
X578827Y-263375D01*
X578881Y-263339D01*
X578921Y-263299D01*
X578954Y-263266D01*
X578965Y-263251D01*
X578972Y-263241D01*
X578980Y-263237D01*
Y-263233D01*
X579005Y-263190D01*
X579027Y-263139D01*
X579049Y-263080D01*
X579063Y-263018D01*
X579078Y-262953D01*
X579089Y-262884D01*
X579107Y-262745D01*
X579114Y-262676D01*
X579118Y-262614D01*
X579122Y-262556D01*
Y-262509D01*
X579125Y-262465D01*
Y-262432D01*
Y-262414D01*
Y-262411D01*
Y-262407D01*
Y-262294D01*
X579118Y-262192D01*
X579111Y-262101D01*
X579103Y-262014D01*
X579093Y-261941D01*
X579078Y-261872D01*
X579063Y-261814D01*
X579052Y-261759D01*
X579038Y-261715D01*
X579023Y-261679D01*
X579012Y-261646D01*
X578998Y-261621D01*
X578991Y-261602D01*
X578983Y-261592D01*
X578976Y-261584D01*
Y-261581D01*
X578947Y-261544D01*
X578918Y-261515D01*
X578889Y-261486D01*
X578860Y-261464D01*
X578798Y-261428D01*
X578743Y-261402D01*
X578692Y-261388D01*
X578656Y-261381D01*
X578641Y-261377D01*
D02*
G37*
G36*
X211509Y8216D02*
X210381D01*
Y7422D01*
X211509Y8216D01*
D02*
G37*
G36*
X205600Y873D02*
X205586D01*
X205578D01*
X205575D01*
X205480Y865D01*
X205396Y851D01*
X205327Y829D01*
X205269Y804D01*
X205222Y775D01*
X205189Y753D01*
X205167Y738D01*
X205160Y731D01*
X205109Y676D01*
X205072Y618D01*
X205047Y560D01*
X205029Y501D01*
X205018Y454D01*
X205014Y414D01*
X205011Y400D01*
Y378D01*
X205018Y301D01*
X205032Y232D01*
X205058Y170D01*
X205087Y116D01*
X205113Y76D01*
X205138Y43D01*
X205153Y25D01*
X205160Y17D01*
X205218Y-30D01*
X205284Y-66D01*
X205349Y-88D01*
X205411Y-106D01*
X205466Y-117D01*
X205487Y-121D01*
X205509D01*
X205527Y-125D01*
X205538D01*
X205546D01*
X205549D01*
X205644Y-117D01*
X205731Y-103D01*
X205808Y-77D01*
X205870Y-48D01*
X205921Y-23D01*
X205957Y3D01*
X205968Y10D01*
X205979Y17D01*
X205982Y25D01*
X205986D01*
X206015Y54D01*
X206044Y83D01*
X206084Y145D01*
X206117Y207D01*
X206135Y265D01*
X206150Y312D01*
X206154Y352D01*
X206157Y367D01*
Y425D01*
X206150Y461D01*
X206132Y527D01*
X206106Y585D01*
X206081Y636D01*
X206052Y676D01*
X206026Y705D01*
X206008Y724D01*
X206004Y731D01*
X206001D01*
X205939Y778D01*
X205870Y815D01*
X205797Y840D01*
X205728Y855D01*
X205669Y865D01*
X205644Y869D01*
X205619D01*
X205600Y873D01*
D02*
G37*
G36*
X216117Y2558D02*
X216095D01*
X216091D01*
X216088D01*
X216030Y2554D01*
X215975Y2540D01*
X215928Y2521D01*
X215888Y2500D01*
X215855Y2478D01*
X215833Y2460D01*
X215815Y2445D01*
X215811Y2441D01*
X215775Y2398D01*
X215746Y2347D01*
X215727Y2299D01*
X215713Y2252D01*
X215706Y2208D01*
X215702Y2176D01*
X215698Y2154D01*
Y2146D01*
X215702Y2081D01*
X215717Y2023D01*
X215735Y1972D01*
X215757Y1928D01*
X215775Y1895D01*
X215793Y1870D01*
X215808Y1852D01*
X215811Y1848D01*
X215855Y1812D01*
X215906Y1782D01*
X215953Y1764D01*
X216001Y1750D01*
X216040Y1743D01*
X216073Y1739D01*
X216095Y1735D01*
X216099D01*
X216102D01*
X216161Y1739D01*
X216212Y1753D01*
X216259Y1772D01*
X216299Y1793D01*
X216332Y1812D01*
X216357Y1830D01*
X216372Y1844D01*
X216375Y1848D01*
X216415Y1895D01*
X216444Y1943D01*
X216463Y1994D01*
X216477Y2041D01*
X216485Y2085D01*
X216492Y2117D01*
Y2146D01*
X216488Y2208D01*
X216474Y2267D01*
X216456Y2314D01*
X216434Y2358D01*
X216412Y2390D01*
X216394Y2416D01*
X216379Y2434D01*
X216375Y2438D01*
X216328Y2478D01*
X216281Y2507D01*
X216233Y2529D01*
X216190Y2543D01*
X216150Y2551D01*
X216117Y2558D01*
D02*
G37*
G36*
X214952Y2660D02*
X214941D01*
X214934D01*
X214930D01*
X214854Y2653D01*
X214781Y2638D01*
X214719Y2613D01*
X214668Y2587D01*
X214628Y2561D01*
X214595Y2536D01*
X214577Y2521D01*
X214570Y2514D01*
X214523Y2456D01*
X214486Y2398D01*
X214464Y2336D01*
X214446Y2278D01*
X214435Y2227D01*
X214432Y2183D01*
X214428Y2168D01*
Y2146D01*
X214432Y2096D01*
X214439Y2045D01*
X214450Y1997D01*
X214461Y1957D01*
X214472Y1925D01*
X214483Y1899D01*
X214490Y1884D01*
X214493Y1877D01*
X214523Y1833D01*
X214552Y1797D01*
X214584Y1764D01*
X214617Y1739D01*
X214643Y1717D01*
X214665Y1702D01*
X214683Y1695D01*
X214686Y1691D01*
X214734Y1673D01*
X214777Y1659D01*
X214821Y1648D01*
X214861Y1641D01*
X214894Y1637D01*
X214919Y1633D01*
X214934D01*
X214941D01*
X215018Y1641D01*
X215087Y1655D01*
X215149Y1677D01*
X215203Y1706D01*
X215243Y1732D01*
X215276Y1753D01*
X215294Y1768D01*
X215302Y1775D01*
X215349Y1830D01*
X215385Y1892D01*
X215411Y1950D01*
X215429Y2008D01*
X215440Y2059D01*
X215444Y2099D01*
X215447Y2114D01*
Y2136D01*
X215440Y2216D01*
X215425Y2289D01*
X215400Y2354D01*
X215374Y2409D01*
X215345Y2452D01*
X215320Y2485D01*
X215305Y2503D01*
X215298Y2510D01*
X215240Y2561D01*
X215178Y2598D01*
X215116Y2623D01*
X215061Y2642D01*
X215007Y2653D01*
X214967Y2656D01*
X214952Y2660D01*
D02*
G37*
G36*
X215935Y676D02*
X215920D01*
X215913D01*
X215910D01*
X215815Y669D01*
X215731Y654D01*
X215662Y632D01*
X215604Y607D01*
X215556Y578D01*
X215524Y556D01*
X215502Y541D01*
X215494Y534D01*
X215444Y479D01*
X215407Y421D01*
X215382Y363D01*
X215364Y305D01*
X215353Y257D01*
X215349Y217D01*
X215345Y203D01*
Y181D01*
X215353Y105D01*
X215367Y35D01*
X215393Y-27D01*
X215422Y-81D01*
X215447Y-121D01*
X215473Y-154D01*
X215487Y-172D01*
X215494Y-179D01*
X215553Y-227D01*
X215618Y-263D01*
X215684Y-285D01*
X215746Y-303D01*
X215800Y-314D01*
X215822Y-318D01*
X215844D01*
X215862Y-321D01*
X215873D01*
X215880D01*
X215884D01*
X215979Y-314D01*
X216066Y-299D01*
X216142Y-274D01*
X216204Y-245D01*
X216255Y-219D01*
X216292Y-194D01*
X216303Y-187D01*
X216314Y-179D01*
X216317Y-172D01*
X216321D01*
X216350Y-143D01*
X216379Y-114D01*
X216419Y-52D01*
X216452Y10D01*
X216470Y68D01*
X216485Y115D01*
X216488Y155D01*
X216492Y170D01*
Y228D01*
X216485Y265D01*
X216466Y330D01*
X216441Y388D01*
X216415Y439D01*
X216386Y479D01*
X216361Y508D01*
X216343Y527D01*
X216339Y534D01*
X216335D01*
X216273Y581D01*
X216204Y618D01*
X216131Y643D01*
X216062Y658D01*
X216004Y669D01*
X215979Y672D01*
X215953D01*
X215935Y676D01*
D02*
G37*
G36*
X202848Y-77828D02*
X202837D01*
X202830D01*
X202826D01*
X202732Y-77836D01*
X202644Y-77850D01*
X202568Y-77876D01*
X202506Y-77905D01*
X202455Y-77930D01*
X202419Y-77956D01*
X202408Y-77963D01*
X202397Y-77970D01*
X202393Y-77978D01*
X202390D01*
X202361Y-78007D01*
X202331Y-78036D01*
X202291Y-78098D01*
X202259Y-78159D01*
X202240Y-78218D01*
X202226Y-78265D01*
X202222Y-78305D01*
X202219Y-78320D01*
Y-78378D01*
X202226Y-78414D01*
X202244Y-78480D01*
X202270Y-78538D01*
X202295Y-78589D01*
X202324Y-78629D01*
X202350Y-78658D01*
X202368Y-78676D01*
X202372Y-78684D01*
X202375D01*
X202437Y-78731D01*
X202506Y-78767D01*
X202579Y-78793D01*
X202648Y-78807D01*
X202706Y-78818D01*
X202732Y-78822D01*
X202757D01*
X202776Y-78826D01*
X202790D01*
X202797D01*
X202801D01*
X202896Y-78818D01*
X202979Y-78804D01*
X203048Y-78782D01*
X203107Y-78756D01*
X203154Y-78727D01*
X203187Y-78706D01*
X203209Y-78691D01*
X203216Y-78684D01*
X203267Y-78629D01*
X203303Y-78571D01*
X203329Y-78513D01*
X203347Y-78454D01*
X203358Y-78407D01*
X203362Y-78367D01*
X203365Y-78352D01*
Y-78331D01*
X203358Y-78254D01*
X203343Y-78185D01*
X203318Y-78123D01*
X203289Y-78069D01*
X203263Y-78028D01*
X203238Y-77996D01*
X203223Y-77978D01*
X203216Y-77970D01*
X203158Y-77923D01*
X203092Y-77886D01*
X203027Y-77865D01*
X202965Y-77846D01*
X202910Y-77836D01*
X202888Y-77832D01*
X202867D01*
X202848Y-77828D01*
D02*
G37*
G36*
Y-79786D02*
X202837D01*
X202830D01*
X202826D01*
X202732Y-79794D01*
X202644Y-79808D01*
X202568Y-79834D01*
X202506Y-79863D01*
X202455Y-79888D01*
X202419Y-79914D01*
X202408Y-79921D01*
X202397Y-79928D01*
X202393Y-79936D01*
X202390D01*
X202361Y-79965D01*
X202331Y-79994D01*
X202291Y-80056D01*
X202259Y-80118D01*
X202240Y-80176D01*
X202226Y-80223D01*
X202222Y-80263D01*
X202219Y-80278D01*
Y-80336D01*
X202226Y-80373D01*
X202244Y-80438D01*
X202270Y-80496D01*
X202295Y-80547D01*
X202324Y-80587D01*
X202350Y-80616D01*
X202368Y-80635D01*
X202372Y-80642D01*
X202375D01*
X202437Y-80689D01*
X202506Y-80726D01*
X202579Y-80751D01*
X202648Y-80766D01*
X202706Y-80777D01*
X202732Y-80780D01*
X202757D01*
X202776Y-80784D01*
X202790D01*
X202797D01*
X202801D01*
X202896Y-80777D01*
X202979Y-80762D01*
X203048Y-80740D01*
X203107Y-80715D01*
X203154Y-80686D01*
X203187Y-80664D01*
X203209Y-80649D01*
X203216Y-80642D01*
X203267Y-80587D01*
X203303Y-80529D01*
X203329Y-80471D01*
X203347Y-80413D01*
X203358Y-80365D01*
X203362Y-80325D01*
X203365Y-80311D01*
Y-80289D01*
X203358Y-80212D01*
X203343Y-80143D01*
X203318Y-80081D01*
X203289Y-80027D01*
X203263Y-79987D01*
X203238Y-79954D01*
X203223Y-79936D01*
X203216Y-79928D01*
X203158Y-79881D01*
X203092Y-79845D01*
X203027Y-79823D01*
X202965Y-79805D01*
X202910Y-79794D01*
X202888Y-79790D01*
X202867D01*
X202848Y-79786D01*
D02*
G37*
G36*
X212947Y-79590D02*
X212914D01*
X212896D01*
X212888D01*
X212775Y-79593D01*
X212674Y-79597D01*
X212579Y-79604D01*
X212492Y-79615D01*
X212415Y-79626D01*
X212346Y-79641D01*
X212284Y-79655D01*
X212229Y-79670D01*
X212182Y-79684D01*
X212142Y-79695D01*
X212109Y-79710D01*
X212080Y-79721D01*
X212062Y-79732D01*
X212048Y-79739D01*
X212040Y-79746D01*
X212037D01*
X212004Y-79772D01*
X211975Y-79797D01*
X211953Y-79826D01*
X211931Y-79855D01*
X211898Y-79914D01*
X211876Y-79968D01*
X211865Y-80016D01*
X211858Y-80056D01*
X211855Y-80070D01*
Y-80092D01*
X211858Y-80132D01*
X211862Y-80172D01*
X211873Y-80208D01*
X211887Y-80241D01*
X211920Y-80303D01*
X211957Y-80358D01*
X211997Y-80398D01*
X212029Y-80431D01*
X212044Y-80441D01*
X212055Y-80449D01*
X212058Y-80456D01*
X212062D01*
X212106Y-80481D01*
X212157Y-80503D01*
X212215Y-80525D01*
X212277Y-80540D01*
X212342Y-80554D01*
X212411Y-80565D01*
X212550Y-80583D01*
X212619Y-80591D01*
X212681Y-80594D01*
X212739Y-80598D01*
X212786D01*
X212830Y-80602D01*
X212863D01*
X212881D01*
X212885D01*
X212888D01*
X213001D01*
X213103Y-80594D01*
X213194Y-80587D01*
X213281Y-80580D01*
X213354Y-80569D01*
X213423Y-80554D01*
X213482Y-80540D01*
X213536Y-80529D01*
X213580Y-80514D01*
X213616Y-80500D01*
X213649Y-80489D01*
X213675Y-80474D01*
X213693Y-80467D01*
X213704Y-80460D01*
X213711Y-80452D01*
X213715D01*
X213751Y-80423D01*
X213780Y-80394D01*
X213809Y-80365D01*
X213831Y-80336D01*
X213867Y-80274D01*
X213893Y-80219D01*
X213908Y-80168D01*
X213915Y-80132D01*
X213918Y-80117D01*
Y-80096D01*
X213915Y-80056D01*
X213911Y-80019D01*
X213886Y-79950D01*
X213853Y-79888D01*
X213817Y-79834D01*
X213780Y-79794D01*
X213747Y-79761D01*
X213722Y-79743D01*
X213718Y-79735D01*
X213715D01*
X213671Y-79710D01*
X213620Y-79688D01*
X213562Y-79666D01*
X213500Y-79652D01*
X213434Y-79637D01*
X213365Y-79626D01*
X213223Y-79608D01*
X213158Y-79601D01*
X213096Y-79597D01*
X213038Y-79593D01*
X212990D01*
X212947Y-79590D01*
D02*
G37*
G36*
Y-81548D02*
X212914D01*
X212896D01*
X212888D01*
X212775Y-81552D01*
X212674Y-81555D01*
X212579Y-81563D01*
X212492Y-81573D01*
X212415Y-81584D01*
X212346Y-81599D01*
X212284Y-81613D01*
X212229Y-81628D01*
X212182Y-81643D01*
X212142Y-81654D01*
X212109Y-81668D01*
X212080Y-81679D01*
X212062Y-81690D01*
X212048Y-81697D01*
X212040Y-81704D01*
X212037D01*
X212004Y-81730D01*
X211975Y-81756D01*
X211953Y-81785D01*
X211931Y-81814D01*
X211898Y-81872D01*
X211876Y-81927D01*
X211865Y-81974D01*
X211858Y-82014D01*
X211855Y-82029D01*
Y-82050D01*
X211858Y-82090D01*
X211862Y-82130D01*
X211873Y-82167D01*
X211887Y-82200D01*
X211920Y-82262D01*
X211957Y-82316D01*
X211997Y-82356D01*
X212029Y-82389D01*
X212044Y-82400D01*
X212055Y-82407D01*
X212058Y-82414D01*
X212062D01*
X212106Y-82440D01*
X212157Y-82462D01*
X212215Y-82484D01*
X212277Y-82498D01*
X212342Y-82513D01*
X212411Y-82524D01*
X212550Y-82542D01*
X212619Y-82549D01*
X212681Y-82553D01*
X212739Y-82556D01*
X212786D01*
X212830Y-82560D01*
X212863D01*
X212881D01*
X212885D01*
X212888D01*
X213001D01*
X213103Y-82553D01*
X213194Y-82545D01*
X213281Y-82538D01*
X213354Y-82527D01*
X213423Y-82513D01*
X213482Y-82498D01*
X213536Y-82487D01*
X213580Y-82473D01*
X213616Y-82458D01*
X213649Y-82447D01*
X213675Y-82433D01*
X213693Y-82425D01*
X213704Y-82418D01*
X213711Y-82411D01*
X213715D01*
X213751Y-82382D01*
X213780Y-82353D01*
X213809Y-82323D01*
X213831Y-82294D01*
X213867Y-82232D01*
X213893Y-82178D01*
X213908Y-82127D01*
X213915Y-82090D01*
X213918Y-82076D01*
Y-82054D01*
X213915Y-82014D01*
X213911Y-81977D01*
X213886Y-81908D01*
X213853Y-81846D01*
X213817Y-81792D01*
X213780Y-81752D01*
X213747Y-81719D01*
X213722Y-81701D01*
X213718Y-81694D01*
X213715D01*
X213671Y-81668D01*
X213620Y-81646D01*
X213562Y-81625D01*
X213500Y-81610D01*
X213434Y-81595D01*
X213365Y-81584D01*
X213223Y-81566D01*
X213158Y-81559D01*
X213096Y-81555D01*
X213038Y-81552D01*
X212990D01*
X212947Y-81548D01*
D02*
G37*
G36*
X407004Y-128123D02*
X406982D01*
X406906Y-128130D01*
X406837Y-128148D01*
X406778Y-128170D01*
X406727Y-128199D01*
X406687Y-128228D01*
X406658Y-128250D01*
X406640Y-128268D01*
X406633Y-128276D01*
X406585Y-128337D01*
X406549Y-128403D01*
X406524Y-128472D01*
X406509Y-128537D01*
X406498Y-128596D01*
X406494Y-128621D01*
Y-128643D01*
X406491Y-128661D01*
Y-128676D01*
Y-128683D01*
Y-128687D01*
X406498Y-128785D01*
X406513Y-128869D01*
X406534Y-128942D01*
X406560Y-129003D01*
X406589Y-129051D01*
X406611Y-129087D01*
X406625Y-129109D01*
X406633Y-129113D01*
Y-129116D01*
X406658Y-129145D01*
X406687Y-129167D01*
X406745Y-129207D01*
X406804Y-129233D01*
X406855Y-129255D01*
X406902Y-129265D01*
X406938Y-129269D01*
X406953Y-129273D01*
X406971D01*
X407022Y-129269D01*
X407069Y-129262D01*
X407113Y-129247D01*
X407150Y-129233D01*
X407182Y-129222D01*
X407208Y-129207D01*
X407222Y-129200D01*
X407230Y-129196D01*
X407273Y-129164D01*
X407310Y-129131D01*
X407342Y-129091D01*
X407368Y-129058D01*
X407390Y-129025D01*
X407404Y-129000D01*
X407415Y-128982D01*
X407419Y-128974D01*
X407441Y-128920D01*
X407455Y-128865D01*
X407470Y-128814D01*
X407477Y-128767D01*
X407481Y-128727D01*
X407484Y-128694D01*
Y-128676D01*
Y-128669D01*
X407477Y-128581D01*
X407463Y-128505D01*
X407437Y-128436D01*
X407412Y-128381D01*
X407386Y-128334D01*
X407361Y-128301D01*
X407346Y-128283D01*
X407339Y-128276D01*
X407281Y-128225D01*
X407222Y-128188D01*
X407161Y-128159D01*
X407106Y-128141D01*
X407055Y-128130D01*
X407019Y-128126D01*
X407004Y-128123D01*
D02*
G37*
G36*
X409901Y-127245D02*
X409108D01*
X409010Y-127249D01*
X408926Y-127263D01*
X408853Y-127282D01*
X408799Y-127304D01*
X408751Y-127325D01*
X408722Y-127344D01*
X408704Y-127358D01*
X408697Y-127362D01*
X408653Y-127409D01*
X408620Y-127456D01*
X408598Y-127507D01*
X408580Y-127551D01*
X408573Y-127595D01*
X408569Y-127628D01*
X408566Y-127649D01*
Y-127653D01*
Y-127657D01*
X408569Y-127700D01*
X408576Y-127744D01*
X408587Y-127780D01*
X408598Y-127813D01*
X408613Y-127842D01*
X408624Y-127864D01*
X408631Y-127879D01*
X408635Y-127882D01*
X408660Y-127919D01*
X408693Y-127952D01*
X408726Y-127977D01*
X408758Y-127999D01*
X408788Y-128013D01*
X408809Y-128024D01*
X408824Y-128032D01*
X408831Y-128035D01*
X408882Y-128050D01*
X408940Y-128061D01*
X408999Y-128068D01*
X409057Y-128072D01*
X409108Y-128075D01*
X409152Y-128079D01*
X409901D01*
Y-127245D01*
D02*
G37*
G36*
X426689Y-131272D02*
X426667D01*
X426591Y-131280D01*
X426522Y-131298D01*
X426463Y-131319D01*
X426412Y-131349D01*
X426372Y-131378D01*
X426343Y-131400D01*
X426325Y-131418D01*
X426318Y-131425D01*
X426270Y-131487D01*
X426234Y-131553D01*
X426208Y-131622D01*
X426194Y-131687D01*
X426183Y-131745D01*
X426179Y-131771D01*
Y-131793D01*
X426176Y-131811D01*
Y-131825D01*
Y-131833D01*
Y-131836D01*
X426183Y-131935D01*
X426198Y-132018D01*
X426219Y-132091D01*
X426245Y-132153D01*
X426274Y-132200D01*
X426296Y-132237D01*
X426310Y-132259D01*
X426318Y-132262D01*
Y-132266D01*
X426343Y-132295D01*
X426372Y-132317D01*
X426431Y-132357D01*
X426489Y-132382D01*
X426540Y-132404D01*
X426587Y-132415D01*
X426623Y-132419D01*
X426638Y-132422D01*
X426656D01*
X426707Y-132419D01*
X426755Y-132412D01*
X426798Y-132397D01*
X426835Y-132382D01*
X426867Y-132371D01*
X426893Y-132357D01*
X426907Y-132350D01*
X426915Y-132346D01*
X426958Y-132313D01*
X426995Y-132281D01*
X427028Y-132240D01*
X427053Y-132208D01*
X427075Y-132175D01*
X427089Y-132149D01*
X427100Y-132131D01*
X427104Y-132124D01*
X427126Y-132069D01*
X427140Y-132015D01*
X427155Y-131964D01*
X427162Y-131916D01*
X427166Y-131876D01*
X427170Y-131844D01*
Y-131825D01*
Y-131818D01*
X427162Y-131731D01*
X427148Y-131654D01*
X427122Y-131585D01*
X427097Y-131531D01*
X427071Y-131483D01*
X427046Y-131450D01*
X427031Y-131432D01*
X427024Y-131425D01*
X426966Y-131374D01*
X426907Y-131338D01*
X426846Y-131309D01*
X426791Y-131290D01*
X426740Y-131280D01*
X426704Y-131276D01*
X426689Y-131272D01*
D02*
G37*
G36*
X429586Y-130395D02*
X428793D01*
X428695Y-130399D01*
X428611Y-130413D01*
X428538Y-130431D01*
X428483Y-130453D01*
X428436Y-130475D01*
X428407Y-130493D01*
X428389Y-130508D01*
X428382Y-130511D01*
X428338Y-130559D01*
X428305Y-130606D01*
X428283Y-130657D01*
X428265Y-130701D01*
X428258Y-130744D01*
X428254Y-130777D01*
X428251Y-130799D01*
Y-130803D01*
Y-130806D01*
X428254Y-130850D01*
X428262Y-130894D01*
X428272Y-130930D01*
X428283Y-130963D01*
X428298Y-130992D01*
X428309Y-131014D01*
X428316Y-131028D01*
X428320Y-131032D01*
X428345Y-131068D01*
X428378Y-131101D01*
X428411Y-131127D01*
X428443Y-131148D01*
X428473Y-131163D01*
X428494Y-131174D01*
X428509Y-131181D01*
X428516Y-131185D01*
X428567Y-131199D01*
X428625Y-131210D01*
X428684Y-131218D01*
X428742Y-131221D01*
X428793Y-131225D01*
X428837Y-131228D01*
X429586D01*
Y-130395D01*
D02*
G37*
G36*
X58659Y-31892D02*
X58655D01*
X58651D01*
X58608Y-31896D01*
X58564Y-31903D01*
X58527Y-31914D01*
X58495Y-31925D01*
X58466Y-31940D01*
X58444Y-31951D01*
X58429Y-31958D01*
X58426Y-31962D01*
X58389Y-31987D01*
X58356Y-32020D01*
X58331Y-32052D01*
X58309Y-32085D01*
X58295Y-32114D01*
X58284Y-32136D01*
X58276Y-32151D01*
X58273Y-32158D01*
X58258Y-32209D01*
X58247Y-32267D01*
X58240Y-32326D01*
X58236Y-32384D01*
X58233Y-32435D01*
X58229Y-32478D01*
Y-33228D01*
X59063D01*
Y-32435D01*
X59059Y-32336D01*
X59044Y-32253D01*
X59026Y-32180D01*
X59004Y-32125D01*
X58983Y-32078D01*
X58964Y-32049D01*
X58950Y-32031D01*
X58946Y-32023D01*
X58899Y-31980D01*
X58851Y-31947D01*
X58801Y-31925D01*
X58757Y-31907D01*
X58713Y-31900D01*
X58680Y-31896D01*
X58659Y-31892D01*
D02*
G37*
G36*
X106739Y-51083D02*
X106736D01*
X106732D01*
X106674Y-51087D01*
X106623Y-51102D01*
X106576Y-51120D01*
X106536Y-51142D01*
X106503Y-51160D01*
X106477Y-51178D01*
X106463Y-51193D01*
X106459Y-51196D01*
X106419Y-51244D01*
X106390Y-51291D01*
X106372Y-51342D01*
X106357Y-51389D01*
X106350Y-51433D01*
X106343Y-51466D01*
Y-51495D01*
X106346Y-51557D01*
X106361Y-51615D01*
X106379Y-51662D01*
X106401Y-51706D01*
X106423Y-51739D01*
X106441Y-51764D01*
X106456Y-51782D01*
X106459Y-51786D01*
X106507Y-51826D01*
X106554Y-51855D01*
X106601Y-51877D01*
X106645Y-51892D01*
X106685Y-51899D01*
X106718Y-51906D01*
X106739D01*
X106743D01*
X106747D01*
X106805Y-51903D01*
X106860Y-51888D01*
X106907Y-51870D01*
X106947Y-51848D01*
X106980Y-51826D01*
X107002Y-51808D01*
X107020Y-51793D01*
X107024Y-51790D01*
X107060Y-51746D01*
X107089Y-51695D01*
X107107Y-51648D01*
X107122Y-51600D01*
X107129Y-51557D01*
X107133Y-51524D01*
X107136Y-51502D01*
Y-51495D01*
X107133Y-51429D01*
X107118Y-51371D01*
X107100Y-51320D01*
X107078Y-51276D01*
X107060Y-51244D01*
X107042Y-51218D01*
X107027Y-51200D01*
X107024Y-51196D01*
X106980Y-51160D01*
X106929Y-51131D01*
X106881Y-51113D01*
X106834Y-51098D01*
X106794Y-51091D01*
X106761Y-51087D01*
X106739Y-51083D01*
D02*
G37*
G36*
X107915Y-50982D02*
X107901D01*
X107893D01*
X107817Y-50989D01*
X107748Y-51003D01*
X107686Y-51025D01*
X107631Y-51054D01*
X107591Y-51080D01*
X107559Y-51102D01*
X107540Y-51116D01*
X107533Y-51123D01*
X107486Y-51178D01*
X107449Y-51240D01*
X107424Y-51298D01*
X107406Y-51357D01*
X107395Y-51407D01*
X107391Y-51447D01*
X107387Y-51462D01*
Y-51484D01*
X107395Y-51564D01*
X107409Y-51637D01*
X107435Y-51702D01*
X107460Y-51757D01*
X107489Y-51801D01*
X107515Y-51833D01*
X107529Y-51851D01*
X107537Y-51859D01*
X107595Y-51910D01*
X107657Y-51946D01*
X107719Y-51972D01*
X107773Y-51990D01*
X107828Y-52001D01*
X107868Y-52004D01*
X107882Y-52008D01*
X107893D01*
X107901D01*
X107904D01*
X107981Y-52001D01*
X108054Y-51986D01*
X108115Y-51961D01*
X108166Y-51935D01*
X108206Y-51910D01*
X108239Y-51884D01*
X108257Y-51870D01*
X108265Y-51863D01*
X108312Y-51804D01*
X108348Y-51746D01*
X108370Y-51684D01*
X108388Y-51626D01*
X108399Y-51575D01*
X108403Y-51531D01*
X108407Y-51517D01*
Y-51495D01*
X108403Y-51444D01*
X108396Y-51393D01*
X108385Y-51346D01*
X108374Y-51306D01*
X108363Y-51273D01*
X108352Y-51247D01*
X108345Y-51233D01*
X108341Y-51226D01*
X108312Y-51182D01*
X108283Y-51145D01*
X108250Y-51113D01*
X108217Y-51087D01*
X108192Y-51065D01*
X108170Y-51051D01*
X108152Y-51043D01*
X108148Y-51040D01*
X108101Y-51022D01*
X108057Y-51007D01*
X108013Y-50996D01*
X107974Y-50989D01*
X107941Y-50985D01*
X107915Y-50982D01*
D02*
G37*
G36*
X280201Y-198104D02*
X280190D01*
X280183D01*
X280179D01*
X280084Y-198111D01*
X279997Y-198126D01*
X279921Y-198151D01*
X279859Y-198180D01*
X279808Y-198206D01*
X279771Y-198231D01*
X279760Y-198239D01*
X279749Y-198246D01*
X279746Y-198253D01*
X279742D01*
X279713Y-198282D01*
X279684Y-198311D01*
X279644Y-198373D01*
X279611Y-198435D01*
X279593Y-198493D01*
X279578Y-198541D01*
X279575Y-198581D01*
X279571Y-198595D01*
Y-198653D01*
X279578Y-198690D01*
X279597Y-198755D01*
X279622Y-198814D01*
X279648Y-198865D01*
X279677Y-198905D01*
X279702Y-198934D01*
X279720Y-198952D01*
X279724Y-198959D01*
X279728D01*
X279789Y-199006D01*
X279859Y-199043D01*
X279931Y-199068D01*
X280001Y-199083D01*
X280059Y-199094D01*
X280084Y-199098D01*
X280110D01*
X280128Y-199101D01*
X280143D01*
X280150D01*
X280153D01*
X280248Y-199094D01*
X280332Y-199079D01*
X280401Y-199057D01*
X280459Y-199032D01*
X280507Y-199003D01*
X280539Y-198981D01*
X280561Y-198967D01*
X280569Y-198959D01*
X280620Y-198905D01*
X280656Y-198846D01*
X280681Y-198788D01*
X280699Y-198730D01*
X280710Y-198683D01*
X280714Y-198643D01*
X280718Y-198628D01*
Y-198606D01*
X280710Y-198530D01*
X280696Y-198460D01*
X280670Y-198399D01*
X280641Y-198344D01*
X280616Y-198304D01*
X280590Y-198271D01*
X280576Y-198253D01*
X280569Y-198246D01*
X280510Y-198198D01*
X280445Y-198162D01*
X280379Y-198140D01*
X280317Y-198122D01*
X280263Y-198111D01*
X280241Y-198108D01*
X280219D01*
X280201Y-198104D01*
D02*
G37*
G36*
X281056Y-200088D02*
X281038D01*
X281031D01*
X280943Y-200095D01*
X280867Y-200110D01*
X280798Y-200135D01*
X280743Y-200160D01*
X280696Y-200186D01*
X280663Y-200211D01*
X280645Y-200226D01*
X280638Y-200233D01*
X280587Y-200291D01*
X280550Y-200350D01*
X280521Y-200412D01*
X280503Y-200466D01*
X280492Y-200517D01*
X280488Y-200553D01*
X280485Y-200568D01*
Y-200590D01*
X280492Y-200666D01*
X280510Y-200735D01*
X280532Y-200794D01*
X280561Y-200845D01*
X280590Y-200885D01*
X280612Y-200914D01*
X280630Y-200932D01*
X280638Y-200939D01*
X280699Y-200987D01*
X280765Y-201023D01*
X280834Y-201049D01*
X280900Y-201063D01*
X280958Y-201074D01*
X280983Y-201078D01*
X281005D01*
X281024Y-201081D01*
X281038D01*
X281045D01*
X281049D01*
X281147Y-201074D01*
X281231Y-201060D01*
X281304Y-201038D01*
X281366Y-201012D01*
X281413Y-200983D01*
X281449Y-200961D01*
X281471Y-200947D01*
X281475Y-200939D01*
X281479D01*
X281508Y-200914D01*
X281529Y-200885D01*
X281570Y-200827D01*
X281595Y-200768D01*
X281617Y-200717D01*
X281628Y-200670D01*
X281631Y-200634D01*
X281635Y-200619D01*
Y-200601D01*
X281631Y-200550D01*
X281624Y-200503D01*
X281610Y-200459D01*
X281595Y-200423D01*
X281584Y-200390D01*
X281570Y-200364D01*
X281562Y-200350D01*
X281559Y-200342D01*
X281526Y-200299D01*
X281493Y-200262D01*
X281453Y-200230D01*
X281420Y-200204D01*
X281387Y-200182D01*
X281362Y-200168D01*
X281344Y-200157D01*
X281336Y-200153D01*
X281282Y-200131D01*
X281227Y-200117D01*
X281176Y-200102D01*
X281129Y-200095D01*
X281089Y-200091D01*
X281056Y-200088D01*
D02*
G37*
G36*
X336051Y-290595D02*
X335992D01*
X335956Y-290602D01*
X335890Y-290620D01*
X335832Y-290646D01*
X335781Y-290671D01*
X335741Y-290700D01*
X335712Y-290726D01*
X335694Y-290744D01*
X335686Y-290748D01*
Y-290751D01*
X335639Y-290813D01*
X335603Y-290882D01*
X335577Y-290955D01*
X335563Y-291024D01*
X335552Y-291083D01*
X335548Y-291108D01*
Y-291133D01*
X335544Y-291152D01*
Y-291166D01*
Y-291174D01*
Y-291177D01*
X335552Y-291272D01*
X335566Y-291355D01*
X335588Y-291425D01*
X335614Y-291483D01*
X335643Y-291530D01*
X335665Y-291563D01*
X335679Y-291585D01*
X335686Y-291592D01*
X335741Y-291643D01*
X335799Y-291680D01*
X335858Y-291705D01*
X335916Y-291723D01*
X335963Y-291734D01*
X336003Y-291738D01*
X336018Y-291741D01*
X336039D01*
X336116Y-291734D01*
X336185Y-291720D01*
X336247Y-291694D01*
X336302Y-291665D01*
X336342Y-291639D01*
X336374Y-291614D01*
X336393Y-291599D01*
X336400Y-291592D01*
X336447Y-291534D01*
X336484Y-291468D01*
X336506Y-291403D01*
X336524Y-291341D01*
X336535Y-291286D01*
X336538Y-291265D01*
Y-291243D01*
X336542Y-291225D01*
Y-291214D01*
Y-291206D01*
Y-291203D01*
X336535Y-291108D01*
X336520Y-291021D01*
X336494Y-290944D01*
X336465Y-290882D01*
X336440Y-290831D01*
X336414Y-290795D01*
X336407Y-290784D01*
X336400Y-290773D01*
X336393Y-290770D01*
Y-290766D01*
X336364Y-290737D01*
X336334Y-290708D01*
X336273Y-290668D01*
X336211Y-290635D01*
X336152Y-290617D01*
X336105Y-290602D01*
X336065Y-290598D01*
X336051Y-290595D01*
D02*
G37*
G36*
X333910Y-290853D02*
Y-291982D01*
X334704D01*
X333910Y-290853D01*
D02*
G37*
G36*
X317153Y-291382D02*
X317095D01*
X317058Y-291389D01*
X316993Y-291408D01*
X316934Y-291433D01*
X316883Y-291459D01*
X316843Y-291488D01*
X316814Y-291513D01*
X316796Y-291531D01*
X316789Y-291535D01*
Y-291539D01*
X316741Y-291601D01*
X316705Y-291670D01*
X316680Y-291742D01*
X316665Y-291812D01*
X316654Y-291870D01*
X316651Y-291895D01*
Y-291921D01*
X316647Y-291939D01*
Y-291954D01*
Y-291961D01*
Y-291965D01*
X316654Y-292059D01*
X316669Y-292143D01*
X316690Y-292212D01*
X316716Y-292270D01*
X316745Y-292318D01*
X316767Y-292350D01*
X316781Y-292372D01*
X316789Y-292379D01*
X316843Y-292430D01*
X316902Y-292467D01*
X316960Y-292492D01*
X317018Y-292511D01*
X317066Y-292522D01*
X317106Y-292525D01*
X317120Y-292529D01*
X317142D01*
X317218Y-292522D01*
X317287Y-292507D01*
X317349Y-292481D01*
X317404Y-292452D01*
X317444Y-292427D01*
X317477Y-292401D01*
X317495Y-292387D01*
X317502Y-292379D01*
X317550Y-292321D01*
X317586Y-292256D01*
X317608Y-292190D01*
X317626Y-292128D01*
X317637Y-292074D01*
X317641Y-292052D01*
Y-292030D01*
X317644Y-292012D01*
Y-292001D01*
Y-291994D01*
Y-291990D01*
X317637Y-291895D01*
X317622Y-291808D01*
X317597Y-291732D01*
X317568Y-291670D01*
X317542Y-291619D01*
X317517Y-291582D01*
X317510Y-291571D01*
X317502Y-291561D01*
X317495Y-291557D01*
Y-291553D01*
X317466Y-291524D01*
X317437Y-291495D01*
X317375Y-291455D01*
X317313Y-291422D01*
X317255Y-291404D01*
X317207Y-291389D01*
X317167Y-291386D01*
X317153Y-291382D01*
D02*
G37*
G36*
X322256Y-238359D02*
X322235D01*
X322158Y-238366D01*
X322089Y-238384D01*
X322031Y-238406D01*
X321980Y-238435D01*
X321940Y-238464D01*
X321911Y-238486D01*
X321892Y-238504D01*
X321885Y-238512D01*
X321838Y-238574D01*
X321801Y-238639D01*
X321776Y-238708D01*
X321761Y-238774D01*
X321750Y-238832D01*
X321747Y-238858D01*
Y-238879D01*
X321743Y-238897D01*
Y-238912D01*
Y-238919D01*
Y-238923D01*
X321750Y-239021D01*
X321765Y-239105D01*
X321787Y-239178D01*
X321812Y-239240D01*
X321841Y-239287D01*
X321863Y-239323D01*
X321878Y-239345D01*
X321885Y-239349D01*
Y-239352D01*
X321911Y-239382D01*
X321940Y-239404D01*
X321998Y-239443D01*
X322056Y-239469D01*
X322107Y-239491D01*
X322154Y-239502D01*
X322191Y-239505D01*
X322205Y-239509D01*
X322224D01*
X322275Y-239505D01*
X322322Y-239498D01*
X322366Y-239484D01*
X322402Y-239469D01*
X322435Y-239458D01*
X322460Y-239443D01*
X322475Y-239436D01*
X322482Y-239433D01*
X322526Y-239400D01*
X322562Y-239367D01*
X322595Y-239327D01*
X322620Y-239294D01*
X322642Y-239262D01*
X322657Y-239236D01*
X322668Y-239218D01*
X322671Y-239211D01*
X322693Y-239156D01*
X322708Y-239101D01*
X322722Y-239050D01*
X322730Y-239003D01*
X322733Y-238963D01*
X322737Y-238930D01*
Y-238912D01*
Y-238905D01*
X322730Y-238817D01*
X322715Y-238741D01*
X322690Y-238672D01*
X322664Y-238617D01*
X322639Y-238570D01*
X322613Y-238537D01*
X322599Y-238519D01*
X322591Y-238512D01*
X322533Y-238461D01*
X322475Y-238424D01*
X322413Y-238395D01*
X322358Y-238377D01*
X322307Y-238366D01*
X322271Y-238362D01*
X322256Y-238359D01*
D02*
G37*
G36*
X320313Y-237445D02*
X320254D01*
X320218Y-237452D01*
X320152Y-237471D01*
X320094Y-237496D01*
X320043Y-237522D01*
X320003Y-237551D01*
X319974Y-237576D01*
X319956Y-237594D01*
X319949Y-237598D01*
Y-237602D01*
X319901Y-237664D01*
X319865Y-237733D01*
X319839Y-237806D01*
X319825Y-237875D01*
X319814Y-237933D01*
X319810Y-237958D01*
Y-237984D01*
X319807Y-238002D01*
Y-238017D01*
Y-238024D01*
Y-238028D01*
X319814Y-238122D01*
X319829Y-238206D01*
X319850Y-238275D01*
X319876Y-238333D01*
X319905Y-238381D01*
X319927Y-238413D01*
X319941Y-238435D01*
X319949Y-238442D01*
X320003Y-238493D01*
X320061Y-238530D01*
X320120Y-238555D01*
X320178Y-238574D01*
X320225Y-238584D01*
X320265Y-238588D01*
X320280Y-238592D01*
X320302D01*
X320378Y-238584D01*
X320447Y-238570D01*
X320509Y-238544D01*
X320564Y-238515D01*
X320604Y-238490D01*
X320637Y-238464D01*
X320655Y-238450D01*
X320662Y-238442D01*
X320709Y-238384D01*
X320746Y-238319D01*
X320768Y-238253D01*
X320786Y-238191D01*
X320797Y-238137D01*
X320800Y-238115D01*
Y-238093D01*
X320804Y-238075D01*
Y-238064D01*
Y-238057D01*
Y-238053D01*
X320797Y-237958D01*
X320782Y-237871D01*
X320757Y-237795D01*
X320728Y-237733D01*
X320702Y-237682D01*
X320677Y-237645D01*
X320669Y-237634D01*
X320662Y-237624D01*
X320655Y-237620D01*
Y-237616D01*
X320626Y-237587D01*
X320597Y-237558D01*
X320535Y-237518D01*
X320473Y-237485D01*
X320414Y-237467D01*
X320367Y-237452D01*
X320327Y-237449D01*
X320313Y-237445D01*
D02*
G37*
G36*
X383267Y-233227D02*
X383245D01*
X383205Y-233231D01*
X383169Y-233235D01*
X383100Y-233260D01*
X383038Y-233293D01*
X382983Y-233329D01*
X382943Y-233366D01*
X382910Y-233398D01*
X382892Y-233424D01*
X382885Y-233427D01*
Y-233431D01*
X382859Y-233475D01*
X382838Y-233526D01*
X382816Y-233584D01*
X382801Y-233646D01*
X382787Y-233711D01*
X382776Y-233781D01*
X382757Y-233922D01*
X382750Y-233988D01*
X382747Y-234050D01*
X382743Y-234108D01*
Y-234155D01*
X382739Y-234199D01*
Y-234232D01*
Y-234250D01*
Y-234257D01*
X382743Y-234370D01*
X382747Y-234472D01*
X382754Y-234567D01*
X382765Y-234654D01*
X382776Y-234731D01*
X382790Y-234800D01*
X382805Y-234862D01*
X382819Y-234916D01*
X382834Y-234963D01*
X382845Y-235003D01*
X382859Y-235036D01*
X382870Y-235065D01*
X382881Y-235084D01*
X382889Y-235098D01*
X382896Y-235105D01*
Y-235109D01*
X382921Y-235142D01*
X382947Y-235171D01*
X382976Y-235193D01*
X383005Y-235215D01*
X383063Y-235247D01*
X383118Y-235269D01*
X383165Y-235280D01*
X383205Y-235287D01*
X383220Y-235291D01*
X383242D01*
X383282Y-235287D01*
X383322Y-235284D01*
X383358Y-235273D01*
X383391Y-235258D01*
X383453Y-235226D01*
X383507Y-235189D01*
X383547Y-235149D01*
X383580Y-235116D01*
X383591Y-235102D01*
X383598Y-235091D01*
X383606Y-235087D01*
Y-235084D01*
X383631Y-235040D01*
X383653Y-234989D01*
X383675Y-234931D01*
X383689Y-234869D01*
X383704Y-234803D01*
X383715Y-234734D01*
X383733Y-234596D01*
X383740Y-234527D01*
X383744Y-234465D01*
X383748Y-234407D01*
Y-234359D01*
X383751Y-234316D01*
Y-234283D01*
Y-234265D01*
Y-234261D01*
Y-234257D01*
Y-234144D01*
X383744Y-234043D01*
X383737Y-233952D01*
X383729Y-233864D01*
X383718Y-233791D01*
X383704Y-233722D01*
X383689Y-233664D01*
X383678Y-233609D01*
X383664Y-233566D01*
X383649Y-233529D01*
X383638Y-233497D01*
X383624Y-233471D01*
X383616Y-233453D01*
X383609Y-233442D01*
X383602Y-233435D01*
Y-233431D01*
X383573Y-233395D01*
X383544Y-233366D01*
X383515Y-233336D01*
X383486Y-233315D01*
X383424Y-233278D01*
X383369Y-233253D01*
X383318Y-233238D01*
X383282Y-233231D01*
X383267Y-233227D01*
D02*
G37*
G36*
X551794Y-328910D02*
X551772D01*
X551696Y-328917D01*
X551627Y-328935D01*
X551568Y-328957D01*
X551517Y-328986D01*
X551477Y-329015D01*
X551448Y-329037D01*
X551430Y-329056D01*
X551423Y-329063D01*
X551375Y-329125D01*
X551339Y-329190D01*
X551314Y-329259D01*
X551299Y-329325D01*
X551288Y-329383D01*
X551285Y-329409D01*
Y-329431D01*
X551281Y-329449D01*
Y-329463D01*
Y-329470D01*
Y-329474D01*
X551288Y-329572D01*
X551303Y-329656D01*
X551325Y-329729D01*
X551350Y-329791D01*
X551379Y-329838D01*
X551401Y-329875D01*
X551415Y-329896D01*
X551423Y-329900D01*
Y-329904D01*
X551448Y-329933D01*
X551477Y-329955D01*
X551536Y-329995D01*
X551594Y-330020D01*
X551645Y-330042D01*
X551692Y-330053D01*
X551729Y-330057D01*
X551743Y-330060D01*
X551761D01*
X551812Y-330057D01*
X551860Y-330049D01*
X551903Y-330035D01*
X551940Y-330020D01*
X551972Y-330009D01*
X551998Y-329995D01*
X552012Y-329987D01*
X552020Y-329984D01*
X552064Y-329951D01*
X552100Y-329918D01*
X552133Y-329878D01*
X552158Y-329845D01*
X552180Y-329813D01*
X552194Y-329787D01*
X552205Y-329769D01*
X552209Y-329762D01*
X552231Y-329707D01*
X552246Y-329653D01*
X552260Y-329602D01*
X552267Y-329554D01*
X552271Y-329514D01*
X552275Y-329481D01*
Y-329463D01*
Y-329456D01*
X552267Y-329369D01*
X552253Y-329292D01*
X552227Y-329223D01*
X552202Y-329168D01*
X552176Y-329121D01*
X552151Y-329088D01*
X552136Y-329070D01*
X552129Y-329063D01*
X552071Y-329012D01*
X552012Y-328976D01*
X551951Y-328946D01*
X551896Y-328928D01*
X551845Y-328917D01*
X551809Y-328914D01*
X551794Y-328910D01*
D02*
G37*
G36*
X538679Y-313204D02*
X537885D01*
X538679Y-314333D01*
Y-313204D01*
D02*
G37*
G36*
X118713Y-34815D02*
X118691D01*
X118615Y-34823D01*
X118546Y-34841D01*
X118487Y-34863D01*
X118436Y-34892D01*
X118396Y-34921D01*
X118367Y-34943D01*
X118349Y-34961D01*
X118342Y-34968D01*
X118294Y-35030D01*
X118258Y-35096D01*
X118233Y-35165D01*
X118218Y-35230D01*
X118207Y-35289D01*
X118203Y-35314D01*
Y-35336D01*
X118200Y-35354D01*
Y-35369D01*
Y-35376D01*
Y-35380D01*
X118207Y-35478D01*
X118222Y-35562D01*
X118244Y-35634D01*
X118269Y-35696D01*
X118298Y-35744D01*
X118320Y-35780D01*
X118334Y-35802D01*
X118342Y-35805D01*
Y-35809D01*
X118367Y-35838D01*
X118396Y-35860D01*
X118455Y-35900D01*
X118513Y-35926D01*
X118564Y-35947D01*
X118611Y-35958D01*
X118648Y-35962D01*
X118662Y-35966D01*
X118680D01*
X118731Y-35962D01*
X118779Y-35955D01*
X118822Y-35940D01*
X118859Y-35926D01*
X118891Y-35915D01*
X118917Y-35900D01*
X118931Y-35893D01*
X118939Y-35889D01*
X118982Y-35857D01*
X119019Y-35824D01*
X119052Y-35784D01*
X119077Y-35751D01*
X119099Y-35718D01*
X119113Y-35693D01*
X119124Y-35675D01*
X119128Y-35667D01*
X119150Y-35613D01*
X119164Y-35558D01*
X119179Y-35507D01*
X119186Y-35460D01*
X119190Y-35420D01*
X119193Y-35387D01*
Y-35369D01*
Y-35361D01*
X119186Y-35274D01*
X119172Y-35198D01*
X119146Y-35129D01*
X119121Y-35074D01*
X119095Y-35027D01*
X119070Y-34994D01*
X119055Y-34976D01*
X119048Y-34968D01*
X118990Y-34917D01*
X118931Y-34881D01*
X118870Y-34852D01*
X118815Y-34834D01*
X118764Y-34823D01*
X118728Y-34819D01*
X118713Y-34815D01*
D02*
G37*
G36*
X116780Y-33902D02*
X116758D01*
X116718Y-33906D01*
X116678Y-33909D01*
X116642Y-33920D01*
X116609Y-33935D01*
X116547Y-33967D01*
X116493Y-34004D01*
X116453Y-34044D01*
X116420Y-34076D01*
X116409Y-34091D01*
X116402Y-34102D01*
X116394Y-34106D01*
Y-34109D01*
X116369Y-34153D01*
X116347Y-34204D01*
X116325Y-34262D01*
X116311Y-34324D01*
X116296Y-34390D01*
X116285Y-34459D01*
X116267Y-34597D01*
X116260Y-34666D01*
X116256Y-34728D01*
X116252Y-34786D01*
Y-34834D01*
X116249Y-34877D01*
Y-34910D01*
Y-34928D01*
Y-34932D01*
Y-34936D01*
Y-35048D01*
X116256Y-35150D01*
X116263Y-35241D01*
X116271Y-35329D01*
X116281Y-35401D01*
X116296Y-35471D01*
X116311Y-35529D01*
X116322Y-35583D01*
X116336Y-35627D01*
X116351Y-35664D01*
X116362Y-35696D01*
X116376Y-35722D01*
X116383Y-35740D01*
X116391Y-35751D01*
X116398Y-35758D01*
Y-35762D01*
X116427Y-35798D01*
X116456Y-35827D01*
X116485Y-35857D01*
X116515Y-35878D01*
X116576Y-35915D01*
X116631Y-35940D01*
X116682Y-35955D01*
X116718Y-35962D01*
X116733Y-35966D01*
X116755D01*
X116795Y-35962D01*
X116831Y-35958D01*
X116900Y-35933D01*
X116962Y-35900D01*
X117017Y-35864D01*
X117057Y-35827D01*
X117090Y-35795D01*
X117108Y-35769D01*
X117115Y-35765D01*
Y-35762D01*
X117141Y-35718D01*
X117162Y-35667D01*
X117184Y-35609D01*
X117199Y-35547D01*
X117213Y-35482D01*
X117224Y-35412D01*
X117243Y-35271D01*
X117250Y-35205D01*
X117253Y-35143D01*
X117257Y-35085D01*
Y-35037D01*
X117261Y-34994D01*
Y-34961D01*
Y-34943D01*
Y-34936D01*
X117257Y-34823D01*
X117253Y-34721D01*
X117246Y-34626D01*
X117235Y-34539D01*
X117224Y-34462D01*
X117210Y-34393D01*
X117195Y-34331D01*
X117181Y-34277D01*
X117166Y-34229D01*
X117155Y-34189D01*
X117141Y-34157D01*
X117130Y-34128D01*
X117119Y-34109D01*
X117111Y-34095D01*
X117104Y-34087D01*
Y-34084D01*
X117079Y-34051D01*
X117053Y-34022D01*
X117024Y-34000D01*
X116995Y-33978D01*
X116937Y-33946D01*
X116882Y-33924D01*
X116835Y-33913D01*
X116795Y-33906D01*
X116780Y-33902D01*
D02*
G37*
G36*
X128905Y-75506D02*
X128112D01*
X128905Y-76635D01*
Y-75506D01*
D02*
G37*
G36*
X142766Y-68754D02*
X142737D01*
X142675Y-68757D01*
X142616Y-68772D01*
X142569Y-68790D01*
X142525Y-68812D01*
X142493Y-68834D01*
X142467Y-68852D01*
X142449Y-68867D01*
X142445Y-68870D01*
X142405Y-68918D01*
X142376Y-68965D01*
X142354Y-69012D01*
X142340Y-69056D01*
X142333Y-69096D01*
X142325Y-69129D01*
Y-69151D01*
Y-69154D01*
Y-69158D01*
X142329Y-69216D01*
X142343Y-69271D01*
X142362Y-69318D01*
X142384Y-69358D01*
X142405Y-69391D01*
X142424Y-69413D01*
X142438Y-69431D01*
X142442Y-69434D01*
X142485Y-69471D01*
X142536Y-69500D01*
X142584Y-69518D01*
X142631Y-69533D01*
X142675Y-69540D01*
X142708Y-69544D01*
X142729Y-69547D01*
X142737D01*
X142802Y-69544D01*
X142860Y-69529D01*
X142911Y-69511D01*
X142955Y-69489D01*
X142988Y-69471D01*
X143013Y-69453D01*
X143032Y-69438D01*
X143035Y-69434D01*
X143071Y-69391D01*
X143101Y-69340D01*
X143119Y-69292D01*
X143133Y-69245D01*
X143141Y-69205D01*
X143144Y-69172D01*
X143148Y-69151D01*
Y-69147D01*
Y-69143D01*
X143144Y-69085D01*
X143130Y-69034D01*
X143112Y-68987D01*
X143090Y-68947D01*
X143071Y-68914D01*
X143053Y-68888D01*
X143039Y-68874D01*
X143035Y-68870D01*
X142988Y-68830D01*
X142940Y-68801D01*
X142889Y-68783D01*
X142842Y-68768D01*
X142798Y-68761D01*
X142766Y-68754D01*
D02*
G37*
G36*
X142769Y-69798D02*
X142748D01*
X142667Y-69806D01*
X142595Y-69820D01*
X142529Y-69846D01*
X142474Y-69871D01*
X142431Y-69900D01*
X142398Y-69926D01*
X142380Y-69940D01*
X142373Y-69948D01*
X142322Y-70006D01*
X142285Y-70068D01*
X142260Y-70130D01*
X142242Y-70184D01*
X142231Y-70239D01*
X142227Y-70279D01*
X142223Y-70293D01*
Y-70304D01*
Y-70312D01*
Y-70315D01*
X142231Y-70392D01*
X142245Y-70465D01*
X142271Y-70526D01*
X142296Y-70577D01*
X142322Y-70618D01*
X142347Y-70650D01*
X142362Y-70668D01*
X142369Y-70676D01*
X142427Y-70723D01*
X142485Y-70759D01*
X142547Y-70781D01*
X142606Y-70799D01*
X142657Y-70810D01*
X142700Y-70814D01*
X142715Y-70818D01*
X142737D01*
X142788Y-70814D01*
X142839Y-70807D01*
X142886Y-70796D01*
X142926Y-70785D01*
X142959Y-70774D01*
X142984Y-70763D01*
X142999Y-70756D01*
X143006Y-70752D01*
X143050Y-70723D01*
X143086Y-70694D01*
X143119Y-70661D01*
X143144Y-70628D01*
X143166Y-70603D01*
X143181Y-70581D01*
X143188Y-70563D01*
X143192Y-70559D01*
X143210Y-70512D01*
X143224Y-70468D01*
X143235Y-70425D01*
X143243Y-70385D01*
X143246Y-70352D01*
X143250Y-70326D01*
Y-70312D01*
Y-70304D01*
X143243Y-70228D01*
X143228Y-70159D01*
X143206Y-70097D01*
X143177Y-70042D01*
X143152Y-70002D01*
X143130Y-69970D01*
X143115Y-69951D01*
X143108Y-69944D01*
X143053Y-69897D01*
X142991Y-69860D01*
X142933Y-69835D01*
X142875Y-69817D01*
X142824Y-69806D01*
X142784Y-69802D01*
X142769Y-69798D01*
D02*
G37*
G36*
X147700Y-48426D02*
X146572Y-49220D01*
X147700D01*
Y-48426D01*
D02*
G37*
G36*
X616344Y-239755D02*
X616323D01*
X616246Y-239762D01*
X616177Y-239777D01*
X616115Y-239802D01*
X616061Y-239831D01*
X616020Y-239857D01*
X615988Y-239882D01*
X615970Y-239897D01*
X615962Y-239904D01*
X615915Y-239962D01*
X615879Y-240028D01*
X615857Y-240093D01*
X615838Y-240155D01*
X615828Y-240210D01*
X615824Y-240232D01*
Y-240253D01*
X615820Y-240272D01*
Y-240283D01*
Y-240290D01*
Y-240293D01*
X615828Y-240388D01*
X615842Y-240476D01*
X615868Y-240552D01*
X615897Y-240614D01*
X615922Y-240665D01*
X615948Y-240701D01*
X615955Y-240712D01*
X615962Y-240723D01*
X615970Y-240727D01*
Y-240730D01*
X615999Y-240759D01*
X616028Y-240789D01*
X616090Y-240828D01*
X616152Y-240861D01*
X616210Y-240880D01*
X616257Y-240894D01*
X616297Y-240898D01*
X616312Y-240901D01*
X616370D01*
X616406Y-240894D01*
X616472Y-240876D01*
X616530Y-240850D01*
X616581Y-240825D01*
X616621Y-240796D01*
X616650Y-240770D01*
X616669Y-240752D01*
X616676Y-240749D01*
Y-240745D01*
X616723Y-240683D01*
X616759Y-240614D01*
X616785Y-240541D01*
X616799Y-240472D01*
X616810Y-240414D01*
X616814Y-240388D01*
Y-240363D01*
X616818Y-240344D01*
Y-240330D01*
Y-240323D01*
Y-240319D01*
X616810Y-240224D01*
X616796Y-240141D01*
X616774Y-240071D01*
X616749Y-240013D01*
X616719Y-239966D01*
X616698Y-239933D01*
X616683Y-239911D01*
X616676Y-239904D01*
X616621Y-239853D01*
X616563Y-239817D01*
X616505Y-239791D01*
X616446Y-239773D01*
X616399Y-239762D01*
X616359Y-239758D01*
X616344Y-239755D01*
D02*
G37*
G36*
X617678Y-232274D02*
X617656D01*
X617580Y-232282D01*
X617511Y-232296D01*
X617449Y-232322D01*
X617394Y-232351D01*
X617354Y-232376D01*
X617321Y-232402D01*
X617303Y-232416D01*
X617296Y-232424D01*
X617249Y-232482D01*
X617212Y-232547D01*
X617191Y-232613D01*
X617172Y-232675D01*
X617161Y-232729D01*
X617158Y-232751D01*
Y-232773D01*
X617154Y-232791D01*
Y-232802D01*
Y-232809D01*
Y-232813D01*
X617161Y-232908D01*
X617176Y-232995D01*
X617201Y-233072D01*
X617231Y-233133D01*
X617256Y-233184D01*
X617281Y-233221D01*
X617289Y-233232D01*
X617296Y-233243D01*
X617303Y-233246D01*
Y-233250D01*
X617332Y-233279D01*
X617361Y-233308D01*
X617423Y-233348D01*
X617485Y-233381D01*
X617544Y-233399D01*
X617591Y-233414D01*
X617631Y-233417D01*
X617646Y-233421D01*
X617704D01*
X617740Y-233414D01*
X617806Y-233396D01*
X617864Y-233370D01*
X617915Y-233345D01*
X617955Y-233315D01*
X617984Y-233290D01*
X618002Y-233272D01*
X618010Y-233268D01*
Y-233264D01*
X618057Y-233203D01*
X618093Y-233133D01*
X618119Y-233061D01*
X618133Y-232992D01*
X618144Y-232933D01*
X618148Y-232908D01*
Y-232882D01*
X618151Y-232864D01*
Y-232850D01*
Y-232842D01*
Y-232839D01*
X618144Y-232744D01*
X618130Y-232660D01*
X618108Y-232591D01*
X618082Y-232533D01*
X618053Y-232486D01*
X618031Y-232453D01*
X618017Y-232431D01*
X618010Y-232424D01*
X617955Y-232373D01*
X617897Y-232336D01*
X617838Y-232311D01*
X617780Y-232293D01*
X617733Y-232282D01*
X617693Y-232278D01*
X617678Y-232274D01*
D02*
G37*
G36*
X617624Y-303187D02*
X617602D01*
X617526Y-303194D01*
X617457Y-303209D01*
X617395Y-303234D01*
X617340Y-303263D01*
X617300Y-303289D01*
X617267Y-303314D01*
X617249Y-303329D01*
X617242Y-303336D01*
X617195Y-303394D01*
X617158Y-303460D01*
X617136Y-303525D01*
X617118Y-303587D01*
X617107Y-303642D01*
X617103Y-303664D01*
Y-303686D01*
X617100Y-303704D01*
Y-303715D01*
Y-303722D01*
Y-303726D01*
X617107Y-303820D01*
X617122Y-303908D01*
X617147Y-303984D01*
X617176Y-304046D01*
X617202Y-304097D01*
X617227Y-304133D01*
X617235Y-304144D01*
X617242Y-304155D01*
X617249Y-304159D01*
Y-304162D01*
X617278Y-304191D01*
X617307Y-304221D01*
X617369Y-304261D01*
X617431Y-304293D01*
X617489Y-304312D01*
X617537Y-304326D01*
X617577Y-304330D01*
X617591Y-304333D01*
X617650D01*
X617686Y-304326D01*
X617752Y-304308D01*
X617810Y-304282D01*
X617861Y-304257D01*
X617901Y-304228D01*
X617930Y-304202D01*
X617948Y-304184D01*
X617955Y-304181D01*
Y-304177D01*
X618003Y-304115D01*
X618039Y-304046D01*
X618064Y-303973D01*
X618079Y-303904D01*
X618090Y-303846D01*
X618094Y-303820D01*
Y-303795D01*
X618097Y-303777D01*
Y-303762D01*
Y-303755D01*
Y-303751D01*
X618090Y-303656D01*
X618075Y-303573D01*
X618054Y-303504D01*
X618028Y-303445D01*
X617999Y-303398D01*
X617977Y-303365D01*
X617963Y-303343D01*
X617955Y-303336D01*
X617901Y-303285D01*
X617842Y-303249D01*
X617784Y-303223D01*
X617726Y-303205D01*
X617679Y-303194D01*
X617639Y-303190D01*
X617624Y-303187D01*
D02*
G37*
G36*
X619586Y-302270D02*
X619564D01*
X619524Y-302273D01*
X619488Y-302277D01*
X619419Y-302302D01*
X619357Y-302335D01*
X619302Y-302372D01*
X619262Y-302408D01*
X619229Y-302441D01*
X619211Y-302466D01*
X619204Y-302470D01*
Y-302473D01*
X619178Y-302517D01*
X619157Y-302568D01*
X619135Y-302626D01*
X619120Y-302688D01*
X619106Y-302754D01*
X619095Y-302823D01*
X619076Y-302965D01*
X619069Y-303030D01*
X619066Y-303092D01*
X619062Y-303151D01*
Y-303198D01*
X619058Y-303241D01*
Y-303274D01*
Y-303292D01*
Y-303300D01*
X619062Y-303413D01*
X619066Y-303515D01*
X619073Y-303609D01*
X619084Y-303696D01*
X619095Y-303773D01*
X619109Y-303842D01*
X619124Y-303904D01*
X619138Y-303959D01*
X619153Y-304006D01*
X619164Y-304046D01*
X619178Y-304079D01*
X619189Y-304108D01*
X619200Y-304126D01*
X619207Y-304141D01*
X619215Y-304148D01*
Y-304152D01*
X619240Y-304184D01*
X619266Y-304213D01*
X619295Y-304235D01*
X619324Y-304257D01*
X619382Y-304290D01*
X619437Y-304312D01*
X619484Y-304323D01*
X619524Y-304330D01*
X619539Y-304333D01*
X619560D01*
X619601Y-304330D01*
X619641Y-304326D01*
X619677Y-304315D01*
X619710Y-304301D01*
X619772Y-304268D01*
X619826Y-304232D01*
X619866Y-304191D01*
X619899Y-304159D01*
X619910Y-304144D01*
X619917Y-304133D01*
X619924Y-304130D01*
Y-304126D01*
X619950Y-304082D01*
X619972Y-304031D01*
X619994Y-303973D01*
X620008Y-303911D01*
X620023Y-303846D01*
X620034Y-303777D01*
X620052Y-303638D01*
X620059Y-303569D01*
X620063Y-303507D01*
X620066Y-303449D01*
Y-303402D01*
X620070Y-303358D01*
Y-303325D01*
Y-303307D01*
Y-303303D01*
Y-303300D01*
Y-303187D01*
X620063Y-303085D01*
X620056Y-302994D01*
X620048Y-302907D01*
X620037Y-302834D01*
X620023Y-302765D01*
X620008Y-302706D01*
X619997Y-302652D01*
X619983Y-302608D01*
X619968Y-302572D01*
X619957Y-302539D01*
X619943Y-302514D01*
X619936Y-302495D01*
X619928Y-302484D01*
X619921Y-302477D01*
Y-302473D01*
X619892Y-302437D01*
X619863Y-302408D01*
X619834Y-302379D01*
X619804Y-302357D01*
X619743Y-302321D01*
X619688Y-302295D01*
X619637Y-302280D01*
X619601Y-302273D01*
X619586Y-302270D01*
D02*
G37*
G36*
X382648Y-132721D02*
X382619D01*
X382557Y-132724D01*
X382499Y-132739D01*
X382451Y-132757D01*
X382408Y-132779D01*
X382375Y-132801D01*
X382349Y-132819D01*
X382331Y-132834D01*
X382328Y-132837D01*
X382288Y-132885D01*
X382258Y-132932D01*
X382237Y-132979D01*
X382222Y-133023D01*
X382215Y-133063D01*
X382207Y-133096D01*
Y-133117D01*
Y-133121D01*
Y-133125D01*
X382211Y-133183D01*
X382226Y-133238D01*
X382244Y-133285D01*
X382266Y-133325D01*
X382288Y-133358D01*
X382306Y-133380D01*
X382320Y-133398D01*
X382324Y-133401D01*
X382368Y-133438D01*
X382419Y-133467D01*
X382466Y-133485D01*
X382513Y-133500D01*
X382557Y-133507D01*
X382590Y-133511D01*
X382611Y-133514D01*
X382619D01*
X382684Y-133511D01*
X382743Y-133496D01*
X382793Y-133478D01*
X382837Y-133456D01*
X382870Y-133438D01*
X382895Y-133420D01*
X382914Y-133405D01*
X382917Y-133401D01*
X382954Y-133358D01*
X382983Y-133307D01*
X383001Y-133259D01*
X383015Y-133212D01*
X383023Y-133172D01*
X383026Y-133139D01*
X383030Y-133117D01*
Y-133114D01*
Y-133110D01*
X383026Y-133052D01*
X383012Y-133001D01*
X382994Y-132954D01*
X382972Y-132914D01*
X382954Y-132881D01*
X382935Y-132855D01*
X382921Y-132841D01*
X382917Y-132837D01*
X382870Y-132797D01*
X382823Y-132768D01*
X382772Y-132750D01*
X382724Y-132735D01*
X382681Y-132728D01*
X382648Y-132721D01*
D02*
G37*
G36*
X382651Y-133765D02*
X382630D01*
X382550Y-133773D01*
X382477Y-133787D01*
X382411Y-133813D01*
X382357Y-133838D01*
X382313Y-133867D01*
X382280Y-133893D01*
X382262Y-133907D01*
X382255Y-133915D01*
X382204Y-133973D01*
X382167Y-134035D01*
X382142Y-134097D01*
X382124Y-134151D01*
X382113Y-134206D01*
X382109Y-134246D01*
X382105Y-134260D01*
Y-134271D01*
Y-134279D01*
Y-134282D01*
X382113Y-134359D01*
X382127Y-134432D01*
X382153Y-134493D01*
X382178Y-134544D01*
X382204Y-134584D01*
X382229Y-134617D01*
X382244Y-134635D01*
X382251Y-134643D01*
X382309Y-134690D01*
X382368Y-134726D01*
X382430Y-134748D01*
X382488Y-134766D01*
X382539Y-134777D01*
X382582Y-134781D01*
X382597Y-134785D01*
X382619D01*
X382670Y-134781D01*
X382721Y-134774D01*
X382768Y-134763D01*
X382808Y-134752D01*
X382841Y-134741D01*
X382866Y-134730D01*
X382881Y-134723D01*
X382888Y-134719D01*
X382932Y-134690D01*
X382968Y-134661D01*
X383001Y-134628D01*
X383026Y-134595D01*
X383048Y-134570D01*
X383063Y-134548D01*
X383070Y-134530D01*
X383074Y-134526D01*
X383092Y-134479D01*
X383106Y-134435D01*
X383117Y-134391D01*
X383125Y-134352D01*
X383128Y-134319D01*
X383132Y-134293D01*
Y-134279D01*
Y-134271D01*
X383125Y-134195D01*
X383110Y-134126D01*
X383088Y-134064D01*
X383059Y-134009D01*
X383034Y-133969D01*
X383012Y-133937D01*
X382997Y-133918D01*
X382990Y-133911D01*
X382935Y-133864D01*
X382874Y-133827D01*
X382815Y-133802D01*
X382757Y-133784D01*
X382706Y-133773D01*
X382666Y-133769D01*
X382651Y-133765D01*
D02*
G37*
G36*
X95230Y-51662D02*
X95211D01*
X95204D01*
X95117Y-51670D01*
X95040Y-51684D01*
X94971Y-51710D01*
X94916Y-51735D01*
X94869Y-51761D01*
X94836Y-51786D01*
X94818Y-51801D01*
X94811Y-51808D01*
X94760Y-51866D01*
X94723Y-51925D01*
X94694Y-51986D01*
X94676Y-52041D01*
X94665Y-52092D01*
X94662Y-52128D01*
X94658Y-52143D01*
Y-52165D01*
X94665Y-52241D01*
X94683Y-52310D01*
X94705Y-52369D01*
X94734Y-52420D01*
X94763Y-52460D01*
X94785Y-52489D01*
X94804Y-52507D01*
X94811Y-52514D01*
X94873Y-52561D01*
X94938Y-52598D01*
X95007Y-52623D01*
X95073Y-52638D01*
X95131Y-52649D01*
X95157Y-52653D01*
X95179D01*
X95197Y-52656D01*
X95211D01*
X95219D01*
X95222D01*
X95320Y-52649D01*
X95404Y-52634D01*
X95477Y-52613D01*
X95539Y-52587D01*
X95586Y-52558D01*
X95623Y-52536D01*
X95644Y-52522D01*
X95648Y-52514D01*
X95652D01*
X95681Y-52489D01*
X95703Y-52460D01*
X95743Y-52401D01*
X95768Y-52343D01*
X95790Y-52292D01*
X95801Y-52245D01*
X95805Y-52208D01*
X95808Y-52194D01*
Y-52176D01*
X95805Y-52125D01*
X95797Y-52077D01*
X95783Y-52034D01*
X95768Y-51997D01*
X95757Y-51964D01*
X95743Y-51939D01*
X95735Y-51925D01*
X95732Y-51917D01*
X95699Y-51874D01*
X95666Y-51837D01*
X95626Y-51804D01*
X95594Y-51779D01*
X95561Y-51757D01*
X95535Y-51743D01*
X95517Y-51732D01*
X95510Y-51728D01*
X95455Y-51706D01*
X95401Y-51692D01*
X95350Y-51677D01*
X95302Y-51670D01*
X95262Y-51666D01*
X95230Y-51662D01*
D02*
G37*
G36*
X605757Y-62642D02*
X605735D01*
X605695Y-62646D01*
X605655Y-62649D01*
X605618Y-62660D01*
X605585Y-62675D01*
X605524Y-62708D01*
X605469Y-62744D01*
X605429Y-62784D01*
X605396Y-62817D01*
X605385Y-62831D01*
X605378Y-62842D01*
X605371Y-62846D01*
Y-62849D01*
X605345Y-62893D01*
X605323Y-62944D01*
X605302Y-63002D01*
X605287Y-63064D01*
X605272Y-63130D01*
X605262Y-63199D01*
X605243Y-63337D01*
X605236Y-63406D01*
X605232Y-63468D01*
X605229Y-63526D01*
Y-63574D01*
X605225Y-63617D01*
Y-63650D01*
Y-63669D01*
Y-63672D01*
Y-63676D01*
Y-63789D01*
X605232Y-63890D01*
X605240Y-63981D01*
X605247Y-64069D01*
X605258Y-64142D01*
X605272Y-64211D01*
X605287Y-64269D01*
X605298Y-64324D01*
X605312Y-64367D01*
X605327Y-64404D01*
X605338Y-64437D01*
X605352Y-64462D01*
X605360Y-64480D01*
X605367Y-64491D01*
X605374Y-64498D01*
Y-64502D01*
X605404Y-64538D01*
X605433Y-64568D01*
X605462Y-64597D01*
X605491Y-64618D01*
X605553Y-64655D01*
X605607Y-64680D01*
X605658Y-64695D01*
X605695Y-64702D01*
X605709Y-64706D01*
X605731D01*
X605771Y-64702D01*
X605807Y-64699D01*
X605877Y-64673D01*
X605939Y-64640D01*
X605993Y-64604D01*
X606033Y-64568D01*
X606066Y-64535D01*
X606084Y-64509D01*
X606091Y-64506D01*
Y-64502D01*
X606117Y-64458D01*
X606139Y-64407D01*
X606161Y-64349D01*
X606175Y-64287D01*
X606190Y-64222D01*
X606201Y-64153D01*
X606219Y-64011D01*
X606226Y-63945D01*
X606230Y-63883D01*
X606233Y-63825D01*
Y-63778D01*
X606237Y-63734D01*
Y-63701D01*
Y-63683D01*
Y-63676D01*
X606233Y-63563D01*
X606230Y-63461D01*
X606222Y-63366D01*
X606212Y-63279D01*
X606201Y-63203D01*
X606186Y-63133D01*
X606172Y-63072D01*
X606157Y-63017D01*
X606142Y-62970D01*
X606132Y-62930D01*
X606117Y-62897D01*
X606106Y-62868D01*
X606095Y-62849D01*
X606088Y-62835D01*
X606081Y-62828D01*
Y-62824D01*
X606055Y-62791D01*
X606030Y-62762D01*
X606001Y-62740D01*
X605971Y-62718D01*
X605913Y-62686D01*
X605859Y-62664D01*
X605811Y-62653D01*
X605771Y-62646D01*
X605757Y-62642D01*
D02*
G37*
G36*
X148080Y-122808D02*
X148058D01*
X147981Y-122815D01*
X147912Y-122833D01*
X147854Y-122855D01*
X147803Y-122884D01*
X147763Y-122913D01*
X147734Y-122935D01*
X147716Y-122953D01*
X147708Y-122960D01*
X147661Y-123022D01*
X147625Y-123088D01*
X147599Y-123157D01*
X147585Y-123223D01*
X147574Y-123281D01*
X147570Y-123306D01*
Y-123328D01*
X147566Y-123346D01*
Y-123361D01*
Y-123368D01*
Y-123372D01*
X147574Y-123470D01*
X147588Y-123554D01*
X147610Y-123627D01*
X147636Y-123688D01*
X147665Y-123736D01*
X147687Y-123772D01*
X147701Y-123794D01*
X147708Y-123798D01*
Y-123801D01*
X147734Y-123830D01*
X147763Y-123852D01*
X147821Y-123892D01*
X147880Y-123918D01*
X147930Y-123940D01*
X147978Y-123951D01*
X148014Y-123954D01*
X148029Y-123958D01*
X148047D01*
X148098Y-123954D01*
X148145Y-123947D01*
X148189Y-123932D01*
X148225Y-123918D01*
X148258Y-123907D01*
X148284Y-123892D01*
X148298Y-123885D01*
X148305Y-123881D01*
X148349Y-123849D01*
X148385Y-123816D01*
X148418Y-123776D01*
X148444Y-123743D01*
X148466Y-123710D01*
X148480Y-123685D01*
X148491Y-123667D01*
X148495Y-123659D01*
X148516Y-123605D01*
X148531Y-123550D01*
X148546Y-123499D01*
X148553Y-123452D01*
X148556Y-123412D01*
X148560Y-123379D01*
Y-123361D01*
Y-123354D01*
X148553Y-123266D01*
X148538Y-123190D01*
X148513Y-123121D01*
X148487Y-123066D01*
X148462Y-123019D01*
X148436Y-122986D01*
X148422Y-122968D01*
X148415Y-122960D01*
X148356Y-122909D01*
X148298Y-122873D01*
X148236Y-122844D01*
X148182Y-122826D01*
X148131Y-122815D01*
X148094Y-122811D01*
X148080Y-122808D01*
D02*
G37*
G36*
X164127Y-104429D02*
X164109D01*
X164102D01*
X164014Y-104436D01*
X163938Y-104450D01*
X163869Y-104476D01*
X163814Y-104501D01*
X163767Y-104527D01*
X163734Y-104552D01*
X163716Y-104567D01*
X163708Y-104574D01*
X163658Y-104632D01*
X163621Y-104691D01*
X163592Y-104753D01*
X163574Y-104807D01*
X163563Y-104858D01*
X163559Y-104894D01*
X163556Y-104909D01*
Y-104931D01*
X163563Y-105007D01*
X163581Y-105076D01*
X163603Y-105135D01*
X163632Y-105186D01*
X163661Y-105226D01*
X163683Y-105255D01*
X163701Y-105273D01*
X163708Y-105280D01*
X163770Y-105328D01*
X163836Y-105364D01*
X163905Y-105389D01*
X163971Y-105404D01*
X164029Y-105415D01*
X164054Y-105419D01*
X164076D01*
X164094Y-105422D01*
X164109D01*
X164116D01*
X164120D01*
X164218Y-105415D01*
X164302Y-105400D01*
X164375Y-105378D01*
X164436Y-105353D01*
X164484Y-105324D01*
X164520Y-105302D01*
X164542Y-105288D01*
X164546Y-105280D01*
X164549D01*
X164578Y-105255D01*
X164600Y-105226D01*
X164640Y-105167D01*
X164666Y-105109D01*
X164688Y-105058D01*
X164699Y-105011D01*
X164702Y-104974D01*
X164706Y-104960D01*
Y-104942D01*
X164702Y-104891D01*
X164695Y-104843D01*
X164680Y-104800D01*
X164666Y-104763D01*
X164655Y-104731D01*
X164640Y-104705D01*
X164633Y-104691D01*
X164629Y-104683D01*
X164597Y-104640D01*
X164564Y-104603D01*
X164524Y-104570D01*
X164491Y-104545D01*
X164458Y-104523D01*
X164433Y-104509D01*
X164415Y-104498D01*
X164407Y-104494D01*
X164353Y-104472D01*
X164298Y-104458D01*
X164247Y-104443D01*
X164200Y-104436D01*
X164160Y-104432D01*
X164127Y-104429D01*
D02*
G37*
G36*
X151461Y-104403D02*
X151450D01*
X151443D01*
X151439D01*
X151344Y-104410D01*
X151257Y-104425D01*
X151180Y-104450D01*
X151119Y-104480D01*
X151068Y-104505D01*
X151031Y-104530D01*
X151020Y-104538D01*
X151009Y-104545D01*
X151006Y-104552D01*
X151002D01*
X150973Y-104581D01*
X150944Y-104611D01*
X150904Y-104672D01*
X150871Y-104734D01*
X150853Y-104792D01*
X150838Y-104840D01*
X150835Y-104880D01*
X150831Y-104894D01*
Y-104953D01*
X150838Y-104989D01*
X150856Y-105055D01*
X150882Y-105113D01*
X150907Y-105164D01*
X150936Y-105204D01*
X150962Y-105233D01*
X150980Y-105251D01*
X150984Y-105258D01*
X150988D01*
X151049Y-105306D01*
X151119Y-105342D01*
X151191Y-105368D01*
X151260Y-105382D01*
X151319Y-105393D01*
X151344Y-105397D01*
X151370D01*
X151388Y-105400D01*
X151402D01*
X151410D01*
X151413D01*
X151508Y-105393D01*
X151592Y-105378D01*
X151661Y-105357D01*
X151719Y-105331D01*
X151766Y-105302D01*
X151799Y-105280D01*
X151821Y-105266D01*
X151828Y-105258D01*
X151879Y-105204D01*
X151916Y-105146D01*
X151941Y-105087D01*
X151959Y-105029D01*
X151970Y-104982D01*
X151974Y-104942D01*
X151978Y-104927D01*
Y-104905D01*
X151970Y-104829D01*
X151956Y-104760D01*
X151930Y-104698D01*
X151901Y-104643D01*
X151876Y-104603D01*
X151850Y-104570D01*
X151836Y-104552D01*
X151828Y-104545D01*
X151770Y-104498D01*
X151705Y-104461D01*
X151639Y-104439D01*
X151577Y-104421D01*
X151523Y-104410D01*
X151501Y-104407D01*
X151479D01*
X151461Y-104403D01*
D02*
G37*
%LPD*%
D15*
X594109Y-289839D02*
Y-281680D01*
Y-289839D02*
X598331D01*
Y-281680D01*
X594109D02*
X598331D01*
X546046Y-274828D02*
Y-268874D01*
X542896D02*
X546046D01*
X542896Y-274828D02*
Y-268874D01*
Y-274828D02*
X546046D01*
X582441Y-280469D02*
Y-274515D01*
X579291D02*
X582441D01*
X579291Y-280469D02*
Y-274515D01*
Y-280469D02*
X582441D01*
X578755Y-289446D02*
Y-281286D01*
Y-289446D02*
X582977D01*
Y-281286D01*
X578755D02*
X582977D01*
X553959Y-279180D02*
X559912D01*
X553959Y-282330D02*
Y-279180D01*
Y-282330D02*
X559912D01*
Y-279180D01*
X586503Y-282847D02*
X592802D01*
Y-277138D01*
X586503D02*
X592802D01*
X586503Y-282847D02*
Y-277138D01*
X597795Y-281256D02*
Y-275303D01*
X594646D02*
X597795D01*
X594646Y-281256D02*
Y-275303D01*
Y-281256D02*
X597795D01*
X476298Y-303364D02*
Y-297410D01*
Y-303364D02*
X479447D01*
Y-297410D01*
X476298D02*
X479447D01*
X483292Y-267323D02*
Y-264173D01*
X477338Y-267323D02*
X483292D01*
X477338D02*
Y-264173D01*
X483292D01*
X188189Y-91511D02*
X191339D01*
Y-97465D02*
Y-91511D01*
X188189Y-97465D02*
X191339D01*
X188189D02*
Y-91511D01*
X150176Y6920D02*
X153325D01*
Y967D02*
Y6920D01*
X150176Y967D02*
X153325D01*
X150176D02*
Y6920D01*
X500221Y-253937D02*
Y-250787D01*
X494268Y-253937D02*
X500221D01*
X494268D02*
Y-250787D01*
X500221D01*
X504701Y-261711D02*
Y-258561D01*
X510654D01*
Y-261711D02*
Y-258561D01*
X504701Y-261711D02*
X510654D01*
X500614Y-261417D02*
Y-258268D01*
X494661Y-261417D02*
X500614D01*
X494661D02*
Y-258268D01*
X500614D01*
X568922Y-262694D02*
Y-259544D01*
X562968Y-262694D02*
X568922D01*
X562968D02*
Y-259544D01*
X568922D01*
X570350Y-262697D02*
Y-259547D01*
X576303D01*
Y-262697D02*
Y-259547D01*
X570350Y-262697D02*
X576303D01*
X207874Y-221D02*
X211024D01*
X207874D02*
Y5733D01*
X211024D01*
Y-221D02*
Y5733D01*
X202264Y-5929D02*
X205413D01*
X202264D02*
Y24D01*
X205413D01*
Y-5929D02*
Y24D01*
X212598Y-6126D02*
X215748D01*
X212598D02*
Y-173D01*
X215748D01*
Y-6126D02*
Y-173D01*
X202962Y-72023D02*
X206112D01*
Y-77977D02*
Y-72023D01*
X202962Y-77977D02*
X206112D01*
X202962D02*
Y-72023D01*
X212598Y-71826D02*
X215748D01*
Y-77780D02*
Y-71826D01*
X212598Y-77780D02*
X215748D01*
X212598D02*
Y-71826D01*
X406890Y-127953D02*
X413583D01*
X406890Y-131102D02*
Y-127953D01*
Y-131102D02*
X413583D01*
Y-127953D01*
X411668Y-122298D02*
X419828D01*
X411668Y-126521D02*
Y-122298D01*
Y-126521D02*
X419828D01*
Y-122298D01*
X425756Y-130566D02*
X434086D01*
X425756Y-134788D02*
Y-130566D01*
Y-134788D02*
X434086D01*
Y-130566D01*
X55249Y-36909D02*
X58399D01*
X55249D02*
Y-30217D01*
X58399D01*
Y-36909D02*
Y-30217D01*
X108913Y-14031D02*
X117072D01*
X108913Y-18253D02*
Y-14031D01*
Y-18253D02*
X117072D01*
Y-14031D01*
X91590Y-79277D02*
Y-75054D01*
X99749D01*
Y-79277D02*
Y-75054D01*
X91590Y-79277D02*
X99749D01*
X107087Y-43222D02*
X110236D01*
Y-49175D02*
Y-43222D01*
X107087Y-49175D02*
X110236D01*
X107087D02*
Y-43222D01*
X280315Y-192299D02*
X283465D01*
Y-198252D02*
Y-192299D01*
X280315Y-198252D02*
X283465D01*
X280315D02*
Y-192299D01*
X336393Y-291339D02*
X342347D01*
X336393Y-294488D02*
Y-291339D01*
Y-294488D02*
X342347D01*
Y-291339D01*
X317496Y-292126D02*
X323449D01*
X317496Y-295276D02*
Y-292126D01*
Y-295276D02*
X323449D01*
Y-292126D01*
X322614Y-238189D02*
X328567D01*
X322614Y-241339D02*
Y-238189D01*
Y-241339D02*
X328567D01*
Y-238189D01*
X374976Y-234547D02*
X380929D01*
Y-231398D01*
X374976D02*
X380929D01*
X374976Y-234547D02*
Y-231398D01*
X550787Y-327067D02*
X563386D01*
X550787Y-333563D02*
Y-327067D01*
Y-333563D02*
X563386D01*
Y-327067D01*
X526920Y-332085D02*
X539518D01*
Y-325589D01*
X526920D02*
X539518D01*
X526920Y-332085D02*
Y-325589D01*
X559842Y-313090D02*
X572441D01*
Y-306594D01*
X559842D02*
X572441D01*
X559842Y-313090D02*
Y-306594D01*
X526920Y-315521D02*
X539518D01*
Y-309024D01*
X526920D02*
X539518D01*
X526920Y-315521D02*
Y-309024D01*
X115748Y-32972D02*
X128347D01*
X115748Y-39469D02*
Y-32972D01*
Y-39469D02*
X128347D01*
Y-32972D01*
X119104Y-77823D02*
X131703D01*
Y-71326D01*
X119104D02*
X131703D01*
X119104Y-77823D02*
Y-71326D01*
X154332Y-74321D02*
Y-67824D01*
X141734Y-74321D02*
X154332D01*
X141734D02*
Y-67824D01*
X154332D01*
X145384Y-39419D02*
X151880D01*
Y-52017D02*
Y-39419D01*
X145384Y-52017D02*
X151880D01*
X145384D02*
Y-39419D01*
X610015Y-240158D02*
X615969D01*
Y-237008D01*
X610015D02*
X615969D01*
X610015Y-240158D02*
Y-237008D01*
X611349Y-232677D02*
X617303D01*
Y-229528D01*
X611349D02*
X617303D01*
X611349Y-232677D02*
Y-229528D01*
X611373Y-304232D02*
X617170D01*
Y-301279D01*
X611373D02*
X617170D01*
X611373Y-304232D02*
Y-301279D01*
X381429Y-132677D02*
X390484D01*
X381429Y-137402D02*
Y-132677D01*
Y-137402D02*
X390484D01*
Y-132677D01*
X66890Y-60501D02*
Y-51446D01*
X62165D02*
X66890D01*
X62165Y-60501D02*
Y-51446D01*
Y-60501D02*
X66890D01*
X93952Y-42771D02*
X98174D01*
Y-50930D02*
Y-42771D01*
X93952Y-50930D02*
X98174D01*
X93952D02*
Y-42771D01*
X99606Y-41929D02*
X104331D01*
Y-50984D02*
Y-41929D01*
X99606Y-50984D02*
X104331D01*
X99606D02*
Y-41929D01*
X606496Y-62598D02*
X615551D01*
X606496Y-67323D02*
Y-62598D01*
Y-67323D02*
X615551D01*
Y-62598D01*
X148515Y-122736D02*
X154312D01*
X148515Y-125689D02*
Y-122736D01*
Y-125689D02*
X154312D01*
Y-122736D01*
X162598Y-106102D02*
Y-97047D01*
Y-106102D02*
X167323D01*
Y-97047D01*
X162598D02*
X167323D01*
X151038Y-105655D02*
Y-97495D01*
Y-105655D02*
X155261D01*
Y-97495D01*
X151038D02*
X155261D01*
X160236Y-102966D02*
Y-97013D01*
X157087D02*
X160236D01*
X157087Y-102966D02*
Y-97013D01*
Y-102966D02*
X160236D01*
M02*
